(kicad_pcb
	(version 20240108)
	(generator "pcbnew")
	(generator_version "8.0")
	(general
		(thickness 1.586)
		(legacy_teardrops no)
	)
	(paper "A4")
	(title_block
		(title "GMSL Serializer")
		(date "2024-11-27")
		(rev "1.1.1")
		(company "Antmicro Ltd")
		(comment 1 "www.antmicro.com")
	)
	(layers
		(0 "F.Cu" signal)
		(1 "In1.Cu" power)
		(2 "In2.Cu" power)
		(31 "B.Cu" signal)
		(32 "B.Adhes" user "B.Adhesive")
		(33 "F.Adhes" user "F.Adhesive")
		(34 "B.Paste" user)
		(35 "F.Paste" user)
		(36 "B.SilkS" user "B.Silkscreen")
		(37 "F.SilkS" user "F.Silkscreen")
		(38 "B.Mask" user)
		(39 "F.Mask" user)
		(40 "Dwgs.User" user "User.Drawings")
		(41 "Cmts.User" user "User.Comments")
		(42 "Eco1.User" user "User.Eco1")
		(43 "Eco2.User" user "User.Eco2")
		(44 "Edge.Cuts" user)
		(45 "Margin" user)
		(46 "B.CrtYd" user "B.Courtyard")
		(47 "F.CrtYd" user "F.Courtyard")
		(48 "B.Fab" user)
		(49 "F.Fab" user)
	)
	(setup
		(stackup
			(layer "F.SilkS"
				(type "Top Silk Screen")
			)
			(layer "F.Paste"
				(type "Top Solder Paste")
			)
			(layer "F.Mask"
				(type "Top Solder Mask")
				(thickness 0.02)
			)
			(layer "F.Cu"
				(type "copper")
				(thickness 0.018)
			)
			(layer "dielectric 1"
				(type "prepreg")
				(thickness 0.12)
				(material "IS400 PR2116")
				(epsilon_r 4.06)
				(loss_tangent 0.0189)
			)
			(layer "In1.Cu"
				(type "copper")
				(thickness 0.035)
			)
			(layer "dielectric 2"
				(type "core")
				(thickness 1.2)
				(material "FR-4")
				(epsilon_r 4.35)
				(loss_tangent 0.02)
			)
			(layer "In2.Cu"
				(type "copper")
				(thickness 0.035)
			)
			(layer "dielectric 3"
				(type "prepreg")
				(thickness 0.12)
				(material "IS400 PR2116")
				(epsilon_r 4.06)
				(loss_tangent 0.0189)
			)
			(layer "B.Cu"
				(type "copper")
				(thickness 0.018)
			)
			(layer "B.Mask"
				(type "Bottom Solder Mask")
				(thickness 0.02)
			)
			(layer "B.Paste"
				(type "Bottom Solder Paste")
			)
			(layer "B.SilkS"
				(type "Bottom Silk Screen")
			)
			(copper_finish "None")
			(dielectric_constraints yes)
		)
		(pad_to_mask_clearance 0)
		(allow_soldermask_bridges_in_footprints no)
		(grid_origin 166.65 120.85)
		(pcbplotparams
			(layerselection 0x00010fc_ffffffff)
			(plot_on_all_layers_selection 0x0000000_00000000)
			(disableapertmacros no)
			(usegerberextensions no)
			(usegerberattributes yes)
			(usegerberadvancedattributes yes)
			(creategerberjobfile yes)
			(dashed_line_dash_ratio 12.000000)
			(dashed_line_gap_ratio 3.000000)
			(svgprecision 6)
			(plotframeref no)
			(viasonmask no)
			(mode 1)
			(useauxorigin no)
			(hpglpennumber 1)
			(hpglpenspeed 20)
			(hpglpendiameter 15.000000)
			(pdf_front_fp_property_popups yes)
			(pdf_back_fp_property_popups yes)
			(dxfpolygonmode yes)
			(dxfimperialunits yes)
			(dxfusepcbnewfont yes)
			(psnegative no)
			(psa4output no)
			(plotreference yes)
			(plotvalue yes)
			(plotfptext yes)
			(plotinvisibletext no)
			(sketchpadsonfab no)
			(subtractmaskfromsilk no)
			(outputformat 1)
			(mirror no)
			(drillshape 1)
			(scaleselection 1)
			(outputdirectory "")
		)
	)
	(net 0 "")
	(net 1 "GND")
	(net 2 "+12V")
	(net 3 "Net-(U1-BST)")
	(net 4 "/Supply/SW_5V")
	(net 5 "Net-(U2-BST)")
	(net 6 "/Supply/SW_1V8")
	(net 7 "/Supply/OUT_5V")
	(net 8 "/Supply/OUT_1V8")
	(net 9 "+5V")
	(net 10 "+3V3")
	(net 11 "+1V8")
	(net 12 "+1V2")
	(net 13 "/Serializer/X1")
	(net 14 "/Serializer/X2_R")
	(net 15 "Net-(U6-CAP_VDD)")
	(net 16 "Net-(C31-Pad2)")
	(net 17 "Net-(U6-SIOP)")
	(net 18 "/GMSL Connector/SIO_P")
	(net 19 "unconnected-(J1-Pad1)")
	(net 20 "unconnected-(J1-Pad2)")
	(net 21 "unconnected-(J1-Pad3)")
	(net 22 "unconnected-(J1-Pad4)")
	(net 23 "unconnected-(J1-Pad5)")
	(net 24 "unconnected-(J1-Pad6)")
	(net 25 "unconnected-(J1-Pad7)")
	(net 26 "unconnected-(J1-Pad8)")
	(net 27 "unconnected-(J1-Pad10)")
	(net 28 "unconnected-(J1-Pad11)")
	(net 29 "unconnected-(J1-Pad13)")
	(net 30 "unconnected-(J1-Pad14)")
	(net 31 "unconnected-(J1-Pad16)")
	(net 32 "unconnected-(J1-Pad17)")
	(net 33 "Net-(U6-SION)")
	(net 34 "/CSI Connector/SDA_CAM0")
	(net 35 "/CSI Connector/SCL_CAM0")
	(net 36 "/CSI Connector/SDA_CAM1")
	(net 37 "/CSI Connector/SCL_CAM1")
	(net 38 "/CSI Connector/GPIO3")
	(net 39 "/CSI Connector/GPIO4_1V8")
	(net 40 "/CSI Connector/CSI.D3_N")
	(net 41 "/CSI Connector/CSI.D3_P")
	(net 42 "/CSI Connector/CSI.D2_N")
	(net 43 "unconnected-(J1-Pad31)")
	(net 44 "/CSI Connector/CSI.D2_P")
	(net 45 "unconnected-(J1-Pad33)")
	(net 46 "unconnected-(J1-Pad35)")
	(net 47 "unconnected-(J1-Pad36)")
	(net 48 "unconnected-(J1-Pad37)")
	(net 49 "unconnected-(J1-Pad38)")
	(net 50 "/CSI Connector/CSI.D1_N")
	(net 51 "/CSI Connector/CSI.D1_P")
	(net 52 "unconnected-(J1-Pad43)")
	(net 53 "unconnected-(J1-Pad44)")
	(net 54 "unconnected-(J1-Pad45)")
	(net 55 "unconnected-(J1-Pad46)")
	(net 56 "/CSI Connector/CSI.D0_N")
	(net 57 "/CSI Connector/CSI.D0_P")
	(net 58 "Net-(L3-Pad2)")
	(net 59 "Net-(L4-Pad2)")
	(net 60 "Net-(L5-Pad2)")
	(net 61 "/CSI Connector/CSI.CLK_N")
	(net 62 "/Supply/EN_5V")
	(net 63 "/Supply/EN_1V8")
	(net 64 "/Supply/FB_5V")
	(net 65 "/Supply/FB_1V8")
	(net 66 "/Serializer/CFG0")
	(net 67 "/Serializer/X2")
	(net 68 "/Serializer/CFG1")
	(net 69 "Net-(D5-C)")
	(net 70 "Net-(D6-C)")
	(net 71 "Net-(D6-A)")
	(net 72 "/Supply/SW_3V3")
	(net 73 "Net-(D8-C)")
	(net 74 "Net-(D8-A)")
	(net 75 "Net-(D9-C)")
	(net 76 "Net-(U6-XRES)")
	(net 77 "Net-(U6-PWDNB)")
	(net 78 "Net-(U6-MFP7)")
	(net 79 "Net-(U6-MFP8)")
	(net 80 "/CSI Connector/CSI.CLK_P")
	(net 81 "Net-(U6-MFP9)")
	(net 82 "Net-(U6-MFP10)")
	(net 83 "Net-(U6-MFP0)")
	(net 84 "Net-(U6-MFP5)")
	(net 85 "Net-(U6-MFP6)")
	(net 86 "unconnected-(U5-NC-Pad4)")
	(net 87 "/CSI Connector/GPIO4")
	(net 88 "/CSI Connector/I2C.SDA")
	(net 89 "/CSI Connector/I2C.SCL")
	(net 90 "/Serializer/VREF")
	(net 91 "unconnected-(D3-Pad4)")
	(net 92 "unconnected-(D3-Pad5)")
	(net 93 "Net-(U3-BST)")
	(net 94 "/Supply/OUT_3V3")
	(net 95 "Net-(D11-C)")
	(net 96 "/Supply/FB_3V3")
	(net 97 "/Supply/EN_3V3")
	(footprint "antmicro-footprints:R_0402_1005Metric"
		(layer "F.Cu")
		(at 135.4 110.95)
		(descr "Resistor SMD 0402")
		(tags "resistor SMD 0402")
		(property "Reference" "R31"
			(at 0.9 0.3375 0)
			(layer "F.SilkS")
			(effects
				(font
					(size 0.7 0.7)
					(thickness 0.15)
				)
				(justify left bottom)
			)
		)
		(property "Value" "R_0R_0402"
			(at -1.011843 1.772047 0)
			(layer "F.Fab")
			(effects
				(font
					(size 0.7 0.7)
					(thickness 0.15)
				)
				(justify left bottom)
			)
		)
		(property "Footprint" "antmicro-footprints:R_0402_1005Metric"
			(at 0 0 0)
			(layer "F.Fab")
			(hide yes)
			(effects
				(font
					(size 1.27 1.27)
					(thickness 0.15)
				)
			)
		)
		(property "Datasheet" "https://industrial.panasonic.com/cdbs/www-data/pdf/RDA0000/AOA0000C301.pdf"
			(at 0 0 0)
			(layer "F.Fab")
			(hide yes)
			(effects
				(font
					(size 1.27 1.27)
					(thickness 0.15)
				)
			)
		)
		(property "Author" "Antmicro"
			(at 0 0 0)
			(layer "F.Fab")
			(hide yes)
			(effects
				(font
					(size 1 1)
					(thickness 0.15)
				)
			)
		)
		(property "Current" "1A"
			(at 0 0 0)
			(layer "F.Fab")
			(hide yes)
			(effects
				(font
					(size 1 1)
					(thickness 0.15)
				)
			)
		)
		(property "License" "Apache-2.0"
			(at 0 0 0)
			(layer "F.Fab")
			(hide yes)
			(effects
				(font
					(size 1 1)
					(thickness 0.15)
				)
			)
		)
		(property "MPN" "ERJ2GE0R00X"
			(at 0 0 0)
			(layer "F.Fab")
			(hide yes)
			(effects
				(font
					(size 1 1)
					(thickness 0.15)
				)
			)
		)
		(property "Manufacturer" "Panasonic"
			(at 0 0 0)
			(layer "F.Fab")
			(hide yes)
			(effects
				(font
					(size 1 1)
					(thickness 0.15)
				)
			)
		)
		(property "Tolerance" ""
			(at 0 0 0)
			(layer "F.Fab")
			(hide yes)
			(effects
				(font
					(size 1 1)
					(thickness 0.15)
				)
			)
		)
		(property "Val" "0R"
			(at 0 0 0)
			(layer "F.Fab")
			(hide yes)
			(effects
				(font
					(size 1 1)
					(thickness 0.15)
				)
			)
		)
		(sheetname "Serializer")
		(sheetfile "serializer.kicad_sch")
		(attr smd exclude_from_bom dnp)
		(fp_rect
			(start -0.925 -0.47)
			(end 0.925 0.47)
			(stroke
				(width 0.05)
				(type default)
			)
			(fill none)
			(layer "F.CrtYd")
		)
		(fp_rect
			(start -0.5 -0.25)
			(end 0.5 0.25)
			(stroke
				(width 0.15)
				(type solid)
			)
			(fill none)
			(layer "F.Fab")
		)
		(fp_text user "License: Apache-2.0"
			(at -0.95 5.169 0)
			(layer "F.Fab")
			(hide yes)
			(effects
				(font
					(size 0.7 0.7)
					(thickness 0.15)
				)
				(justify left bottom)
			)
		)
		(fp_text user "${REFERENCE}"
			(at -0.95 3.168 0)
			(layer "F.Fab")
			(hide yes)
			(effects
				(font
					(size 0.7 0.7)
					(thickness 0.15)
				)
				(justify left bottom)
			)
		)
		(fp_text user "Author: Antmicro"
			(at -0.95 4.169 0)
			(layer "F.Fab")
			(hide yes)
			(effects
				(font
					(size 0.7 0.7)
					(thickness 0.15)
				)
				(justify left bottom)
			)
		)
		(pad "1" smd roundrect
			(at -0.48 0)
			(size 0.59 0.64)
			(layers "F.Cu" "F.Paste" "F.Mask")
			(roundrect_rratio 0.25)
			(net 89 "/CSI Connector/I2C.SCL")
			(pintype "passive")
		)
		(pad "2" smd roundrect
			(at 0.48 0)
			(size 0.59 0.64)
			(layers "F.Cu" "F.Paste" "F.Mask")
			(roundrect_rratio 0.25)
			(net 79 "Net-(U6-MFP8)")
			(pintype "passive")
		)
	)
	(footprint "antmicro-footprints:C_0402_1005Metric"
		(layer "F.Cu")
		(at 131.12 84.881 -90)
		(descr "Capacitor SMD 0402")
		(tags "capacitor SMD 0402")
		(property "Reference" "C3"
			(at -0.73 0.589 90)
			(layer "F.SilkS")
			(effects
				(font
					(size 0.7 0.7)
					(thickness 0.15)
				)
				(justify right bottom)
			)
		)
		(property "Value" "C_220n_0402"
			(at -1.022927 2.155213 90)
			(layer "F.Fab")
			(effects
				(font
					(size 0.7 0.7)
					(thickness 0.15)
				)
				(justify right bottom)
			)
		)
		(property "Footprint" "antmicro-footprints:C_0402_1005Metric"
			(at 0 0 -90)
			(layer "F.Fab")
			(hide yes)
			(effects
				(font
					(size 1.27 1.27)
					(thickness 0.15)
				)
			)
		)
		(property "Datasheet" "https://www.yageo.com/en/Chart/Download/pdf/CC0402KRX5R6BB224"
			(at 0 0 -90)
			(layer "F.Fab")
			(hide yes)
			(effects
				(font
					(size 1.27 1.27)
					(thickness 0.15)
				)
			)
		)
		(property "Author" "Antmicro"
			(at 48.159 217.621 0)
			(layer "F.Fab")
			(hide yes)
			(effects
				(font
					(size 1 1)
					(thickness 0.15)
				)
			)
		)
		(property "Dielectric" ""
			(at 48.159 217.621 0)
			(layer "F.Fab")
			(hide yes)
			(effects
				(font
					(size 1 1)
					(thickness 0.15)
				)
			)
		)
		(property "License" "Apache-2.0"
			(at 48.159 217.621 0)
			(layer "F.Fab")
			(hide yes)
			(effects
				(font
					(size 1 1)
					(thickness 0.15)
				)
			)
		)
		(property "MPN" "CC0402KRX5R6BB224"
			(at 48.159 217.621 0)
			(layer "F.Fab")
			(hide yes)
			(effects
				(font
					(size 1 1)
					(thickness 0.15)
				)
			)
		)
		(property "Manufacturer" "YAGEO"
			(at 48.159 217.621 0)
			(layer "F.Fab")
			(hide yes)
			(effects
				(font
					(size 1 1)
					(thickness 0.15)
				)
			)
		)
		(property "Val" "220n"
			(at 48.159 217.621 0)
			(layer "F.Fab")
			(hide yes)
			(effects
				(font
					(size 1 1)
					(thickness 0.15)
				)
			)
		)
		(property "Voltage" ""
			(at 48.159 217.621 0)
			(layer "F.Fab")
			(hide yes)
			(effects
				(font
					(size 1 1)
					(thickness 0.15)
				)
			)
		)
		(sheetname "Supply")
		(sheetfile "supply.kicad_sch")
		(attr smd)
		(fp_rect
			(start -0.925 -0.47)
			(end 0.925 0.47)
			(stroke
				(width 0.05)
				(type default)
			)
			(fill none)
			(layer "F.CrtYd")
		)
		(fp_line
			(start -0.494 0.248)
			(end -0.494 -0.25)
			(stroke
				(width 0.15)
				(type solid)
			)
			(layer "F.Fab")
		)
		(fp_line
			(start 0.504 0.248)
			(end -0.494 0.248)
			(stroke
				(width 0.15)
				(type solid)
			)
			(layer "F.Fab")
		)
		(fp_line
			(start -0.494 -0.25)
			(end 0.504 -0.25)
			(stroke
				(width 0.15)
				(type solid)
			)
			(layer "F.Fab")
		)
		(fp_line
			(start 0.504 -0.25)
			(end 0.504 0.248)
			(stroke
				(width 0.15)
				(type solid)
			)
			(layer "F.Fab")
		)
		(fp_text user "Author: Antmicro"
			(at -0.939 3.399 90)
			(layer "F.Fab")
			(hide yes)
			(effects
				(font
					(size 0.7 0.7)
					(thickness 0.15)
				)
				(justify right bottom)
			)
		)
		(fp_text user "${REFERENCE}"
			(at -0.939 4.599 90)
			(layer "F.Fab")
			(hide yes)
			(effects
				(font
					(size 0.7 0.7)
					(thickness 0.15)
				)
				(justify right bottom)
			)
		)
		(fp_text user "License: Apache-2.0"
			(at -0.939 5.799 90)
			(layer "F.Fab")
			(hide yes)
			(effects
				(font
					(size 0.7 0.7)
					(thickness 0.15)
				)
				(justify right bottom)
			)
		)
		(pad "1" smd roundrect
			(at -0.48 0 270)
			(size 0.59 0.64)
			(layers "F.Cu" "F.Paste" "F.Mask")
			(roundrect_rratio 0.25)
			(net 3 "Net-(U1-BST)")
			(pintype "passive")
		)
		(pad "2" smd roundrect
			(at 0.48 0 270)
			(size 0.59 0.64)
			(layers "F.Cu" "F.Paste" "F.Mask")
			(roundrect_rratio 0.25)
			(net 4 "/Supply/SW_5V")
			(pintype "passive")
		)
	)
	(footprint "antmicro-footprints:R_0603_1608Metric"
		(layer "F.Cu")
		(at 164.4 106.3 -90)
		(descr "Resistor SMD 0603")
		(tags "resistor SMD 0603")
		(property "Reference" "R14"
			(at -0.675 -1.4976 90)
			(layer "F.SilkS")
			(effects
				(font
					(size 0.7 0.7)
					(thickness 0.15)
				)
				(justify right bottom)
			)
		)
		(property "Value" "R_0R_22.4A_0603"
			(at 0 1.6 90)
			(layer "F.Fab")
			(effects
				(font
					(size 0.7 0.7)
					(thickness 0.15)
				)
				(justify right bottom)
			)
		)
		(property "Footprint" "antmicro-footprints:R_0603_1608Metric"
			(at 0 0 -90)
			(layer "F.Fab")
			(hide yes)
			(effects
				(font
					(size 1.27 1.27)
					(thickness 0.15)
				)
			)
		)
		(property "Datasheet" "https://fscdn.rohm.com/en/products/databook/datasheet/passive/resistor/chip_resistor/pmr-jpw-e.pdf"
			(at 0 0 -90)
			(layer "F.Fab")
			(hide yes)
			(effects
				(font
					(size 1.27 1.27)
					(thickness 0.15)
				)
			)
		)
		(property "Author" "Antmicro"
			(at 58.1 270.7 0)
			(layer "F.Fab")
			(hide yes)
			(effects
				(font
					(size 1 1)
					(thickness 0.15)
				)
			)
		)
		(property "License" "Apache-2.0"
			(at 58.1 270.7 0)
			(layer "F.Fab")
			(hide yes)
			(effects
				(font
					(size 1 1)
					(thickness 0.15)
				)
			)
		)
		(property "MPN" "PMR03EZPJ000"
			(at 58.1 270.7 0)
			(layer "F.Fab")
			(hide yes)
			(effects
				(font
					(size 1 1)
					(thickness 0.15)
				)
			)
		)
		(property "Manufacturer" "ROHM Semiconductor"
			(at 58.1 270.7 0)
			(layer "F.Fab")
			(hide yes)
			(effects
				(font
					(size 1 1)
					(thickness 0.15)
				)
			)
		)
		(property "Max. Curr." "22.4A"
			(at 58.1 270.7 0)
			(layer "F.Fab")
			(hide yes)
			(effects
				(font
					(size 1 1)
					(thickness 0.15)
				)
			)
		)
		(property "Tolerance" "template_tolerance"
			(at 58.1 270.7 0)
			(layer "F.Fab")
			(hide yes)
			(effects
				(font
					(size 1 1)
					(thickness 0.15)
				)
			)
		)
		(property "Val" "0R"
			(at 58.1 270.7 0)
			(layer "F.Fab")
			(hide yes)
			(effects
				(font
					(size 1 1)
					(thickness 0.15)
				)
			)
		)
		(sheetname "Supply")
		(sheetfile "supply.kicad_sch")
		(attr smd)
		(fp_line
			(start -0.15 0.4)
			(end 0.15 0.4)
			(stroke
				(width 0.15)
				(type solid)
			)
			(layer "F.SilkS")
		)
		(fp_line
			(start -0.15 -0.4)
			(end 0.15 -0.4)
			(stroke
				(width 0.15)
				(type solid)
			)
			(layer "F.SilkS")
		)
		(fp_rect
			(start -1.25 -0.65)
			(end 1.25 0.65)
			(stroke
				(width 0.05)
				(type solid)
			)
			(fill none)
			(layer "F.CrtYd")
		)
		(fp_rect
			(start -0.8 -0.4)
			(end 0.8 0.4)
			(stroke
				(width 0.15)
				(type solid)
			)
			(fill none)
			(layer "F.Fab")
		)
		(fp_text user "${REFERENCE}"
			(at -1.25 3.898 90)
			(layer "F.Fab")
			(hide yes)
			(effects
				(font
					(size 0.7 0.7)
					(thickness 0.15)
				)
				(justify right bottom)
			)
		)
		(fp_text user "License: Apache-2.0"
			(at -1.25 5.9 90)
			(layer "F.Fab")
			(hide yes)
			(effects
				(font
					(size 0.7 0.7)
					(thickness 0.15)
				)
				(justify right bottom)
			)
		)
		(fp_text user "Author: Antmicro"
			(at -1.25 4.9 90)
			(layer "F.Fab")
			(hide yes)
			(effects
				(font
					(size 0.7 0.7)
					(thickness 0.15)
				)
				(justify right bottom)
			)
		)
		(pad "1" smd roundrect
			(at -0.7 0 270)
			(size 0.8 1)
			(layers "F.Cu" "F.Paste" "F.Mask")
			(roundrect_rratio 0.2)
			(net 8 "/Supply/OUT_1V8")
			(pintype "passive")
		)
		(pad "2" smd roundrect
			(at 0.7 0 270)
			(size 0.8 1)
			(layers "F.Cu" "F.Paste" "F.Mask")
			(roundrect_rratio 0.2)
			(net 11 "+1V8")
			(pintype "passive")
		)
	)
	(footprint "antmicro-footprints:TQFN-32-1EP_5x5mm_P0.5mm"
		(layer "F.Cu")
		(at 147.65 101.85 135)
		(property "Reference" "U6"
			(at -1.704127 -3.768879 -45)
			(unlocked yes)
			(layer "F.SilkS")
			(effects
				(font
					(size 0.7 0.7)
					(thickness 0.15)
				)
				(justify left bottom)
			)
		)
		(property "Value" "MAX96717GTJ_VY+"
			(at -3.05 4 135)
			(unlocked yes)
			(layer "F.Fab")
			(effects
				(font
					(size 0.7 0.7)
					(thickness 0.15)
				)
				(justify left bottom)
			)
		)
		(property "Footprint" "antmicro-footprints:TQFN-32-1EP_5x5mm_P0.5mm"
			(at 0 0 135)
			(layer "F.Fab")
			(hide yes)
			(effects
				(font
					(size 1.27 1.27)
					(thickness 0.15)
				)
			)
		)
		(property "Datasheet" "https://www.analog.com/media/en/technical-documentation/data-sheets/max96717.pdf"
			(at 0 0 135)
			(layer "F.Fab")
			(hide yes)
			(effects
				(font
					(size 1.27 1.27)
					(thickness 0.15)
				)
			)
		)
		(property "Author" "Antmicro"
			(at 324.073142 69.464509 0)
			(layer "F.Fab")
			(hide yes)
			(effects
				(font
					(size 1 1)
					(thickness 0.15)
				)
			)
		)
		(property "License" "Apache-2.0"
			(at 324.073142 69.464509 0)
			(layer "F.Fab")
			(hide yes)
			(effects
				(font
					(size 1 1)
					(thickness 0.15)
				)
			)
		)
		(property "MPN" "MAX96717GTJ/VY+"
			(at 324.073142 69.464509 0)
			(layer "F.Fab")
			(hide yes)
			(effects
				(font
					(size 1 1)
					(thickness 0.15)
				)
			)
		)
		(property "Manufacturer" "Analog Devices"
			(at 324.073142 69.464509 0)
			(layer "F.Fab")
			(hide yes)
			(effects
				(font
					(size 1 1)
					(thickness 0.15)
				)
			)
		)
		(sheetname "Serializer")
		(sheetfile "serializer.kicad_sch")
		(attr smd)
		(fp_poly
			(pts
				(xy 0.1 -1.5) (xy 0.1 -0.1) (xy 1.5 -0.1) (xy 1.5 -1.5)
			)
			(stroke
				(width 0)
				(type solid)
			)
			(fill solid)
			(layer "F.Paste")
		)
		(fp_poly
			(pts
				(xy 0.1 0.1) (xy 0.1 1.5) (xy 1.5 1.5) (xy 1.5 0.1)
			)
			(stroke
				(width 0)
				(type solid)
			)
			(fill solid)
			(layer "F.Paste")
		)
		(fp_poly
			(pts
				(xy -1.5 -1.5) (xy -1.5 -0.1) (xy -0.1 -0.1) (xy -0.1 -1.5)
			)
			(stroke
				(width 0)
				(type solid)
			)
			(fill solid)
			(layer "F.Paste")
		)
		(fp_poly
			(pts
				(xy -1.5 0.1) (xy -1.5 1.5) (xy -0.1 1.5) (xy -0.1 0.1)
			)
			(stroke
				(width 0)
				(type solid)
			)
			(fill solid)
			(layer "F.Paste")
		)
		(fp_line
			(start 2.629 -2.629)
			(end 2.21 -2.629)
			(stroke
				(width 0.15)
				(type solid)
			)
			(layer "F.SilkS")
		)
		(fp_line
			(start 2.629 -2.21)
			(end 2.629 -2.629)
			(stroke
				(width 0.15)
				(type solid)
			)
			(layer "F.SilkS")
		)
		(fp_line
			(start -2.21 -2.629)
			(end -2.629 -2.629)
			(stroke
				(width 0.15)
				(type solid)
			)
			(layer "F.SilkS")
		)
		(fp_line
			(start 2.629 2.629)
			(end 2.629 2.21)
			(stroke
				(width 0.15)
				(type solid)
			)
			(layer "F.SilkS")
		)
		(fp_line
			(start -2.629 -2.619)
			(end -2.629 -2.3)
			(stroke
				(width 0.15)
				(type solid)
			)
			(layer "F.SilkS")
		)
		(fp_line
			(start 2.21 2.629)
			(end 2.629 2.629)
			(stroke
				(width 0.15)
				(type solid)
			)
			(layer "F.SilkS")
		)
		(fp_line
			(start -2.629 2.21)
			(end -2.629 2.629)
			(stroke
				(width 0.15)
				(type solid)
			)
			(layer "F.SilkS")
		)
		(fp_line
			(start -2.629 2.629)
			(end -2.21 2.629)
			(stroke
				(width 0.15)
				(type solid)
			)
			(layer "F.SilkS")
		)
		(fp_circle
			(center -2.7 -2.05)
			(end -2.65 -2.05)
			(stroke
				(width 0.15)
				(type solid)
			)
			(fill solid)
			(layer "F.SilkS")
		)
		(fp_poly
			(pts
				(xy -2.88 -2.92) (xy 2.88 -2.92) (xy 2.88 2.9) (xy -2.88 2.9)
			)
			(stroke
				(width 0.05)
				(type solid)
			)
			(fill none)
			(layer "F.CrtYd")
		)
		(fp_line
			(start 2.502 -2.502)
			(end 2.502 -2.502)
			(stroke
				(width 0.15)
				(type solid)
			)
			(layer "F.Fab")
		)
		(fp_line
			(start 2.502 -2.502)
			(end -2.502 -2.502)
			(stroke
				(width 0.15)
				(type solid)
			)
			(layer "F.Fab")
		)
		(fp_line
			(start 2.502 -1.902)
			(end 2.502 -1.902)
			(stroke
				(width 0.15)
				(type solid)
			)
			(layer "F.Fab")
		)
		(fp_line
			(start 2.502 -1.902)
			(end 2.502 -1.598)
			(stroke
				(width 0.15)
				(type solid)
			)
			(layer "F.Fab")
		)
		(fp_line
			(start 1.902 -2.502)
			(end 1.902 -2.502)
			(stroke
				(width 0.15)
				(type solid)
			)
			(layer "F.Fab")
		)
		(fp_line
			(start 1.902 -2.502)
			(end 1.598 -2.502)
			(stroke
				(width 0.15)
				(type solid)
			)
			(layer "F.Fab")
		)
		(fp_line
			(start 2.502 -1.598)
			(end 2.502 -1.902)
			(stroke
				(width 0.15)
				(type solid)
			)
			(layer "F.Fab")
		)
		(fp_line
			(start 2.502 -1.598)
			(end 2.502 -1.598)
			(stroke
				(width 0.15)
				(type solid)
			)
			(layer "F.Fab")
		)
		(fp_line
			(start 1.598 -2.502)
			(end 1.902 -2.502)
			(stroke
				(width 0.15)
				(type solid)
			)
			(layer "F.Fab")
		)
		(fp_line
			(start 1.598 -2.502)
			(end 1.598 -2.502)
			(stroke
				(width 0.15)
				(type solid)
			)
			(layer "F.Fab")
		)
		(fp_line
			(start 2.502 -1.402)
			(end 2.502 -1.402)
			(stroke
				(width 0.15)
				(type solid)
			)
			(layer "F.Fab")
		)
		(fp_line
			(start 2.502 -1.402)
			(end 2.502 -1.098)
			(stroke
				(width 0.15)
				(type solid)
			)
			(layer "F.Fab")
		)
		(fp_line
			(start 1.402 -2.502)
			(end 1.402 -2.502)
			(stroke
				(width 0.15)
				(type solid)
			)
			(layer "F.Fab")
		)
		(fp_line
			(start 1.402 -2.502)
			(end 1.098 -2.502)
			(stroke
				(width 0.15)
				(type solid)
			)
			(layer "F.Fab")
		)
		(fp_line
			(start 2.502 -1.098)
			(end 2.502 -1.402)
			(stroke
				(width 0.15)
				(type solid)
			)
			(layer "F.Fab")
		)
		(fp_line
			(start 2.502 -1.098)
			(end 2.502 -1.098)
			(stroke
				(width 0.15)
				(type solid)
			)
			(layer "F.Fab")
		)
		(fp_line
			(start 1.098 -2.502)
			(end 1.402 -2.502)
			(stroke
				(width 0.15)
				(type solid)
			)
			(layer "F.Fab")
		)
		(fp_line
			(start 1.098 -2.502)
			(end 1.098 -2.502)
			(stroke
				(width 0.15)
				(type solid)
			)
			(layer "F.Fab")
		)
		(fp_line
			(start 2.502 -0.902)
			(end 2.502 -0.902)
			(stroke
				(width 0.15)
				(type solid)
			)
			(layer "F.Fab")
		)
		(fp_line
			(start 2.502 -0.902)
			(end 2.502 -0.598)
			(stroke
				(width 0.15)
				(type solid)
			)
			(layer "F.Fab")
		)
		(fp_line
			(start 0.902 -2.502)
			(end 0.902 -2.502)
			(stroke
				(width 0.15)
				(type solid)
			)
			(layer "F.Fab")
		)
		(fp_line
			(start 0.902 -2.502)
			(end 0.598 -2.502)
			(stroke
				(width 0.15)
				(type solid)
			)
			(layer "F.Fab")
		)
		(fp_line
			(start 2.502 -0.598)
			(end 2.502 -0.902)
			(stroke
				(width 0.15)
				(type solid)
			)
			(layer "F.Fab")
		)
		(fp_line
			(start 2.502 -0.598)
			(end 2.502 -0.598)
			(stroke
				(width 0.15)
				(type solid)
			)
			(layer "F.Fab")
		)
		(fp_line
			(start 0.598 -2.502)
			(end 0.902 -2.502)
			(stroke
				(width 0.15)
				(type solid)
			)
			(layer "F.Fab")
		)
		(fp_line
			(start 0.598 -2.502)
			(end 0.598 -2.502)
			(stroke
				(width 0.15)
				(type solid)
			)
			(layer "F.Fab")
		)
		(fp_line
			(start 2.502 -0.402)
			(end 2.502 -0.402)
			(stroke
				(width 0.15)
				(type solid)
			)
			(layer "F.Fab")
		)
		(fp_line
			(start 2.502 -0.402)
			(end 2.502 -0.098)
			(stroke
				(width 0.15)
				(type solid)
			)
			(layer "F.Fab")
		)
		(fp_line
			(start 0.402 -2.502)
			(end 0.402 -2.502)
			(stroke
				(width 0.15)
				(type solid)
			)
			(layer "F.Fab")
		)
		(fp_line
			(start 0.402 -2.502)
			(end 0.098 -2.502)
			(stroke
				(width 0.15)
				(type solid)
			)
			(layer "F.Fab")
		)
		(fp_line
			(start 2.502 -0.098)
			(end 2.502 -0.402)
			(stroke
				(width 0.15)
				(type solid)
			)
			(layer "F.Fab")
		)
		(fp_line
			(start 2.502 -0.098)
			(end 2.502 -0.098)
			(stroke
				(width 0.15)
				(type solid)
			)
			(layer "F.Fab")
		)
		(fp_line
			(start 0.098 -2.502)
			(end 0.402 -2.502)
			(stroke
				(width 0.15)
				(type solid)
			)
			(layer "F.Fab")
		)
		(fp_line
			(start 0.098 -2.502)
			(end 0.098 -2.502)
			(stroke
				(width 0.15)
				(type solid)
			)
			(layer "F.Fab")
		)
		(fp_line
			(start 2.502 0.098)
			(end 2.502 0.098)
			(stroke
				(width 0.15)
				(type solid)
			)
			(layer "F.Fab")
		)
		(fp_line
			(start 2.502 0.098)
			(end 2.502 0.402)
			(stroke
				(width 0.15)
				(type solid)
			)
			(layer "F.Fab")
		)
		(fp_line
			(start -0.098 -2.502)
			(end -0.098 -2.502)
			(stroke
				(width 0.15)
				(type solid)
			)
			(layer "F.Fab")
		)
		(fp_line
			(start -0.098 -2.502)
			(end -0.402 -2.502)
			(stroke
				(width 0.15)
				(type solid)
			)
			(layer "F.Fab")
		)
		(fp_line
			(start 2.502 0.402)
			(end 2.502 0.098)
			(stroke
				(width 0.15)
				(type solid)
			)
			(layer "F.Fab")
		)
		(fp_line
			(start 2.502 0.402)
			(end 2.502 0.402)
			(stroke
				(width 0.15)
				(type solid)
			)
			(layer "F.Fab")
		)
		(fp_line
			(start -0.402 -2.502)
			(end -0.098 -2.502)
			(stroke
				(width 0.15)
				(type solid)
			)
			(layer "F.Fab")
		)
		(fp_line
			(start -0.402 -2.502)
			(end -0.402 -2.502)
			(stroke
				(width 0.15)
				(type solid)
			)
			(layer "F.Fab")
		)
		(fp_line
			(start 2.502 0.598)
			(end 2.502 0.598)
			(stroke
				(width 0.15)
				(type solid)
			)
			(layer "F.Fab")
		)
		(fp_line
			(start 2.502 0.598)
			(end 2.502 0.902)
			(stroke
				(width 0.15)
				(type solid)
			)
			(layer "F.Fab")
		)
		(fp_line
			(start -0.598 -2.502)
			(end -0.598 -2.502)
			(stroke
				(width 0.15)
				(type solid)
			)
			(layer "F.Fab")
		)
		(fp_line
			(start -0.598 -2.502)
			(end -0.902 -2.502)
			(stroke
				(width 0.15)
				(type solid)
			)
			(layer "F.Fab")
		)
		(fp_line
			(start 2.502 0.902)
			(end 2.502 0.598)
			(stroke
				(width 0.15)
				(type solid)
			)
			(layer "F.Fab")
		)
		(fp_line
			(start 2.502 0.902)
			(end 2.502 0.902)
			(stroke
				(width 0.15)
				(type solid)
			)
			(layer "F.Fab")
		)
		(fp_line
			(start -0.902 -2.502)
			(end -0.598 -2.502)
			(stroke
				(width 0.15)
				(type solid)
			)
			(layer "F.Fab")
		)
		(fp_line
			(start -0.902 -2.502)
			(end -0.902 -2.502)
			(stroke
				(width 0.15)
				(type solid)
			)
			(layer "F.Fab")
		)
		(fp_line
			(start 2.502 1.098)
			(end 2.502 1.098)
			(stroke
				(width 0.15)
				(type solid)
			)
			(layer "F.Fab")
		)
		(fp_line
			(start 2.502 1.098)
			(end 2.502 1.402)
			(stroke
				(width 0.15)
				(type solid)
			)
			(layer "F.Fab")
		)
		(fp_line
			(start -1.098 -2.502)
			(end -1.098 -2.502)
			(stroke
				(width 0.15)
				(type solid)
			)
			(layer "F.Fab")
		)
		(fp_line
			(start -1.098 -2.502)
			(end -1.402 -2.502)
			(stroke
				(width 0.15)
				(type solid)
			)
			(layer "F.Fab")
		)
		(fp_line
			(start 2.502 1.402)
			(end 2.502 1.098)
			(stroke
				(width 0.15)
				(type solid)
			)
			(layer "F.Fab")
		)
		(fp_line
			(start 2.502 1.402)
			(end 2.502 1.402)
			(stroke
				(width 0.15)
				(type solid)
			)
			(layer "F.Fab")
		)
		(fp_line
			(start -1.402 -2.502)
			(end -1.098 -2.502)
			(stroke
				(width 0.15)
				(type solid)
			)
			(layer "F.Fab")
		)
		(fp_line
			(start -1.402 -2.502)
			(end -1.402 -2.502)
			(stroke
				(width 0.15)
				(type solid)
			)
			(layer "F.Fab")
		)
		(fp_line
			(start 2.502 1.598)
			(end 2.502 1.598)
			(stroke
				(width 0.15)
				(type solid)
			)
			(layer "F.Fab")
		)
		(fp_line
			(start 2.502 1.598)
			(end 2.502 1.902)
			(stroke
				(width 0.15)
				(type solid)
			)
			(layer "F.Fab")
		)
		(fp_line
			(start -1.598 -2.502)
			(end -1.598 -2.502)
			(stroke
				(width 0.15)
				(type solid)
			)
			(layer "F.Fab")
		)
		(fp_line
			(start -1.598 -2.502)
			(end -1.902 -2.502)
			(stroke
				(width 0.15)
				(type solid)
			)
			(layer "F.Fab")
		)
		(fp_line
			(start 2.502 1.902)
			(end 2.502 1.598)
			(stroke
				(width 0.15)
				(type solid)
			)
			(layer "F.Fab")
		)
		(fp_line
			(start 2.502 1.902)
			(end 2.502 1.902)
			(stroke
				(width 0.15)
				(type solid)
			)
			(layer "F.Fab")
		)
		(fp_line
			(start -1.902 -2.502)
			(end -1.598 -2.502)
			(stroke
				(width 0.15)
				(type solid)
			)
			(layer "F.Fab")
		)
		(fp_line
			(start -1.902 -2.502)
			(end -1.902 -2.502)
			(stroke
				(width 0.15)
				(type solid)
			)
			(layer "F.Fab")
		)
		(fp_line
			(start 2.502 2.502)
			(end 2.502 -2.502)
			(stroke
				(width 0.15)
				(type solid)
			)
			(layer "F.Fab")
		)
		(fp_line
			(start 2.502 2.502)
			(end 2.502 2.502)
			(stroke
				(width 0.15)
				(type solid)
			)
			(layer "F.Fab")
		)
		(fp_line
			(start -2.502 -2.502)
			(end -2.502 -2.502)
			(stroke
				(width 0.15)
				(type solid)
			)
			(layer "F.Fab")
		)
		(fp_line
			(start -2.502 -2.502)
			(end -2.502 2.502)
			(stroke
				(width 0.15)
				(type solid)
			)
			(layer "F.Fab")
		)
		(fp_line
			(start 1.902 2.502)
			(end 1.902 2.502)
			(stroke
				(width 0.15)
				(type solid)
			)
			(layer "F.Fab")
		)
		(fp_line
			(start 1.902 2.502)
			(end 1.598 2.502)
			(stroke
				(width 0.15)
				(type solid)
			)
			(layer "F.Fab")
		)
		(fp_line
			(start -2.502 -1.902)
			(end -2.502 -1.902)
			(stroke
				(width 0.15)
				(type solid)
			)
			(layer "F.Fab")
		)
		(fp_line
			(start -2.502 -1.902)
			(end -2.502 -1.598)
			(stroke
				(width 0.15)
				(type solid)
			)
			(layer "F.Fab")
		)
		(fp_line
			(start 1.598 2.502)
			(end 1.902 2.502)
			(stroke
				(width 0.15)
				(type solid)
			)
			(layer "F.Fab")
		)
		(fp_line
			(start 1.598 2.502)
			(end 1.598 2.502)
			(stroke
				(width 0.15)
				(type solid)
			)
			(layer "F.Fab")
		)
		(fp_line
			(start -2.502 -1.598)
			(end -2.502 -1.902)
			(stroke
				(width 0.15)
				(type solid)
			)
			(layer "F.Fab")
		)
		(fp_line
			(start -2.502 -1.598)
			(end -2.502 -1.598)
			(stroke
				(width 0.15)
				(type solid)
			)
			(layer "F.Fab")
		)
		(fp_line
			(start 1.402 2.502)
			(end 1.402 2.502)
			(stroke
				(width 0.15)
				(type solid)
			)
			(layer "F.Fab")
		)
		(fp_line
			(start 1.402 2.502)
			(end 1.098 2.502)
			(stroke
				(width 0.15)
				(type solid)
			)
			(layer "F.Fab")
		)
		(fp_line
			(start -2.502 -1.402)
			(end -2.502 -1.402)
			(stroke
				(width 0.15)
				(type solid)
			)
			(layer "F.Fab")
		)
		(fp_line
			(start -2.502 -1.402)
			(end -2.502 -1.098)
			(stroke
				(width 0.15)
				(type solid)
			)
			(layer "F.Fab")
		)
		(fp_line
			(start -2.502 -1.232)
			(end -1.232 -2.502)
			(stroke
				(width 0.15)
				(type solid)
			)
			(layer "F.Fab")
		)
		(fp_line
			(start 1.098 2.502)
			(end 1.402 2.502)
			(stroke
				(width 0.15)
				(type solid)
			)
			(layer "F.Fab")
		)
		(fp_line
			(start 1.098 2.502)
			(end 1.098 2.502)
			(stroke
				(width 0.15)
				(type solid)
			)
			(layer "F.Fab")
		)
		(fp_line
			(start -2.502 -1.098)
			(end -2.502 -1.402)
			(stroke
				(width 0.15)
				(type solid)
			)
			(layer "F.Fab")
		)
		(fp_line
			(start -2.502 -1.098)
			(end -2.502 -1.098)
			(stroke
				(width 0.15)
				(type solid)
			)
			(layer "F.Fab")
		)
		(fp_line
			(start 0.902 2.502)
			(end 0.902 2.502)
			(stroke
				(width 0.15)
				(type solid)
			)
			(layer "F.Fab")
		)
		(fp_line
			(start 0.902 2.502)
			(end 0.598 2.502)
			(stroke
				(width 0.15)
				(type solid)
			)
			(layer "F.Fab")
		)
		(fp_line
			(start -2.502 -0.902)
			(end -2.502 -0.902)
			(stroke
				(width 0.15)
				(type solid)
			)
			(layer "F.Fab")
		)
		(fp_line
			(start -2.502 -0.902)
			(end -2.502 -0.598)
			(stroke
				(width 0.15)
				(type solid)
			)
			(layer "F.Fab")
		)
		(fp_line
			(start 0.598 2.502)
			(end 0.902 2.502)
			(stroke
				(width 0.15)
				(type solid)
			)
			(layer "F.Fab")
		)
		(fp_line
			(start 0.598 2.502)
			(end 0.598 2.502)
			(stroke
				(width 0.15)
				(type solid)
			)
			(layer "F.Fab")
		)
		(fp_line
			(start -2.502 -0.598)
			(end -2.502 -0.902)
			(stroke
				(width 0.15)
				(type solid)
			)
			(layer "F.Fab")
		)
		(fp_line
			(start -2.502 -0.598)
			(end -2.502 -0.598)
			(stroke
				(width 0.15)
				(type solid)
			)
			(layer "F.Fab")
		)
		(fp_line
			(start 0.402 2.502)
			(end 0.402 2.502)
			(stroke
				(width 0.15)
				(type solid)
			)
			(layer "F.Fab")
		)
		(fp_line
			(start 0.402 2.502)
			(end 0.098 2.502)
			(stroke
				(width 0.15)
				(type solid)
			)
			(layer "F.Fab")
		)
		(fp_line
			(start -2.502 -0.402)
			(end -2.502 -0.402)
			(stroke
				(width 0.15)
				(type solid)
			)
			(layer "F.Fab")
		)
		(fp_line
			(start -2.502 -0.402)
			(end -2.502 -0.098)
			(stroke
				(width 0.15)
				(type solid)
			)
			(layer "F.Fab")
		)
		(fp_line
			(start 0.098 2.502)
			(end 0.402 2.502)
			(stroke
				(width 0.15)
				(type solid)
			)
			(layer "F.Fab")
		)
		(fp_line
			(start 0.098 2.502)
			(end 0.098 2.502)
			(stroke
				(width 0.15)
				(type solid)
			)
			(layer "F.Fab")
		)
		(fp_line
			(start -2.502 -0.098)
			(end -2.502 -0.402)
			(stroke
				(width 0.15)
				(type solid)
			)
			(layer "F.Fab")
		)
		(fp_line
			(start -2.502 -0.098)
			(end -2.502 -0.098)
			(stroke
				(width 0.15)
				(type solid)
			)
			(layer "F.Fab")
		)
		(fp_line
			(start -0.098 2.502)
			(end -0.098 2.502)
			(stroke
				(width 0.15)
				(type solid)
			)
			(layer "F.Fab")
		)
		(fp_line
			(start -0.098 2.502)
			(end -0.402 2.502)
			(stroke
				(width 0.15)
				(type solid)
			)
			(layer "F.Fab")
		)
		(fp_line
			(start -2.502 0.098)
			(end -2.502 0.098)
			(stroke
				(width 0.15)
				(type solid)
			)
			(layer "F.Fab")
		)
		(fp_line
			(start -2.502 0.098)
			(end -2.502 0.402)
			(stroke
				(width 0.15)
				(type solid)
			)
			(layer "F.Fab")
		)
		(fp_line
			(start -0.402 2.502)
			(end -0.098 2.502)
			(stroke
				(width 0.15)
				(type solid)
			)
			(layer "F.Fab")
		)
		(fp_line
			(start -0.402 2.502)
			(end -0.402 2.502)
			(stroke
				(width 0.15)
				(type solid)
			)
			(layer "F.Fab")
		)
		(fp_line
			(start -2.502 0.402)
			(end -2.502 0.098)
			(stroke
				(width 0.15)
				(type solid)
			)
			(layer "F.Fab")
		)
		(fp_line
			(start -2.502 0.402)
			(end -2.502 0.402)
			(stroke
				(width 0.15)
				(type solid)
			)
			(layer "F.Fab")
		)
		(fp_line
			(start -0.598 2.502)
			(end -0.598 2.502)
			(stroke
				(width 0.15)
				(type solid)
			)
			(layer "F.Fab")
		)
		(fp_line
			(start -0.598 2.502)
			(end -0.902 2.502)
			(stroke
				(width 0.15)
				(type solid)
			)
			(layer "F.Fab")
		)
		(fp_line
			(start -2.502 0.598)
			(end -2.502 0.598)
			(stroke
				(width 0.15)
				(type solid)
			)
			(layer "F.Fab")
		)
		(fp_line
			(start -2.502 0.598)
			(end -2.502 0.902)
			(stroke
				(width 0.15)
				(type solid)
			)
			(layer "F.Fab")
		)
		(fp_line
			(start -0.902 2.502)
			(end -0.598 2.502)
			(stroke
				(width 0.15)
				(type solid)
			)
			(layer "F.Fab")
		)
		(fp_line
			(start -0.902 2.502)
			(end -0.902 2.502)
			(stroke
				(width 0.15)
				(type solid)
			)
			(layer "F.Fab")
		)
		(fp_line
			(start -2.502 0.902)
			(end -2.502 0.598)
			(stroke
				(width 0.15)
				(type solid)
			)
			(layer "F.Fab")
		)
		(fp_line
			(start -2.502 0.902)
			(end -2.502 0.902)
			(stroke
				(width 0.15)
				(type solid)
			)
			(layer "F.Fab")
		)
		(fp_line
			(start -1.098 2.502)
			(end -1.098 2.502)
			(stroke
				(width 0.15)
				(type solid)
			)
			(layer "F.Fab")
		)
		(fp_line
			(start -1.098 2.502)
			(end -1.402 2.502)
			(stroke
				(width 0.15)
				(type solid)
			)
			(layer "F.Fab")
		)
		(fp_line
			(start -2.502 1.098)
			(end -2.502 1.098)
			(stroke
				(width 0.15)
				(type solid)
			)
			(layer "F.Fab")
		)
		(fp_line
			(start -2.502 1.098)
			(end -2.502 1.402)
			(stroke
				(width 0.15)
				(type solid)
			)
			(layer "F.Fab")
		)
		(fp_line
			(start -1.402 2.502)
			(end -1.098 2.502)
			(stroke
				(width 0.15)
				(type solid)
			)
			(layer "F.Fab")
		)
		(fp_line
			(start -1.402 2.502)
			(end -1.402 2.502)
			(stroke
				(width 0.15)
				(type solid)
			)
			(layer "F.Fab")
		)
		(fp_line
			(start -2.502 1.402)
			(end -2.502 1.098)
			(stroke
				(width 0.15)
				(type solid)
			)
			(layer "F.Fab")
		)
		(fp_line
			(start -2.502 1.402)
			(end -2.502 1.402)
			(stroke
				(width 0.15)
				(type solid)
			)
			(layer "F.Fab")
		)
		(fp_line
			(start -1.598 2.502)
			(end -1.598 2.502)
			(stroke
				(width 0.15)
				(type solid)
			)
			(layer "F.Fab")
		)
		(fp_line
			(start -1.598 2.502)
			(end -1.902 2.502)
			(stroke
				(width 0.15)
				(type solid)
			)
			(layer "F.Fab")
		)
		(fp_line
			(start -2.502 1.598)
			(end -2.502 1.598)
			(stroke
				(width 0.15)
				(type solid)
			)
			(layer "F.Fab")
		)
		(fp_line
			(start -2.502 1.598)
			(end -2.502 1.902)
			(stroke
				(width 0.15)
				(type solid)
			)
			(layer "F.Fab")
		)
		(fp_line
			(start -1.902 2.502)
			(end -1.598 2.502)
			(stroke
				(width 0.15)
				(type solid)
			)
			(layer "F.Fab")
		)
		(fp_line
			(start -1.902 2.502)
			(end -1.902 2.502)
			(stroke
				(width 0.15)
				(type solid)
			)
			(layer "F.Fab")
		)
		(fp_line
			(start -2.502 1.902)
			(end -2.502 1.598)
			(stroke
				(width 0.15)
				(type solid)
			)
			(layer "F.Fab")
		)
		(fp_line
			(start -2.502 1.902)
			(end -2.502 1.902)
			(stroke
				(width 0.15)
				(type solid)
			)
			(layer "F.Fab")
		)
		(fp_line
			(start -2.502 2.502)
			(end 2.502 2.502)
			(stroke
				(width 0.15)
				(type solid)
			)
			(layer "F.Fab")
		)
		(fp_line
			(start -2.502 2.502)
			(end -2.502 2.502)
			(stroke
				(width 0.15)
				(type solid)
			)
			(layer "F.Fab")
		)
		(fp_circle
			(center -2.7 -2.05)
			(end -2.65 -2.05)
			(stroke
				(width 0.15)
				(type solid)
			)
			(fill solid)
			(layer "F.Fab")
		)
		(fp_text user "Author: Antmicro"
			(at -3.1 7.600001 135)
			(layer "F.Fab")
			(hide yes)
			(effects
				(font
					(size 0.7 0.7)
					(thickness 0.15)
				)
				(justify left bottom)
			)
		)
		(fp_text user "License: Apache-2.0"
			(at -3.1 5.2 135)
			(layer "F.Fab")
			(hide yes)
			(effects
				(font
					(size 0.7 0.7)
					(thickness 0.15)
				)
				(justify left bottom)
			)
		)
		(fp_text user "${REFERENCE}"
			(at -3.1 6.399999 135)
			(unlocked yes)
			(layer "F.Fab")
			(hide yes)
			(effects
				(font
					(size 0.7 0.7)
					(thickness 0.15)
				)
				(justify left bottom)
			)
		)
		(pad "1" smd roundrect
			(at -2.4 -1.75 225)
			(size 0.254 0.8128)
			(layers "F.Cu" "F.Paste" "F.Mask")
			(roundrect_rratio 0.25)
			(net 77 "Net-(U6-PWDNB)")
			(pinfunction "PWDNB")
			(pintype "input")
		)
		(pad "2" smd roundrect
			(at -2.4 -1.25 225)
			(size 0.254 0.8128)
			(layers "F.Cu" "F.Paste" "F.Mask")
			(roundrect_rratio 0.25)
			(net 83 "Net-(U6-MFP0)")
			(pinfunction "MFP0")
			(pintype "bidirectional")
		)
		(pad "3" smd roundrect
			(at -2.4 -0.75 225)
			(size 0.254 0.8128)
			(layers "F.Cu" "F.Paste" "F.Mask")
			(roundrect_rratio 0.25)
			(net 66 "/Serializer/CFG0")
			(pinfunction "MFP1")
			(pintype "bidirectional")
		)
		(pad "4" smd roundrect
			(at -2.4 -0.25 225)
			(size 0.254 0.8128)
			(layers "F.Cu" "F.Paste" "F.Mask")
			(roundrect_rratio 0.25)
			(net 68 "/Serializer/CFG1")
			(pinfunction "MFP2")
			(pintype "bidirectional")
		)
		(pad "5" smd roundrect
			(at -2.4 0.25 225)
			(size 0.254 0.8128)
			(layers "F.Cu" "F.Paste" "F.Mask")
			(roundrect_rratio 0.25)
			(net 81 "Net-(U6-MFP9)")
			(pinfunction "MFP9")
			(pintype "bidirectional")
		)
		(pad "6" smd roundrect
			(at -2.4 0.75 225)
			(size 0.254 0.8128)
			(layers "F.Cu" "F.Paste" "F.Mask")
			(roundrect_rratio 0.25)
			(net 82 "Net-(U6-MFP10)")
			(pinfunction "MFP10")
			(pintype "bidirectional")
		)
		(pad "7" smd roundrect
			(at -2.4 1.25 225)
			(size 0.254 0.8128)
			(layers "F.Cu" "F.Paste" "F.Mask")
			(roundrect_rratio 0.25)
			(net 90 "/Serializer/VREF")
			(pinfunction "VREF")
			(pintype "power_in")
		)
		(pad "8" smd roundrect
			(at -2.4 1.75 225)
			(size 0.254 0.8128)
			(layers "F.Cu" "F.Paste" "F.Mask")
			(roundrect_rratio 0.25)
			(net 13 "/Serializer/X1")
			(pinfunction "X1/OSC")
			(pintype "bidirectional")
		)
		(pad "9" smd roundrect
			(at -1.75 2.4 135)
			(size 0.254 0.8128)
			(layers "F.Cu" "F.Paste" "F.Mask")
			(roundrect_rratio 0.25)
			(net 67 "/Serializer/X2")
			(pinfunction "X2")
			(pintype "bidirectional")
		)
		(pad "10" smd roundrect
			(at -1.25 2.4 135)
			(size 0.254 0.8128)
			(layers "F.Cu" "F.Paste" "F.Mask")
			(roundrect_rratio 0.25)
			(net 76 "Net-(U6-XRES)")
			(pinfunction "XRES")
			(pintype "passive")
		)
		(pad "11" smd roundrect
			(at -0.75 2.4 135)
			(size 0.254 0.8128)
			(layers "F.Cu" "F.Paste" "F.Mask")
			(roundrect_rratio 0.25)
			(net 11 "+1V8")
			(pinfunction "VDD18")
			(pintype "power_in")
		)
		(pad "12" smd roundrect
			(at -0.25 2.4 135)
			(size 0.254 0.8128)
			(layers "F.Cu" "F.Paste" "F.Mask")
			(roundrect_rratio 0.25)
			(net 17 "Net-(U6-SIOP)")
			(pinfunction "SIOP")
			(pintype "bidirectional")
		)
		(pad "13" smd roundrect
			(at 0.25 2.4 135)
			(size 0.254 0.8128)
			(layers "F.Cu" "F.Paste" "F.Mask")
			(roundrect_rratio 0.25)
			(net 33 "Net-(U6-SION)")
			(pinfunction "SION")
			(pintype "bidirectional")
		)
		(pad "14" smd roundrect
			(at 0.75 2.4 135)
			(size 0.254 0.8128)
			(layers "F.Cu" "F.Paste" "F.Mask")
			(roundrect_rratio 0.25)
			(net 15 "Net-(U6-CAP_VDD)")
			(pinfunction "CAP_VDD")
			(pintype "power_in")
		)
		(pad "15" smd roundrect
			(at 1.25 2.4 135)
			(size 0.254 0.8128)
			(layers "F.Cu" "F.Paste" "F.Mask")
			(roundrect_rratio 0.25)
			(net 12 "+1V2")
			(pinfunction "VDD")
			(pintype "power_in")
		)
		(pad "16" smd roundrect
			(at 1.75 2.4 135)
			(size 0.254 0.8128)
			(layers "F.Cu" "F.Paste" "F.Mask")
			(roundrect_rratio 0.25)
			(net 10 "+3V3")
			(pinfunction "VDDIO")
			(pintype "power_in")
		)
		(pad "17" smd roundrect
			(at 2.4 1.75 225)
			(size 0.254 0.8128)
			(layers "F.Cu" "F.Paste" "F.Mask")
			(roundrect_rratio 0.25)
			(net 38 "/CSI Connector/GPIO3")
			(pinfunction "MFP3")
			(pintype "bidirectional")
		)
		(pad "18" smd roundrect
			(at 2.4 1.25 225)
			(size 0.254 0.8128)
			(layers "F.Cu" "F.Paste" "F.Mask")
			(roundrect_rratio 0.25)
			(net 87 "/CSI Connector/GPIO4")
			(pinfunction "MFP4")
			(pintype "bidirectional")
		)
		(pad "19" smd roundrect
			(at 2.4 0.75 225)
			(size 0.254 0.8128)
			(layers "F.Cu" "F.Paste" "F.Mask")
			(roundrect_rratio 0.25)
			(net 44 "/CSI Connector/CSI.D2_P")
			(pinfunction "D2P")
			(pintype "input")
		)
		(pad "20" smd roundrect
			(at 2.4 0.25 225)
			(size 0.254 0.8128)
			(layers "F.Cu" "F.Paste" "F.Mask")
			(roundrect_rratio 0.25)
			(net 42 "/CSI Connector/CSI.D2_N")
			(pinfunction "D2N")
			(pintype "input")
		)
		(pad "21" smd roundrect
			(at 2.4 -0.25 225)
			(size 0.254 0.8128)
			(layers "F.Cu" "F.Paste" "F.Mask")
			(roundrect_rratio 0.25)
			(net 84 "Net-(U6-MFP5)")
			(pinfunction "MFP5")
			(pintype "bidirectional")
		)
		(pad "22" smd roundrect
			(at 2.4 -0.75 225)
			(size 0.254 0.8128)
			(layers "F.Cu" "F.Paste" "F.Mask")
			(roundrect_rratio 0.25)
			(net 85 "Net-(U6-MFP6)")
			(pinfunction "MFP6")
			(pintype "bidirectional")
		)
		(pad "23" smd roundrect
			(at 2.4 -1.25 225)
			(size 0.254 0.8128)
			(layers "F.Cu" "F.Paste" "F.Mask")
			(roundrect_rratio 0.25)
			(net 41 "/CSI Connector/CSI.D3_P")
			(pinfunction "D3P")
			(pintype "input")
		)
		(pad "24" smd roundrect
			(at 2.4 -1.75 225)
			(size 0.254 0.8128)
			(layers "F.Cu" "F.Paste" "F.Mask")
			(roundrect_rratio 0.25)
			(net 40 "/CSI Connector/CSI.D3_N")
			(pinfunction "D3N")
			(pintype "input")
		)
		(pad "25" smd roundrect
			(at 1.75 -2.4 135)
			(size 0.254 0.8128)
			(layers "F.Cu" "F.Paste" "F.Mask")
			(roundrect_rratio 0.25)
			(net 57 "/CSI Connector/CSI.D0_P")
			(pinfunction "D0P")
			(pintype "input")
		)
		(pad "26" smd roundrect
			(at 1.25 -2.4 135)
			(size 0.254 0.8128)
			(layers "F.Cu" "F.Paste" "F.Mask")
			(roundrect_rratio 0.25)
			(net 56 "/CSI Connector/CSI.D0_N")
			(pinfunction "D0N")
			(pintype "input")
		)
		(pad "27" smd roundrect
			(at 0.75 -2.4 135)
			(size 0.254 0.8128)
			(layers "F.Cu" "F.Paste" "F.Mask")
			(roundrect_rratio 0.25)
			(net 80 "/CSI Connector/CSI.CLK_P")
			(pinfunction "CKP")
			(pintype "input")
		)
		(pad "28" smd roundrect
			(at 0.25 -2.4 135)
			(size 0.254 0.8128)
			(layers "F.Cu" "F.Paste" "F.Mask")
			(roundrect_rratio 0.25)
			(net 61 "/CSI Connector/CSI.CLK_N")
			(pinfunction "CKN")
			(pintype "input")
		)
		(pad "29" smd roundrect
			(at -0.25 -2.4 135)
			(size 0.254 0.8128)
			(layers "F.Cu" "F.Paste" "F.Mask")
			(roundrect_rratio 0.25)
			(net 51 "/CSI Connector/CSI.D1_P")
			(pinfunction "D1P")
			(pintype "input")
		)
		(pad "30" smd roundrect
			(at -0.75 -2.4 135)
			(size 0.254 0.8128)
			(layers "F.Cu" "F.Paste" "F.Mask")
			(roundrect_rratio 0.25)
			(net 50 "/CSI Connector/CSI.D1_N")
			(pinfunction "D1N")
			(pintype "input")
		)
		(pad "31" smd roundrect
			(at -1.25 -2.4 135)
			(size 0.254 0.8128)
			(layers "F.Cu" "F.Paste" "F.Mask")
			(roundrect_rratio 0.25)
			(net 78 "Net-(U6-MFP7)")
			(pinfunction "MFP7")
			(pintype "bidirectional")
		)
		(pad "32" smd roundrect
			(at -1.75 -2.4 135)
			(size 0.254 0.8128)
			(layers "F.Cu" "F.Paste" "F.Mask")
			(roundrect_rratio 0.25)
			(net 79 "Net-(U6-MFP8)")
			(pinfunction "MFP8")
			(pintype "bidirectional")
		)
		(pad "33" smd rect
			(at 0 0 135)
			(size 3.15 3.15)
			(layers "F.Cu" "F.Paste" "F.Mask")
			(net 1 "GND")
			(pinfunction "GND")
			(pintype "power_in")
		)
	)
	(footprint "antmicro-footprints:TP_SMD_1.5mm"
		(layer "F.Cu")
		(at 163.55 111.35)
		(property "Reference" "TP9"
			(at 0 -0.9 0)
			(layer "F.SilkS")
			(hide yes)
			(effects
				(font
					(size 0.7 0.7)
					(thickness 0.15)
				)
				(justify left bottom)
			)
		)
		(property "Value" "TP_1.5mm_SMD"
			(at 0 1.7 0)
			(layer "F.Fab")
			(effects
				(font
					(size 0.7 0.7)
					(thickness 0.15)
				)
				(justify left bottom)
			)
		)
		(property "Footprint" "antmicro-footprints:TP_SMD_1.5mm"
			(at 0 0 0)
			(layer "F.Fab")
			(hide yes)
			(effects
				(font
					(size 1.27 1.27)
					(thickness 0.15)
				)
			)
		)
		(property "Author" "Antmicro"
			(at 0 0 0)
			(layer "F.Fab")
			(hide yes)
			(effects
				(font
					(size 1 1)
					(thickness 0.15)
				)
			)
		)
		(property "License" "Apache-2.0"
			(at 0 0 0)
			(layer "F.Fab")
			(hide yes)
			(effects
				(font
					(size 1 1)
					(thickness 0.15)
				)
			)
		)
		(property "MPN" ""
			(at 0 0 0)
			(layer "F.Fab")
			(hide yes)
			(effects
				(font
					(size 1 1)
					(thickness 0.15)
				)
			)
		)
		(property "Manufacturer" ""
			(at 0 0 0)
			(layer "F.Fab")
			(hide yes)
			(effects
				(font
					(size 1 1)
					(thickness 0.15)
				)
			)
		)
		(sheetname "Supply")
		(sheetfile "supply.kicad_sch")
		(attr exclude_from_pos_files exclude_from_bom)
		(fp_circle
			(center 0 0)
			(end 0.85 0)
			(stroke
				(width 0.05)
				(type default)
			)
			(fill none)
			(layer "F.CrtYd")
		)
		(fp_text user "Author: Antmicro"
			(at -0.7 4.101 0)
			(layer "F.Fab")
			(hide yes)
			(effects
				(font
					(size 0.7 0.7)
					(thickness 0.15)
				)
				(justify left bottom)
			)
		)
		(fp_text user "${REFERENCE}"
			(at -0.7 2.9 0)
			(layer "F.Fab")
			(hide yes)
			(effects
				(font
					(size 0.7 0.7)
					(thickness 0.15)
				)
				(justify left bottom)
			)
		)
		(fp_text user "License: Apache-2.0"
			(at -0.7 5.301 0)
			(layer "F.Fab")
			(hide yes)
			(effects
				(font
					(size 0.7 0.7)
					(thickness 0.15)
				)
				(justify left bottom)
			)
		)
		(pad "1" smd circle
			(at 0 0 270)
			(size 1.5 1.5)
			(layers "F.Cu" "F.Mask")
			(net 1 "GND")
			(pinfunction "1")
			(pintype "passive")
		)
	)
	(footprint "antmicro-footprints:TP_SMD_1.5mm"
		(layer "F.Cu")
		(at 158.75 118)
		(property "Reference" "TP7"
			(at -0.4 -1.139684 0)
			(layer "F.SilkS")
			(hide yes)
			(effects
				(font
					(size 0.7 0.7)
					(thickness 0.15)
				)
				(justify left bottom)
			)
		)
		(property "Value" "TP_1.5mm_SMD"
			(at 0 1.7 0)
			(layer "F.Fab")
			(effects
				(font
					(size 0.7 0.7)
					(thickness 0.15)
				)
				(justify left bottom)
			)
		)
		(property "Footprint" "antmicro-footprints:TP_SMD_1.5mm"
			(at 0 0 0)
			(layer "F.Fab")
			(hide yes)
			(effects
				(font
					(size 1.27 1.27)
					(thickness 0.15)
				)
			)
		)
		(property "Author" "Antmicro"
			(at 0 0 0)
			(layer "F.Fab")
			(hide yes)
			(effects
				(font
					(size 1 1)
					(thickness 0.15)
				)
			)
		)
		(property "License" "Apache-2.0"
			(at 0 0 0)
			(layer "F.Fab")
			(hide yes)
			(effects
				(font
					(size 1 1)
					(thickness 0.15)
				)
			)
		)
		(property "MPN" ""
			(at 0 0 0)
			(layer "F.Fab")
			(hide yes)
			(effects
				(font
					(size 1 1)
					(thickness 0.15)
				)
			)
		)
		(property "Manufacturer" ""
			(at 0 0 0)
			(layer "F.Fab")
			(hide yes)
			(effects
				(font
					(size 1 1)
					(thickness 0.15)
				)
			)
		)
		(sheetname "Serializer")
		(sheetfile "serializer.kicad_sch")
		(attr exclude_from_pos_files exclude_from_bom)
		(fp_circle
			(center 0 0)
			(end 0.85 0)
			(stroke
				(width 0.05)
				(type default)
			)
			(fill none)
			(layer "F.CrtYd")
		)
		(fp_text user "Author: Antmicro"
			(at -0.7 4.101 0)
			(layer "F.Fab")
			(hide yes)
			(effects
				(font
					(size 0.7 0.7)
					(thickness 0.15)
				)
				(justify left bottom)
			)
		)
		(fp_text user "License: Apache-2.0"
			(at -0.7 5.301 0)
			(layer "F.Fab")
			(hide yes)
			(effects
				(font
					(size 0.7 0.7)
					(thickness 0.15)
				)
				(justify left bottom)
			)
		)
		(fp_text user "${REFERENCE}"
			(at -0.7 2.9 0)
			(layer "F.Fab")
			(hide yes)
			(effects
				(font
					(size 0.7 0.7)
					(thickness 0.15)
				)
				(justify left bottom)
			)
		)
		(pad "1" smd circle
			(at 0 0 270)
			(size 1.5 1.5)
			(layers "F.Cu" "F.Mask")
			(net 84 "Net-(U6-MFP5)")
			(pinfunction "1")
			(pintype "passive")
		)
	)
	(footprint "antmicro-footprints:LED_0603_1608Metric_G"
		(layer "F.Cu")
		(at 142.25 115.75 -90)
		(descr "LED SMD 0603 Green")
		(tags "LED SMD 0603 Green")
		(property "Reference" "D5"
			(at -2.725 -0.425 90)
			(layer "F.SilkS")
			(effects
				(font
					(size 0.7 0.7)
					(thickness 0.15)
				)
				(justify right bottom)
			)
		)
		(property "Value" "LED_G_0603_LTST-C190GKT"
			(at -0.001 1.599 90)
			(layer "F.Fab")
			(effects
				(font
					(size 0.7 0.7)
					(thickness 0.15)
				)
				(justify right bottom)
			)
		)
		(property "Footprint" "antmicro-footprints:LED_0603_1608Metric_G"
			(at 0 0 -90)
			(layer "F.Fab")
			(hide yes)
			(effects
				(font
					(size 1.27 1.27)
					(thickness 0.15)
				)
			)
		)
		(property "Datasheet" "https://media.digikey.com/pdf/Data%20Sheets/Lite-On%20PDFs/LTST-C190GKT.pdf"
			(at 0 0 -90)
			(layer "F.Fab")
			(hide yes)
			(effects
				(font
					(size 1.27 1.27)
					(thickness 0.15)
				)
			)
		)
		(property "Author" "Antmicro"
			(at 26.5 258 0)
			(layer "F.Fab")
			(hide yes)
			(effects
				(font
					(size 1 1)
					(thickness 0.15)
				)
			)
		)
		(property "Color" "Green"
			(at 26.5 258 0)
			(layer "F.Fab")
			(hide yes)
			(effects
				(font
					(size 1 1)
					(thickness 0.15)
				)
			)
		)
		(property "License" "Apache-2.0"
			(at 26.5 258 0)
			(layer "F.Fab")
			(hide yes)
			(effects
				(font
					(size 1 1)
					(thickness 0.15)
				)
			)
		)
		(property "MPN" "LTST-C190GKT"
			(at 26.5 258 0)
			(layer "F.Fab")
			(hide yes)
			(effects
				(font
					(size 1 1)
					(thickness 0.15)
				)
			)
		)
		(property "Manufacturer" "Lite-On"
			(at 26.5 258 0)
			(layer "F.Fab")
			(hide yes)
			(effects
				(font
					(size 1 1)
					(thickness 0.15)
				)
			)
		)
		(property "VSD_class" "LED"
			(at 26.5 258 0)
			(layer "F.Fab")
			(hide yes)
			(effects
				(font
					(size 1 1)
					(thickness 0.15)
				)
			)
		)
		(sheetname "Supply")
		(sheetfile "supply.kicad_sch")
		(attr smd)
		(fp_line
			(start 0.22 0.35)
			(end -0.22 0.35)
			(stroke
				(width 0.15)
				(type solid)
			)
			(layer "F.SilkS")
		)
		(fp_line
			(start -0.094672 0.201008)
			(end -0.094672 -0.198992)
			(stroke
				(width 0.1)
				(type solid)
			)
			(layer "F.SilkS")
		)
		(fp_line
			(start 0.105328 0.201008)
			(end -0.094672 0.001008)
			(stroke
				(width 0.1)
				(type solid)
			)
			(layer "F.SilkS")
		)
		(fp_line
			(start 0.105328 0.201008)
			(end 0.105328 -0.198992)
			(stroke
				(width 0.1)
				(type solid)
			)
			(layer "F.SilkS")
		)
		(fp_line
			(start -0.094672 0.001008)
			(end -0.24 0.001008)
			(stroke
				(width 0.1)
				(type solid)
			)
			(layer "F.SilkS")
		)
		(fp_line
			(start -0.094672 0.001008)
			(end 0.105328 -0.198992)
			(stroke
				(width 0.1)
				(type solid)
			)
			(layer "F.SilkS")
		)
		(fp_line
			(start 0.105328 0.001008)
			(end 0.24 0.001)
			(stroke
				(width 0.1)
				(type solid)
			)
			(layer "F.SilkS")
		)
		(fp_line
			(start -1.18 -0.319)
			(end -1.18 0.321)
			(stroke
				(width 0.15)
				(type solid)
			)
			(layer "F.SilkS")
		)
		(fp_line
			(start 0.22 -0.35)
			(end -0.22 -0.35)
			(stroke
				(width 0.15)
				(type solid)
			)
			(layer "F.SilkS")
		)
		(fp_rect
			(start 1.25 0.65)
			(end -1.25 -0.65)
			(stroke
				(width 0.05)
				(type solid)
			)
			(fill none)
			(layer "F.CrtYd")
		)
		(fp_line
			(start -0.199 0.2)
			(end -0.199 0.1)
			(stroke
				(width 0.15)
				(type solid)
			)
			(layer "F.Fab")
		)
		(fp_line
			(start 0.201 0.2)
			(end 0.201 0)
			(stroke
				(width 0.15)
				(type solid)
			)
			(layer "F.Fab")
		)
		(fp_line
			(start -0.199 0)
			(end -0.597 0)
			(stroke
				(width 0.15)
				(type solid)
			)
			(layer "F.Fab")
		)
		(fp_line
			(start -0.101 0)
			(end 0.201 0.2)
			(stroke
				(width 0.15)
				(type solid)
			)
			(layer "F.Fab")
		)
		(fp_line
			(start 0.201 0)
			(end 0.201 -0.202)
			(stroke
				(width 0.15)
				(type solid)
			)
			(layer "F.Fab")
		)
		(fp_line
			(start 0.599 0)
			(end 0.201 0)
			(stroke
				(width 0.15)
				(type solid)
			)
			(layer "F.Fab")
		)
		(fp_line
			(start -0.199 -0.202)
			(end -0.199 0.1)
			(stroke
				(width 0.15)
				(type solid)
			)
			(layer "F.Fab")
		)
		(fp_line
			(start 0.201 -0.202)
			(end -0.101 0)
			(stroke
				(width 0.15)
				(type solid)
			)
			(layer "F.Fab")
		)
		(fp_rect
			(start 0.848 0.4)
			(end -0.85 -0.402)
			(stroke
				(width 0.15)
				(type solid)
			)
			(fill none)
			(layer "F.Fab")
		)
		(fp_text user "License: Apache-2.0"
			(at -1.4224 3.599 90)
			(layer "F.Fab")
			(hide yes)
			(effects
				(font
					(size 0.7 0.7)
					(thickness 0.15)
				)
				(justify right bottom)
			)
		)
		(fp_text user "${REFERENCE}"
			(at -1.4224 5.999 90)
			(layer "F.Fab")
			(hide yes)
			(effects
				(font
					(size 0.7 0.7)
					(thickness 0.15)
				)
				(justify right bottom)
			)
		)
		(fp_text user "Author: Antmicro"
			(at -1.4224 4.799 90)
			(layer "F.Fab")
			(hide yes)
			(effects
				(font
					(size 0.7 0.7)
					(thickness 0.15)
				)
				(justify right bottom)
			)
		)
		(pad "1" smd roundrect
			(at -0.7 0 90)
			(size 0.8 1)
			(layers "F.Cu" "F.Paste" "F.Mask")
			(roundrect_rratio 0.2)
			(net 69 "Net-(D5-C)")
			(pinfunction "C")
			(pintype "passive")
		)
		(pad "2" smd roundrect
			(at 0.7 0 90)
			(size 0.8 1)
			(layers "F.Cu" "F.Paste" "F.Mask")
			(roundrect_rratio 0.2)
			(net 9 "+5V")
			(pinfunction "A")
			(pintype "passive")
		)
	)
	(footprint "antmicro-footprints:R_0402_1005Metric"
		(layer "F.Cu")
		(at 140.83 79.980142)
		(descr "Resistor SMD 0402")
		(tags "resistor SMD 0402")
		(property "Reference" "R44"
			(at -1.08 -0.480142 0)
			(layer "F.SilkS")
			(effects
				(font
					(size 0.7 0.7)
					(thickness 0.15)
				)
				(justify left bottom)
			)
		)
		(property "Value" "R_10k_0402"
			(at -1.011843 1.772047 0)
			(layer "F.Fab")
			(effects
				(font
					(size 0.7 0.7)
					(thickness 0.15)
				)
				(justify left bottom)
			)
		)
		(property "Footprint" "antmicro-footprints:R_0402_1005Metric"
			(at 0 0 0)
			(layer "F.Fab")
			(hide yes)
			(effects
				(font
					(size 1.27 1.27)
					(thickness 0.15)
				)
			)
		)
		(property "Datasheet" "https://www.bourns.com/docs/product-datasheets/cr.pdf"
			(at 0 0 0)
			(layer "F.Fab")
			(hide yes)
			(effects
				(font
					(size 1.27 1.27)
					(thickness 0.15)
				)
			)
		)
		(property "MPN" "CR0402-FX-1002GLF"
			(at 0 0 0)
			(unlocked yes)
			(layer "F.Fab")
			(hide yes)
			(effects
				(font
					(size 1 1)
					(thickness 0.15)
				)
			)
		)
		(property "Manufacturer" "Bourns"
			(at 0 0 0)
			(unlocked yes)
			(layer "F.Fab")
			(hide yes)
			(effects
				(font
					(size 1 1)
					(thickness 0.15)
				)
			)
		)
		(property "License" "Apache-2.0"
			(at 0 0 0)
			(unlocked yes)
			(layer "F.Fab")
			(hide yes)
			(effects
				(font
					(size 1 1)
					(thickness 0.15)
				)
			)
		)
		(property "Author" "Antmicro"
			(at 0 0 0)
			(unlocked yes)
			(layer "F.Fab")
			(hide yes)
			(effects
				(font
					(size 1 1)
					(thickness 0.15)
				)
			)
		)
		(property "Val" "10k"
			(at 0 0 0)
			(unlocked yes)
			(layer "F.Fab")
			(hide yes)
			(effects
				(font
					(size 1 1)
					(thickness 0.15)
				)
			)
		)
		(property "Tolerance" "1%"
			(at 0 0 0)
			(unlocked yes)
			(layer "F.Fab")
			(hide yes)
			(effects
				(font
					(size 1 1)
					(thickness 0.15)
				)
			)
		)
		(sheetname "Supply")
		(sheetfile "supply.kicad_sch")
		(attr smd)
		(fp_rect
			(start -0.925 -0.47)
			(end 0.925 0.47)
			(stroke
				(width 0.05)
				(type default)
			)
			(fill none)
			(layer "F.CrtYd")
		)
		(fp_rect
			(start -0.5 -0.25)
			(end 0.5 0.25)
			(stroke
				(width 0.15)
				(type solid)
			)
			(fill none)
			(layer "F.Fab")
		)
		(fp_text user "${REFERENCE}"
			(at -0.95 3.168 0)
			(layer "F.Fab")
			(hide yes)
			(effects
				(font
					(size 0.7 0.7)
					(thickness 0.15)
				)
				(justify left bottom)
			)
		)
		(fp_text user "License: Apache-2.0"
			(at -0.95 5.169 0)
			(layer "F.Fab")
			(hide yes)
			(effects
				(font
					(size 0.7 0.7)
					(thickness 0.15)
				)
				(justify left bottom)
			)
		)
		(fp_text user "Author: Antmicro"
			(at -0.95 4.169 0)
			(layer "F.Fab")
			(hide yes)
			(effects
				(font
					(size 0.7 0.7)
					(thickness 0.15)
				)
				(justify left bottom)
			)
		)
		(pad "1" smd roundrect
			(at -0.48 0)
			(size 0.59 0.64)
			(layers "F.Cu" "F.Paste" "F.Mask")
			(roundrect_rratio 0.25)
			(net 1 "GND")
			(pintype "passive")
		)
		(pad "2" smd roundrect
			(at 0.48 0)
			(size 0.59 0.64)
			(layers "F.Cu" "F.Paste" "F.Mask")
			(roundrect_rratio 0.25)
			(net 96 "/Supply/FB_3V3")
			(pintype "passive")
		)
	)
	(footprint "antmicro-footprints:R_0402_1005Metric"
		(layer "F.Cu")
		(at 135.4 108.75)
		(descr "Resistor SMD 0402")
		(tags "resistor SMD 0402")
		(property "Reference" "R33"
			(at 0.9 0.4125 0)
			(layer "F.SilkS")
			(effects
				(font
					(size 0.7 0.7)
					(thickness 0.15)
				)
				(justify left bottom)
			)
		)
		(property "Value" "R_0R_0402"
			(at -1.011843 1.772047 0)
			(layer "F.Fab")
			(effects
				(font
					(size 0.7 0.7)
					(thickness 0.15)
				)
				(justify left bottom)
			)
		)
		(property "Footprint" "antmicro-footprints:R_0402_1005Metric"
			(at 0 0 0)
			(layer "F.Fab")
			(hide yes)
			(effects
				(font
					(size 1.27 1.27)
					(thickness 0.15)
				)
			)
		)
		(property "Datasheet" "https://industrial.panasonic.com/cdbs/www-data/pdf/RDA0000/AOA0000C301.pdf"
			(at 0 0 0)
			(layer "F.Fab")
			(hide yes)
			(effects
				(font
					(size 1.27 1.27)
					(thickness 0.15)
				)
			)
		)
		(property "Author" "Antmicro"
			(at 0 0 0)
			(layer "F.Fab")
			(hide yes)
			(effects
				(font
					(size 1 1)
					(thickness 0.15)
				)
			)
		)
		(property "Current" "1A"
			(at 0 0 0)
			(layer "F.Fab")
			(hide yes)
			(effects
				(font
					(size 1 1)
					(thickness 0.15)
				)
			)
		)
		(property "License" "Apache-2.0"
			(at 0 0 0)
			(layer "F.Fab")
			(hide yes)
			(effects
				(font
					(size 1 1)
					(thickness 0.15)
				)
			)
		)
		(property "MPN" "ERJ2GE0R00X"
			(at 0 0 0)
			(layer "F.Fab")
			(hide yes)
			(effects
				(font
					(size 1 1)
					(thickness 0.15)
				)
			)
		)
		(property "Manufacturer" "Panasonic"
			(at 0 0 0)
			(layer "F.Fab")
			(hide yes)
			(effects
				(font
					(size 1 1)
					(thickness 0.15)
				)
			)
		)
		(property "Tolerance" ""
			(at 0 0 0)
			(layer "F.Fab")
			(hide yes)
			(effects
				(font
					(size 1 1)
					(thickness 0.15)
				)
			)
		)
		(property "Val" "0R"
			(at 0 0 0)
			(layer "F.Fab")
			(hide yes)
			(effects
				(font
					(size 1 1)
					(thickness 0.15)
				)
			)
		)
		(sheetname "Serializer")
		(sheetfile "serializer.kicad_sch")
		(attr smd)
		(fp_rect
			(start -0.925 -0.47)
			(end 0.925 0.47)
			(stroke
				(width 0.05)
				(type default)
			)
			(fill none)
			(layer "F.CrtYd")
		)
		(fp_rect
			(start -0.5 -0.25)
			(end 0.5 0.25)
			(stroke
				(width 0.15)
				(type solid)
			)
			(fill none)
			(layer "F.Fab")
		)
		(fp_text user "Author: Antmicro"
			(at -0.95 4.169 0)
			(layer "F.Fab")
			(hide yes)
			(effects
				(font
					(size 0.7 0.7)
					(thickness 0.15)
				)
				(justify left bottom)
			)
		)
		(fp_text user "${REFERENCE}"
			(at -0.95 3.168 0)
			(layer "F.Fab")
			(hide yes)
			(effects
				(font
					(size 0.7 0.7)
					(thickness 0.15)
				)
				(justify left bottom)
			)
		)
		(fp_text user "License: Apache-2.0"
			(at -0.95 5.169 0)
			(layer "F.Fab")
			(hide yes)
			(effects
				(font
					(size 0.7 0.7)
					(thickness 0.15)
				)
				(justify left bottom)
			)
		)
		(pad "1" smd roundrect
			(at -0.48 0)
			(size 0.59 0.64)
			(layers "F.Cu" "F.Paste" "F.Mask")
			(roundrect_rratio 0.25)
			(net 89 "/CSI Connector/I2C.SCL")
			(pintype "passive")
		)
		(pad "2" smd roundrect
			(at 0.48 0)
			(size 0.59 0.64)
			(layers "F.Cu" "F.Paste" "F.Mask")
			(roundrect_rratio 0.25)
			(net 82 "Net-(U6-MFP10)")
			(pintype "passive")
		)
	)
	(footprint "antmicro-footprints:R_0402_1005Metric"
		(layer "F.Cu")
		(at 144.74 79.700142 -90)
		(descr "Resistor SMD 0402")
		(tags "resistor SMD 0402")
		(property "Reference" "R41"
			(at -1.050142 -0.51 90)
			(layer "F.SilkS")
			(effects
				(font
					(size 0.7 0.7)
					(thickness 0.15)
				)
				(justify right top)
			)
		)
		(property "Value" "R_10k_0402"
			(at -1.011843 1.772047 90)
			(layer "F.Fab")
			(effects
				(font
					(size 0.7 0.7)
					(thickness 0.15)
				)
				(justify right top)
			)
		)
		(property "Footprint" "antmicro-footprints:R_0402_1005Metric"
			(at 0 0 90)
			(layer "F.Fab")
			(hide yes)
			(effects
				(font
					(size 1.27 1.27)
					(thickness 0.15)
				)
			)
		)
		(property "Datasheet" "https://www.bourns.com/docs/product-datasheets/cr.pdf"
			(at 0 0 90)
			(layer "F.Fab")
			(hide yes)
			(effects
				(font
					(size 1.27 1.27)
					(thickness 0.15)
				)
			)
		)
		(property "MPN" "CR0402-FX-1002GLF"
			(at 0 0 -90)
			(unlocked yes)
			(layer "F.Fab")
			(hide yes)
			(effects
				(font
					(size 1 1)
					(thickness 0.15)
				)
			)
		)
		(property "Manufacturer" "Bourns"
			(at 0 0 -90)
			(unlocked yes)
			(layer "F.Fab")
			(hide yes)
			(effects
				(font
					(size 1 1)
					(thickness 0.15)
				)
			)
		)
		(property "License" "Apache-2.0"
			(at 0 0 -90)
			(unlocked yes)
			(layer "F.Fab")
			(hide yes)
			(effects
				(font
					(size 1 1)
					(thickness 0.15)
				)
			)
		)
		(property "Author" "Antmicro"
			(at 0 0 -90)
			(unlocked yes)
			(layer "F.Fab")
			(hide yes)
			(effects
				(font
					(size 1 1)
					(thickness 0.15)
				)
			)
		)
		(property "Val" "10k"
			(at 0 0 -90)
			(unlocked yes)
			(layer "F.Fab")
			(hide yes)
			(effects
				(font
					(size 1 1)
					(thickness 0.15)
				)
			)
		)
		(property "Tolerance" "1%"
			(at 0 0 -90)
			(unlocked yes)
			(layer "F.Fab")
			(hide yes)
			(effects
				(font
					(size 1 1)
					(thickness 0.15)
				)
			)
		)
		(sheetname "Supply")
		(sheetfile "supply.kicad_sch")
		(attr smd)
		(fp_rect
			(start -0.925 -0.47)
			(end 0.925 0.47)
			(stroke
				(width 0.05)
				(type default)
			)
			(fill none)
			(layer "F.CrtYd")
		)
		(fp_rect
			(start -0.5 -0.25)
			(end 0.5 0.25)
			(stroke
				(width 0.15)
				(type solid)
			)
			(fill none)
			(layer "F.Fab")
		)
		(fp_text user "License: Apache-2.0"
			(at -0.95 5.169 90)
			(layer "F.Fab")
			(hide yes)
			(effects
				(font
					(size 0.7 0.7)
					(thickness 0.15)
				)
				(justify right top)
			)
		)
		(fp_text user "Author: Antmicro"
			(at -0.95 4.169 90)
			(layer "F.Fab")
			(hide yes)
			(effects
				(font
					(size 0.7 0.7)
					(thickness 0.15)
				)
				(justify right top)
			)
		)
		(fp_text user "${REFERENCE}"
			(at -0.95 3.168 90)
			(layer "F.Fab")
			(hide yes)
			(effects
				(font
					(size 0.7 0.7)
					(thickness 0.15)
				)
				(justify right top)
			)
		)
		(pad "1" smd roundrect
			(at -0.48 0 270)
			(size 0.59 0.64)
			(layers "F.Cu" "F.Paste" "F.Mask")
			(roundrect_rratio 0.25)
			(net 97 "/Supply/EN_3V3")
			(pintype "passive")
		)
		(pad "2" smd roundrect
			(at 0.48 0 270)
			(size 0.59 0.64)
			(layers "F.Cu" "F.Paste" "F.Mask")
			(roundrect_rratio 0.25)
			(net 2 "+12V")
			(pintype "passive")
		)
	)
	(footprint "antmicro-footprints:C_0402_1005Metric"
		(layer "F.Cu")
		(at 160.208 106.394 -90)
		(descr "Capacitor SMD 0402")
		(tags "capacitor SMD 0402")
		(property "Reference" "C14"
			(at 0.956 -0.392 90)
			(layer "F.SilkS")
			(effects
				(font
					(size 0.7 0.7)
					(thickness 0.15)
				)
				(justify right bottom)
			)
		)
		(property "Value" "C_1u_16V_0402"
			(at -1.022927 2.155213 90)
			(layer "F.Fab")
			(effects
				(font
					(size 0.7 0.7)
					(thickness 0.15)
				)
				(justify right bottom)
			)
		)
		(property "Footprint" "antmicro-footprints:C_0402_1005Metric"
			(at 0 0 -90)
			(layer "F.Fab")
			(hide yes)
			(effects
				(font
					(size 1.27 1.27)
					(thickness 0.15)
				)
			)
		)
		(property "Datasheet" "https://www.kemet.com/en/us/capacitors/product/C0402C105M4PACTU.html"
			(at 0 0 -90)
			(layer "F.Fab")
			(hide yes)
			(effects
				(font
					(size 1.27 1.27)
					(thickness 0.15)
				)
			)
		)
		(property "Author" "Antmicro"
			(at 53.814 266.602 0)
			(layer "F.Fab")
			(hide yes)
			(effects
				(font
					(size 1 1)
					(thickness 0.15)
				)
			)
		)
		(property "Dielectric" ""
			(at 53.814 266.602 0)
			(layer "F.Fab")
			(hide yes)
			(effects
				(font
					(size 1 1)
					(thickness 0.15)
				)
			)
		)
		(property "License" "Apache-2.0"
			(at 53.814 266.602 0)
			(layer "F.Fab")
			(hide yes)
			(effects
				(font
					(size 1 1)
					(thickness 0.15)
				)
			)
		)
		(property "MPN" "C0402C105M4PACTU"
			(at 53.814 266.602 0)
			(layer "F.Fab")
			(hide yes)
			(effects
				(font
					(size 1 1)
					(thickness 0.15)
				)
			)
		)
		(property "Manufacturer" "KEMET"
			(at 53.814 266.602 0)
			(layer "F.Fab")
			(hide yes)
			(effects
				(font
					(size 1 1)
					(thickness 0.15)
				)
			)
		)
		(property "Val" "1u"
			(at 53.814 266.602 0)
			(layer "F.Fab")
			(hide yes)
			(effects
				(font
					(size 1 1)
					(thickness 0.15)
				)
			)
		)
		(property "Voltage" "16V"
			(at 53.814 266.602 0)
			(layer "F.Fab")
			(hide yes)
			(effects
				(font
					(size 1 1)
					(thickness 0.15)
				)
			)
		)
		(sheetname "Supply")
		(sheetfile "supply.kicad_sch")
		(attr smd)
		(fp_rect
			(start -0.925 -0.47)
			(end 0.925 0.47)
			(stroke
				(width 0.05)
				(type default)
			)
			(fill none)
			(layer "F.CrtYd")
		)
		(fp_line
			(start -0.494 0.248)
			(end -0.494 -0.25)
			(stroke
				(width 0.15)
				(type solid)
			)
			(layer "F.Fab")
		)
		(fp_line
			(start 0.504 0.248)
			(end -0.494 0.248)
			(stroke
				(width 0.15)
				(type solid)
			)
			(layer "F.Fab")
		)
		(fp_line
			(start -0.494 -0.25)
			(end 0.504 -0.25)
			(stroke
				(width 0.15)
				(type solid)
			)
			(layer "F.Fab")
		)
		(fp_line
			(start 0.504 -0.25)
			(end 0.504 0.248)
			(stroke
				(width 0.15)
				(type solid)
			)
			(layer "F.Fab")
		)
		(fp_text user "${REFERENCE}"
			(at -0.939 4.599 90)
			(layer "F.Fab")
			(hide yes)
			(effects
				(font
					(size 0.7 0.7)
					(thickness 0.15)
				)
				(justify right bottom)
			)
		)
		(fp_text user "Author: Antmicro"
			(at -0.939 3.399 90)
			(layer "F.Fab")
			(hide yes)
			(effects
				(font
					(size 0.7 0.7)
					(thickness 0.15)
				)
				(justify right bottom)
			)
		)
		(fp_text user "License: Apache-2.0"
			(at -0.939 5.799 90)
			(layer "F.Fab")
			(hide yes)
			(effects
				(font
					(size 0.7 0.7)
					(thickness 0.15)
				)
				(justify right bottom)
			)
		)
		(pad "1" smd roundrect
			(at -0.48 0 270)
			(size 0.59 0.64)
			(layers "F.Cu" "F.Paste" "F.Mask")
			(roundrect_rratio 0.25)
			(net 1 "GND")
			(pintype "passive")
		)
		(pad "2" smd roundrect
			(at 0.48 0 270)
			(size 0.59 0.64)
			(layers "F.Cu" "F.Paste" "F.Mask")
			(roundrect_rratio 0.25)
			(net 11 "+1V8")
			(pintype "passive")
		)
	)
	(footprint "antmicro-footprints:C_0402_1005Metric"
		(layer "F.Cu")
		(at 165.55 86.473 -90)
		(descr "Capacitor SMD 0402")
		(tags "capacitor SMD 0402")
		(property "Reference" "C10"
			(at -3.035 -0.495 90)
			(layer "F.SilkS")
			(effects
				(font
					(size 0.7 0.7)
					(thickness 0.15)
				)
				(justify right bottom)
			)
		)
		(property "Value" "C_100n_0402"
			(at -1.022927 2.155213 90)
			(layer "F.Fab")
			(effects
				(font
					(size 0.7 0.7)
					(thickness 0.15)
				)
				(justify right bottom)
			)
		)
		(property "Footprint" "antmicro-footprints:C_0402_1005Metric"
			(at 0 0 -90)
			(layer "F.Fab")
			(hide yes)
			(effects
				(font
					(size 1.27 1.27)
					(thickness 0.15)
				)
			)
		)
		(property "Datasheet" "https://www.murata.com/products/productdetail?partno=GRM155R61H104KE14%23"
			(at 0 0 -90)
			(layer "F.Fab")
			(hide yes)
			(effects
				(font
					(size 1.27 1.27)
					(thickness 0.15)
				)
			)
		)
		(property "Author" "Antmicro"
			(at 79.077 252.023 0)
			(layer "F.Fab")
			(hide yes)
			(effects
				(font
					(size 1 1)
					(thickness 0.15)
				)
			)
		)
		(property "Dielectric" "X5R"
			(at 79.077 252.023 0)
			(layer "F.Fab")
			(hide yes)
			(effects
				(font
					(size 1 1)
					(thickness 0.15)
				)
			)
		)
		(property "License" "Apache-2.0"
			(at 79.077 252.023 0)
			(layer "F.Fab")
			(hide yes)
			(effects
				(font
					(size 1 1)
					(thickness 0.15)
				)
			)
		)
		(property "MPN" "GRM155R61H104KE14D"
			(at 79.077 252.023 0)
			(layer "F.Fab")
			(hide yes)
			(effects
				(font
					(size 1 1)
					(thickness 0.15)
				)
			)
		)
		(property "Manufacturer" "Murata"
			(at 79.077 252.023 0)
			(layer "F.Fab")
			(hide yes)
			(effects
				(font
					(size 1 1)
					(thickness 0.15)
				)
			)
		)
		(property "Val" "100n"
			(at 79.077 252.023 0)
			(layer "F.Fab")
			(hide yes)
			(effects
				(font
					(size 1 1)
					(thickness 0.15)
				)
			)
		)
		(property "Voltage" "50V"
			(at 79.077 252.023 0)
			(layer "F.Fab")
			(hide yes)
			(effects
				(font
					(size 1 1)
					(thickness 0.15)
				)
			)
		)
		(sheetname "GMSL Connector")
		(sheetfile "GMSL.kicad_sch")
		(attr smd)
		(fp_rect
			(start -0.925 -0.47)
			(end 0.925 0.47)
			(stroke
				(width 0.05)
				(type default)
			)
			(fill none)
			(layer "F.CrtYd")
		)
		(fp_line
			(start -0.494 0.248)
			(end -0.494 -0.25)
			(stroke
				(width 0.15)
				(type solid)
			)
			(layer "F.Fab")
		)
		(fp_line
			(start 0.504 0.248)
			(end -0.494 0.248)
			(stroke
				(width 0.15)
				(type solid)
			)
			(layer "F.Fab")
		)
		(fp_line
			(start -0.494 -0.25)
			(end 0.504 -0.25)
			(stroke
				(width 0.15)
				(type solid)
			)
			(layer "F.Fab")
		)
		(fp_line
			(start 0.504 -0.25)
			(end 0.504 0.248)
			(stroke
				(width 0.15)
				(type solid)
			)
			(layer "F.Fab")
		)
		(fp_text user "Author: Antmicro"
			(at -0.939 3.399 90)
			(layer "F.Fab")
			(hide yes)
			(effects
				(font
					(size 0.7 0.7)
					(thickness 0.15)
				)
				(justify right bottom)
			)
		)
		(fp_text user "${REFERENCE}"
			(at -0.939 4.599 90)
			(layer "F.Fab")
			(hide yes)
			(effects
				(font
					(size 0.7 0.7)
					(thickness 0.15)
				)
				(justify right bottom)
			)
		)
		(fp_text user "License: Apache-2.0"
			(at -0.939 5.799 90)
			(layer "F.Fab")
			(hide yes)
			(effects
				(font
					(size 0.7 0.7)
					(thickness 0.15)
				)
				(justify right bottom)
			)
		)
		(pad "1" smd roundrect
			(at -0.48 0 270)
			(size 0.59 0.64)
			(layers "F.Cu" "F.Paste" "F.Mask")
			(roundrect_rratio 0.25)
			(net 1 "GND")
			(pintype "passive")
		)
		(pad "2" smd roundrect
			(at 0.48 0 270)
			(size 0.59 0.64)
			(layers "F.Cu" "F.Paste" "F.Mask")
			(roundrect_rratio 0.25)
			(net 2 "+12V")
			(pintype "passive")
		)
	)
	(footprint "antmicro-footprints:C_0402_1005Metric"
		(layer "F.Cu")
		(at 136.58 85.647 -90)
		(descr "Capacitor SMD 0402")
		(tags "capacitor SMD 0402")
		(property "Reference" "C7"
			(at 0.823 -1.78 90)
			(layer "F.SilkS")
			(effects
				(font
					(size 0.7 0.7)
					(thickness 0.15)
				)
				(justify right bottom)
			)
		)
		(property "Value" "C_22u_0402"
			(at -1.022927 2.155213 90)
			(layer "F.Fab")
			(effects
				(font
					(size 0.7 0.7)
					(thickness 0.15)
				)
				(justify right bottom)
			)
		)
		(property "Footprint" "antmicro-footprints:C_0402_1005Metric"
			(at 0 0 -90)
			(layer "F.Fab")
			(hide yes)
			(effects
				(font
					(size 1.27 1.27)
					(thickness 0.15)
				)
			)
		)
		(property "Datasheet" "https://www.murata.com/products/productdetail?partno=GRM158R60J226ME01%23"
			(at 0 0 -90)
			(layer "F.Fab")
			(hide yes)
			(effects
				(font
					(size 1.27 1.27)
					(thickness 0.15)
				)
			)
		)
		(property "Author" "Antmicro"
			(at 52.853 223.847 0)
			(layer "F.Fab")
			(hide yes)
			(effects
				(font
					(size 1 1)
					(thickness 0.15)
				)
			)
		)
		(property "Dielectric" ""
			(at 52.853 223.847 0)
			(layer "F.Fab")
			(hide yes)
			(effects
				(font
					(size 1 1)
					(thickness 0.15)
				)
			)
		)
		(property "License" "Apache-2.0"
			(at 52.853 223.847 0)
			(layer "F.Fab")
			(hide yes)
			(effects
				(font
					(size 1 1)
					(thickness 0.15)
				)
			)
		)
		(property "MPN" "GRM158R60J226ME01D"
			(at 52.853 223.847 0)
			(layer "F.Fab")
			(hide yes)
			(effects
				(font
					(size 1 1)
					(thickness 0.15)
				)
			)
		)
		(property "Manufacturer" "Murata"
			(at 52.853 223.847 0)
			(layer "F.Fab")
			(hide yes)
			(effects
				(font
					(size 1 1)
					(thickness 0.15)
				)
			)
		)
		(property "Val" "22u"
			(at 52.853 223.847 0)
			(layer "F.Fab")
			(hide yes)
			(effects
				(font
					(size 1 1)
					(thickness 0.15)
				)
			)
		)
		(property "Voltage" ""
			(at 52.853 223.847 0)
			(layer "F.Fab")
			(hide yes)
			(effects
				(font
					(size 1 1)
					(thickness 0.15)
				)
			)
		)
		(sheetname "Supply")
		(sheetfile "supply.kicad_sch")
		(attr smd)
		(fp_rect
			(start -0.925 -0.47)
			(end 0.925 0.47)
			(stroke
				(width 0.05)
				(type default)
			)
			(fill none)
			(layer "F.CrtYd")
		)
		(fp_line
			(start -0.494 0.248)
			(end -0.494 -0.25)
			(stroke
				(width 0.15)
				(type solid)
			)
			(layer "F.Fab")
		)
		(fp_line
			(start 0.504 0.248)
			(end -0.494 0.248)
			(stroke
				(width 0.15)
				(type solid)
			)
			(layer "F.Fab")
		)
		(fp_line
			(start -0.494 -0.25)
			(end 0.504 -0.25)
			(stroke
				(width 0.15)
				(type solid)
			)
			(layer "F.Fab")
		)
		(fp_line
			(start 0.504 -0.25)
			(end 0.504 0.248)
			(stroke
				(width 0.15)
				(type solid)
			)
			(layer "F.Fab")
		)
		(fp_text user "Author: Antmicro"
			(at -0.939 3.399 90)
			(layer "F.Fab")
			(hide yes)
			(effects
				(font
					(size 0.7 0.7)
					(thickness 0.15)
				)
				(justify right bottom)
			)
		)
		(fp_text user "License: Apache-2.0"
			(at -0.939 5.799 90)
			(layer "F.Fab")
			(hide yes)
			(effects
				(font
					(size 0.7 0.7)
					(thickness 0.15)
				)
				(justify right bottom)
			)
		)
		(fp_text user "${REFERENCE}"
			(at -0.939 4.599 90)
			(layer "F.Fab")
			(hide yes)
			(effects
				(font
					(size 0.7 0.7)
					(thickness 0.15)
				)
				(justify right bottom)
			)
		)
		(pad "1" smd roundrect
			(at -0.48 0 270)
			(size 0.59 0.64)
			(layers "F.Cu" "F.Paste" "F.Mask")
			(roundrect_rratio 0.25)
			(net 1 "GND")
			(pintype "passive")
		)
		(pad "2" smd roundrect
			(at 0.48 0 270)
			(size 0.59 0.64)
			(layers "F.Cu" "F.Paste" "F.Mask")
			(roundrect_rratio 0.25)
			(net 7 "/Supply/OUT_5V")
			(pintype "passive")
		)
	)
	(footprint "antmicro-footprints:R_0402_1005Metric"
		(layer "F.Cu")
		(at 140.83 81.060142 180)
		(descr "Resistor SMD 0402")
		(tags "resistor SMD 0402")
		(property "Reference" "R37"
			(at 0.69 0.590142 0)
			(layer "F.SilkS")
			(effects
				(font
					(size 0.7 0.7)
					(thickness 0.15)
				)
				(justify right top)
			)
		)
		(property "Value" "R_31k6_0402"
			(at -1.011843 1.772047 0)
			(layer "F.Fab")
			(effects
				(font
					(size 0.7 0.7)
					(thickness 0.15)
				)
				(justify right top)
			)
		)
		(property "Footprint" "antmicro-footprints:R_0402_1005Metric"
			(at 0 0 0)
			(layer "F.Fab")
			(hide yes)
			(effects
				(font
					(size 1.27 1.27)
					(thickness 0.15)
				)
			)
		)
		(property "Datasheet" "https://www.bourns.com/docs/product-datasheets/cr.pdf"
			(at 0 0 0)
			(layer "F.Fab")
			(hide yes)
			(effects
				(font
					(size 1.27 1.27)
					(thickness 0.15)
				)
			)
		)
		(property "Description" "SMD Chip Resistor"
			(at 0 0 0)
			(layer "F.Fab")
			(hide yes)
			(effects
				(font
					(size 1.27 1.27)
					(thickness 0.15)
				)
			)
		)
		(property "MPN" "CR0402-FX-3162GLF"
			(at 0 0 180)
			(unlocked yes)
			(layer "F.Fab")
			(hide yes)
			(effects
				(font
					(size 1 1)
					(thickness 0.15)
				)
			)
		)
		(property "Manufacturer" "Bourns"
			(at 0 0 180)
			(unlocked yes)
			(layer "F.Fab")
			(hide yes)
			(effects
				(font
					(size 1 1)
					(thickness 0.15)
				)
			)
		)
		(property "License" "Apache-2.0"
			(at 0 0 180)
			(unlocked yes)
			(layer "F.Fab")
			(hide yes)
			(effects
				(font
					(size 1 1)
					(thickness 0.15)
				)
			)
		)
		(property "Author" "Antmicro"
			(at 0 0 180)
			(unlocked yes)
			(layer "F.Fab")
			(hide yes)
			(effects
				(font
					(size 1 1)
					(thickness 0.15)
				)
			)
		)
		(property "Val" "31k6"
			(at 0 0 180)
			(unlocked yes)
			(layer "F.Fab")
			(hide yes)
			(effects
				(font
					(size 1 1)
					(thickness 0.15)
				)
			)
		)
		(property "Tolerance" "1%"
			(at 0 0 180)
			(unlocked yes)
			(layer "F.Fab")
			(hide yes)
			(effects
				(font
					(size 1 1)
					(thickness 0.15)
				)
			)
		)
		(sheetname "Supply")
		(sheetfile "supply.kicad_sch")
		(attr smd)
		(fp_rect
			(start -0.925 -0.47)
			(end 0.925 0.47)
			(stroke
				(width 0.05)
				(type default)
			)
			(fill none)
			(layer "F.CrtYd")
		)
		(fp_rect
			(start -0.5 -0.25)
			(end 0.5 0.25)
			(stroke
				(width 0.15)
				(type solid)
			)
			(fill none)
			(layer "F.Fab")
		)
		(fp_text user "Author: Antmicro"
			(at -0.95 4.169 0)
			(layer "F.Fab")
			(hide yes)
			(effects
				(font
					(size 0.7 0.7)
					(thickness 0.15)
				)
				(justify right top)
			)
		)
		(fp_text user "${REFERENCE}"
			(at -0.95 3.168 0)
			(layer "F.Fab")
			(hide yes)
			(effects
				(font
					(size 0.7 0.7)
					(thickness 0.15)
				)
				(justify right top)
			)
		)
		(fp_text user "License: Apache-2.0"
			(at -0.95 5.169 0)
			(layer "F.Fab")
			(hide yes)
			(effects
				(font
					(size 0.7 0.7)
					(thickness 0.15)
				)
				(justify right top)
			)
		)
		(pad "1" smd roundrect
			(at -0.48 0 180)
			(size 0.59 0.64)
			(layers "F.Cu" "F.Paste" "F.Mask")
			(roundrect_rratio 0.25)
			(net 96 "/Supply/FB_3V3")
			(pintype "passive")
		)
		(pad "2" smd roundrect
			(at 0.48 0 180)
			(size 0.59 0.64)
			(layers "F.Cu" "F.Paste" "F.Mask")
			(roundrect_rratio 0.25)
			(net 94 "/Supply/OUT_3V3")
			(pintype "passive")
		)
	)
	(footprint "antmicro-footprints:R_0402_1005Metric"
		(layer "F.Cu")
		(at 152.908 100.584 -135)
		(descr "Resistor SMD 0402")
		(tags "resistor SMD 0402")
		(property "Reference" "R20"
			(at -0.895197 -0.408708 45)
			(layer "F.SilkS")
			(effects
				(font
					(size 0.7 0.7)
					(thickness 0.15)
				)
				(justify left bottom)
			)
		)
		(property "Value" "R_0R_0402"
			(at -1.011843 1.772046 45)
			(layer "F.Fab")
			(effects
				(font
					(size 0.7 0.7)
					(thickness 0.15)
				)
				(justify right bottom)
			)
		)
		(property "Footprint" "antmicro-footprints:R_0402_1005Metric"
			(at 0 0 -135)
			(layer "F.Fab")
			(hide yes)
			(effects
				(font
					(size 1.27 1.27)
					(thickness 0.15)
				)
			)
		)
		(property "Datasheet" "https://industrial.panasonic.com/cdbs/www-data/pdf/RDA0000/AOA0000C301.pdf"
			(at 0 0 -135)
			(layer "F.Fab")
			(hide yes)
			(effects
				(font
					(size 1.27 1.27)
					(thickness 0.15)
				)
			)
		)
		(property "Author" "Antmicro"
			(at 189.906655 279.829912 0)
			(layer "F.Fab")
			(hide yes)
			(effects
				(font
					(size 1 1)
					(thickness 0.15)
				)
			)
		)
		(property "Current" "1A"
			(at 189.906655 279.829912 0)
			(layer "F.Fab")
			(hide yes)
			(effects
				(font
					(size 1 1)
					(thickness 0.15)
				)
			)
		)
		(property "License" "Apache-2.0"
			(at 189.906655 279.829912 0)
			(layer "F.Fab")
			(hide yes)
			(effects
				(font
					(size 1 1)
					(thickness 0.15)
				)
			)
		)
		(property "MPN" "ERJ2GE0R00X"
			(at 189.906655 279.829912 0)
			(layer "F.Fab")
			(hide yes)
			(effects
				(font
					(size 1 1)
					(thickness 0.15)
				)
			)
		)
		(property "Manufacturer" "Panasonic"
			(at 189.906655 279.829912 0)
			(layer "F.Fab")
			(hide yes)
			(effects
				(font
					(size 1 1)
					(thickness 0.15)
				)
			)
		)
		(property "Tolerance" ""
			(at 189.906655 279.829912 0)
			(layer "F.Fab")
			(hide yes)
			(effects
				(font
					(size 1 1)
					(thickness 0.15)
				)
			)
		)
		(property "Val" "0R"
			(at 189.906655 279.829912 0)
			(layer "F.Fab")
			(hide yes)
			(effects
				(font
					(size 1 1)
					(thickness 0.15)
				)
			)
		)
		(sheetname "Serializer")
		(sheetfile "serializer.kicad_sch")
		(attr smd)
		(fp_poly
			(pts
				(xy -0.925 -0.47) (xy 0.925 -0.47) (xy 0.925 0.47) (xy -0.925 0.47)
			)
			(stroke
				(width 0.05)
				(type default)
			)
			(fill none)
			(layer "F.CrtYd")
		)
		(fp_poly
			(pts
				(xy -0.5 -0.25) (xy 0.5 -0.25) (xy 0.5 0.25) (xy -0.5 0.25)
			)
			(stroke
				(width 0.15)
				(type solid)
			)
			(fill none)
			(layer "F.Fab")
		)
		(fp_text user "${REFERENCE}"
			(at -0.95 3.168 45)
			(layer "F.Fab")
			(hide yes)
			(effects
				(font
					(size 0.7 0.7)
					(thickness 0.15)
				)
				(justify right bottom)
			)
		)
		(fp_text user "License: Apache-2.0"
			(at -0.949999 5.169 45)
			(layer "F.Fab")
			(hide yes)
			(effects
				(font
					(size 0.7 0.7)
					(thickness 0.15)
				)
				(justify right bottom)
			)
		)
		(fp_text user "Author: Antmicro"
			(at -0.95 4.169 45)
			(layer "F.Fab")
			(hide yes)
			(effects
				(font
					(size 0.7 0.7)
					(thickness 0.15)
				)
				(justify right bottom)
			)
		)
		(pad "1" smd roundrect
			(at -0.48 0 225)
			(size 0.59 0.64)
			(layers "F.Cu" "F.Paste" "F.Mask")
			(roundrect_rratio 0.25)
			(net 14 "/Serializer/X2_R")
			(pintype "passive")
		)
		(pad "2" smd roundrect
			(at 0.48 0 225)
			(size 0.59 0.64)
			(layers "F.Cu" "F.Paste" "F.Mask")
			(roundrect_rratio 0.25)
			(net 67 "/Serializer/X2")
			(pintype "passive")
		)
	)
	(footprint "antmicro-footprints:R_0402_1005Metric"
		(layer "F.Cu")
		(at 136.855 79.675 -90)
		(descr "Resistor SMD 0402")
		(tags "resistor SMD 0402")
		(property "Reference" "R7"
			(at -0.935 -1.365 90)
			(layer "F.SilkS")
			(effects
				(font
					(size 0.7 0.7)
					(thickness 0.15)
				)
				(justify right bottom)
			)
		)
		(property "Value" "R_10k_0402"
			(at -1.011843 1.772047 90)
			(layer "F.Fab")
			(effects
				(font
					(size 0.7 0.7)
					(thickness 0.15)
				)
				(justify right bottom)
			)
		)
		(property "Footprint" "antmicro-footprints:R_0402_1005Metric"
			(at 0 0 -90)
			(layer "F.Fab")
			(hide yes)
			(effects
				(font
					(size 1.27 1.27)
					(thickness 0.15)
				)
			)
		)
		(property "Datasheet" "https://www.bourns.com/docs/product-datasheets/cr.pdf"
			(at 0 0 -90)
			(layer "F.Fab")
			(hide yes)
			(effects
				(font
					(size 1.27 1.27)
					(thickness 0.15)
				)
			)
		)
		(property "Author" "Antmicro"
			(at 59.1 218.15 0)
			(layer "F.Fab")
			(hide yes)
			(effects
				(font
					(size 1 1)
					(thickness 0.15)
				)
			)
		)
		(property "License" "Apache-2.0"
			(at 59.1 218.15 0)
			(layer "F.Fab")
			(hide yes)
			(effects
				(font
					(size 1 1)
					(thickness 0.15)
				)
			)
		)
		(property "MPN" "CR0402-FX-1002GLF"
			(at 59.1 218.15 0)
			(layer "F.Fab")
			(hide yes)
			(effects
				(font
					(size 1 1)
					(thickness 0.15)
				)
			)
		)
		(property "Manufacturer" "Bourns"
			(at 59.1 218.15 0)
			(layer "F.Fab")
			(hide yes)
			(effects
				(font
					(size 1 1)
					(thickness 0.15)
				)
			)
		)
		(property "Tolerance" "1%"
			(at 59.1 218.15 0)
			(layer "F.Fab")
			(hide yes)
			(effects
				(font
					(size 1 1)
					(thickness 0.15)
				)
			)
		)
		(property "Val" "10k"
			(at 59.1 218.15 0)
			(layer "F.Fab")
			(hide yes)
			(effects
				(font
					(size 1 1)
					(thickness 0.15)
				)
			)
		)
		(sheetname "Supply")
		(sheetfile "supply.kicad_sch")
		(attr smd)
		(fp_rect
			(start -0.925 -0.47)
			(end 0.925 0.47)
			(stroke
				(width 0.05)
				(type default)
			)
			(fill none)
			(layer "F.CrtYd")
		)
		(fp_rect
			(start -0.5 -0.25)
			(end 0.5 0.25)
			(stroke
				(width 0.15)
				(type solid)
			)
			(fill none)
			(layer "F.Fab")
		)
		(fp_text user "${REFERENCE}"
			(at -0.95 3.168 90)
			(layer "F.Fab")
			(hide yes)
			(effects
				(font
					(size 0.7 0.7)
					(thickness 0.15)
				)
				(justify right bottom)
			)
		)
		(fp_text user "License: Apache-2.0"
			(at -0.95 5.169 90)
			(layer "F.Fab")
			(hide yes)
			(effects
				(font
					(size 0.7 0.7)
					(thickness 0.15)
				)
				(justify right bottom)
			)
		)
		(fp_text user "Author: Antmicro"
			(at -0.95 4.169 90)
			(layer "F.Fab")
			(hide yes)
			(effects
				(font
					(size 0.7 0.7)
					(thickness 0.15)
				)
				(justify right bottom)
			)
		)
		(pad "1" smd roundrect
			(at -0.48 0 270)
			(size 0.59 0.64)
			(layers "F.Cu" "F.Paste" "F.Mask")
			(roundrect_rratio 0.25)
			(net 62 "/Supply/EN_5V")
			(pintype "passive")
		)
		(pad "2" smd roundrect
			(at 0.48 0 270)
			(size 0.59 0.64)
			(layers "F.Cu" "F.Paste" "F.Mask")
			(roundrect_rratio 0.25)
			(net 2 "+12V")
			(pintype "passive")
		)
	)
	(footprint "antmicro-footprints:R_0402_1005Metric"
		(layer "F.Cu")
		(at 133.1 105.574)
		(descr "Resistor SMD 0402")
		(tags "resistor SMD 0402")
		(property "Reference" "R1"
			(at 1.05 -4.890664 0)
			(layer "F.SilkS")
			(effects
				(font
					(size 0.7 0.7)
					(thickness 0.15)
				)
				(justify left bottom)
			)
		)
		(property "Value" "R_10k_0402"
			(at -1.011843 1.772047 0)
			(layer "F.Fab")
			(effects
				(font
					(size 0.7 0.7)
					(thickness 0.15)
				)
				(justify left bottom)
			)
		)
		(property "Footprint" "antmicro-footprints:R_0402_1005Metric"
			(at 0 0 0)
			(layer "F.Fab")
			(hide yes)
			(effects
				(font
					(size 1.27 1.27)
					(thickness 0.15)
				)
			)
		)
		(property "Datasheet" "https://www.bourns.com/docs/product-datasheets/cr.pdf"
			(at 0 0 0)
			(layer "F.Fab")
			(hide yes)
			(effects
				(font
					(size 1.27 1.27)
					(thickness 0.15)
				)
			)
		)
		(property "Author" "Antmicro"
			(at 0 0 0)
			(layer "F.Fab")
			(hide yes)
			(effects
				(font
					(size 1 1)
					(thickness 0.15)
				)
			)
		)
		(property "License" "Apache-2.0"
			(at 0 0 0)
			(layer "F.Fab")
			(hide yes)
			(effects
				(font
					(size 1 1)
					(thickness 0.15)
				)
			)
		)
		(property "MPN" "CR0402-FX-1002GLF"
			(at 0 0 0)
			(layer "F.Fab")
			(hide yes)
			(effects
				(font
					(size 1 1)
					(thickness 0.15)
				)
			)
		)
		(property "Manufacturer" "Bourns"
			(at 0 0 0)
			(layer "F.Fab")
			(hide yes)
			(effects
				(font
					(size 1 1)
					(thickness 0.15)
				)
			)
		)
		(property "Tolerance" "1%"
			(at 0 0 0)
			(layer "F.Fab")
			(hide yes)
			(effects
				(font
					(size 1 1)
					(thickness 0.15)
				)
			)
		)
		(property "Val" "10k"
			(at 0 0 0)
			(layer "F.Fab")
			(hide yes)
			(effects
				(font
					(size 1 1)
					(thickness 0.15)
				)
			)
		)
		(sheetname "CSI Connector")
		(sheetfile "CSI.kicad_sch")
		(attr smd)
		(fp_rect
			(start -0.925 -0.47)
			(end 0.925 0.47)
			(stroke
				(width 0.05)
				(type default)
			)
			(fill none)
			(layer "F.CrtYd")
		)
		(fp_rect
			(start -0.5 -0.25)
			(end 0.5 0.25)
			(stroke
				(width 0.15)
				(type solid)
			)
			(fill none)
			(layer "F.Fab")
		)
		(fp_text user "License: Apache-2.0"
			(at -0.95 5.169 0)
			(layer "F.Fab")
			(hide yes)
			(effects
				(font
					(size 0.7 0.7)
					(thickness 0.15)
				)
				(justify left bottom)
			)
		)
		(fp_text user "Author: Antmicro"
			(at -0.95 4.169 0)
			(layer "F.Fab")
			(hide yes)
			(effects
				(font
					(size 0.7 0.7)
					(thickness 0.15)
				)
				(justify left bottom)
			)
		)
		(fp_text user "${REFERENCE}"
			(at -0.95 3.168 0)
			(layer "F.Fab")
			(hide yes)
			(effects
				(font
					(size 0.7 0.7)
					(thickness 0.15)
				)
				(justify left bottom)
			)
		)
		(pad "1" smd roundrect
			(at -0.48 0)
			(size 0.59 0.64)
			(layers "F.Cu" "F.Paste" "F.Mask")
			(roundrect_rratio 0.25)
			(net 39 "/CSI Connector/GPIO4_1V8")
			(pintype "passive")
		)
		(pad "2" smd roundrect
			(at 0.48 0)
			(size 0.59 0.64)
			(layers "F.Cu" "F.Paste" "F.Mask")
			(roundrect_rratio 0.25)
			(net 87 "/CSI Connector/GPIO4")
			(pintype "passive")
		)
	)
	(footprint "antmicro-footprints:C_0603_1608Metric"
		(layer "F.Cu")
		(at 145.15 82.98 90)
		(descr "Capacitor SMD 0603")
		(tags "capacitor 0603")
		(property "Reference" "C19"
			(at -1.22 0.5 180)
			(layer "F.SilkS")
			(effects
				(font
					(size 0.7 0.7)
					(thickness 0.15)
				)
				(justify left bottom)
			)
		)
		(property "Value" "C_10u_25V_0603"
			(at -1.42757 1.770288 90)
			(layer "F.Fab")
			(effects
				(font
					(size 0.7 0.7)
					(thickness 0.15)
				)
				(justify left bottom)
			)
		)
		(property "Footprint" "antmicro-footprints:C_0603_1608Metric"
			(at 0 0 90)
			(layer "F.Fab")
			(hide yes)
			(effects
				(font
					(size 1.27 1.27)
					(thickness 0.15)
				)
			)
		)
		(property "Datasheet" "https://product.tdk.com/en/search/capacitor/ceramic/mlcc/info?part_no=C1608X5R1E106M080AC"
			(at 0 0 90)
			(layer "F.Fab")
			(hide yes)
			(effects
				(font
					(size 1.27 1.27)
					(thickness 0.15)
				)
			)
		)
		(property "MPN" "C1608X5R1E106M080AC"
			(at 0 0 90)
			(unlocked yes)
			(layer "F.Fab")
			(hide yes)
			(effects
				(font
					(size 1 1)
					(thickness 0.15)
				)
			)
		)
		(property "Manufacturer" "TDK"
			(at 0 0 90)
			(unlocked yes)
			(layer "F.Fab")
			(hide yes)
			(effects
				(font
					(size 1 1)
					(thickness 0.15)
				)
			)
		)
		(property "License" "Apache-2.0"
			(at 0 0 90)
			(unlocked yes)
			(layer "F.Fab")
			(hide yes)
			(effects
				(font
					(size 1 1)
					(thickness 0.15)
				)
			)
		)
		(property "Author" "Antmicro"
			(at 0 0 90)
			(unlocked yes)
			(layer "F.Fab")
			(hide yes)
			(effects
				(font
					(size 1 1)
					(thickness 0.15)
				)
			)
		)
		(property "Val" "10u"
			(at 0 0 90)
			(unlocked yes)
			(layer "F.Fab")
			(hide yes)
			(effects
				(font
					(size 1 1)
					(thickness 0.15)
				)
			)
		)
		(property "Voltage" "25V"
			(at 0 0 90)
			(unlocked yes)
			(layer "F.Fab")
			(hide yes)
			(effects
				(font
					(size 1 1)
					(thickness 0.15)
				)
			)
		)
		(property "Dielectric" ""
			(at 0 0 90)
			(unlocked yes)
			(layer "F.Fab")
			(hide yes)
			(effects
				(font
					(size 1 1)
					(thickness 0.15)
				)
			)
		)
		(sheetname "Supply")
		(sheetfile "supply.kicad_sch")
		(attr smd)
		(fp_line
			(start -0.15 -0.4)
			(end 0.15 -0.4)
			(stroke
				(width 0.15)
				(type solid)
			)
			(layer "F.SilkS")
		)
		(fp_line
			(start -0.15 0.4)
			(end 0.15 0.4)
			(stroke
				(width 0.15)
				(type solid)
			)
			(layer "F.SilkS")
		)
		(fp_rect
			(start -1.25 -0.65)
			(end 1.25 0.65)
			(stroke
				(width 0.05)
				(type solid)
			)
			(fill none)
			(layer "F.CrtYd")
		)
		(fp_rect
			(start -0.8 -0.4)
			(end 0.8 0.4)
			(stroke
				(width 0.15)
				(type solid)
			)
			(fill none)
			(layer "F.Fab")
		)
		(fp_text user "Author: Antmicro"
			(at -1.682 4.894 90)
			(layer "F.Fab")
			(hide yes)
			(effects
				(font
					(size 0.7 0.7)
					(thickness 0.15)
				)
				(justify left bottom)
			)
		)
		(fp_text user "License: Apache-2.0"
			(at -1.682 5.895 90)
			(layer "F.Fab")
			(hide yes)
			(effects
				(font
					(size 0.7 0.7)
					(thickness 0.15)
				)
				(justify left bottom)
			)
		)
		(fp_text user "${REFERENCE}"
			(at -1.682 3.895 90)
			(layer "F.Fab")
			(hide yes)
			(effects
				(font
					(size 0.7 0.7)
					(thickness 0.15)
				)
				(justify left bottom)
			)
		)
		(pad "1" smd roundrect
			(at -0.7 0 90)
			(size 0.8 1)
			(layers "F.Cu" "F.Paste" "F.Mask")
			(roundrect_rratio 0.2)
			(net 1 "GND")
			(pintype "passive")
		)
		(pad "2" smd roundrect
			(at 0.7 0 90)
			(size 0.8 1)
			(layers "F.Cu" "F.Paste" "F.Mask")
			(roundrect_rratio 0.2)
			(net 2 "+12V")
			(pintype "passive")
		)
	)
	(footprint "antmicro-footprints:LED_0603_1608Metric_G"
		(layer "F.Cu")
		(at 144.98 115.76 -90)
		(descr "LED SMD 0603 Green")
		(tags "LED SMD 0603 Green")
		(property "Reference" "D11"
			(at -3.41 0.51 90)
			(layer "F.SilkS")
			(effects
				(font
					(size 0.7 0.7)
					(thickness 0.15)
				)
				(justify right top)
			)
		)
		(property "Value" "LED_G_0603_LTST-C190GKT"
			(at -0.001 1.599 90)
			(layer "F.Fab")
			(effects
				(font
					(size 0.7 0.7)
					(thickness 0.15)
				)
				(justify right top)
			)
		)
		(property "Footprint" "antmicro-footprints:LED_0603_1608Metric_G"
			(at 0 0 90)
			(layer "F.Fab")
			(hide yes)
			(effects
				(font
					(size 1.27 1.27)
					(thickness 0.15)
				)
			)
		)
		(property "Datasheet" "https://media.digikey.com/pdf/Data%20Sheets/Lite-On%20PDFs/LTST-C190GKT.pdf"
			(at 0 0 90)
			(layer "F.Fab")
			(hide yes)
			(effects
				(font
					(size 1.27 1.27)
					(thickness 0.15)
				)
			)
		)
		(property "MPN" "LTST-C190GKT"
			(at 0 0 -90)
			(unlocked yes)
			(layer "F.Fab")
			(hide yes)
			(effects
				(font
					(size 1 1)
					(thickness 0.15)
				)
			)
		)
		(property "Manufacturer" "Lite-On"
			(at 0 0 -90)
			(unlocked yes)
			(layer "F.Fab")
			(hide yes)
			(effects
				(font
					(size 1 1)
					(thickness 0.15)
				)
			)
		)
		(property "Author" "Antmicro"
			(at 0 0 -90)
			(unlocked yes)
			(layer "F.Fab")
			(hide yes)
			(effects
				(font
					(size 1 1)
					(thickness 0.15)
				)
			)
		)
		(property "License" "Apache-2.0"
			(at 0 0 -90)
			(unlocked yes)
			(layer "F.Fab")
			(hide yes)
			(effects
				(font
					(size 1 1)
					(thickness 0.15)
				)
			)
		)
		(property "VSD_class" "LED"
			(at 0 0 -90)
			(unlocked yes)
			(layer "F.Fab")
			(hide yes)
			(effects
				(font
					(size 1 1)
					(thickness 0.15)
				)
			)
		)
		(property "Color" "Green"
			(at 0 0 -90)
			(unlocked yes)
			(layer "F.Fab")
			(hide yes)
			(effects
				(font
					(size 1 1)
					(thickness 0.15)
				)
			)
		)
		(sheetname "Supply")
		(sheetfile "supply.kicad_sch")
		(attr smd)
		(fp_line
			(start 0.22 0.35)
			(end -0.22 0.35)
			(stroke
				(width 0.15)
				(type solid)
			)
			(layer "F.SilkS")
		)
		(fp_line
			(start -0.094672 0.201008)
			(end -0.094672 -0.198992)
			(stroke
				(width 0.1)
				(type solid)
			)
			(layer "F.SilkS")
		)
		(fp_line
			(start 0.105328 0.201008)
			(end -0.094672 0.001008)
			(stroke
				(width 0.1)
				(type solid)
			)
			(layer "F.SilkS")
		)
		(fp_line
			(start 0.105328 0.201008)
			(end 0.105328 -0.198992)
			(stroke
				(width 0.1)
				(type solid)
			)
			(layer "F.SilkS")
		)
		(fp_line
			(start -0.094672 0.001008)
			(end -0.24 0.001008)
			(stroke
				(width 0.1)
				(type solid)
			)
			(layer "F.SilkS")
		)
		(fp_line
			(start -0.094672 0.001008)
			(end 0.105328 -0.198992)
			(stroke
				(width 0.1)
				(type solid)
			)
			(layer "F.SilkS")
		)
		(fp_line
			(start 0.105328 0.001008)
			(end 0.24 0.001)
			(stroke
				(width 0.1)
				(type solid)
			)
			(layer "F.SilkS")
		)
		(fp_line
			(start -1.18 -0.319)
			(end -1.18 0.321)
			(stroke
				(width 0.15)
				(type solid)
			)
			(layer "F.SilkS")
		)
		(fp_line
			(start 0.22 -0.35)
			(end -0.22 -0.35)
			(stroke
				(width 0.15)
				(type solid)
			)
			(layer "F.SilkS")
		)
		(fp_rect
			(start 1.25 0.65)
			(end -1.25 -0.65)
			(stroke
				(width 0.05)
				(type solid)
			)
			(fill none)
			(layer "F.CrtYd")
		)
		(fp_line
			(start -0.199 0.2)
			(end -0.199 0.1)
			(stroke
				(width 0.15)
				(type solid)
			)
			(layer "F.Fab")
		)
		(fp_line
			(start 0.201 0.2)
			(end 0.201 0)
			(stroke
				(width 0.15)
				(type solid)
			)
			(layer "F.Fab")
		)
		(fp_line
			(start -0.199 0)
			(end -0.597 0)
			(stroke
				(width 0.15)
				(type solid)
			)
			(layer "F.Fab")
		)
		(fp_line
			(start -0.101 0)
			(end 0.201 0.2)
			(stroke
				(width 0.15)
				(type solid)
			)
			(layer "F.Fab")
		)
		(fp_line
			(start 0.201 0)
			(end 0.201 -0.202)
			(stroke
				(width 0.15)
				(type solid)
			)
			(layer "F.Fab")
		)
		(fp_line
			(start 0.599 0)
			(end 0.201 0)
			(stroke
				(width 0.15)
				(type solid)
			)
			(layer "F.Fab")
		)
		(fp_line
			(start -0.199 -0.202)
			(end -0.199 0.1)
			(stroke
				(width 0.15)
				(type solid)
			)
			(layer "F.Fab")
		)
		(fp_line
			(start 0.201 -0.202)
			(end -0.101 0)
			(stroke
				(width 0.15)
				(type solid)
			)
			(layer "F.Fab")
		)
		(fp_rect
			(start 0.848 0.4)
			(end -0.85 -0.402)
			(stroke
				(width 0.15)
				(type solid)
			)
			(fill none)
			(layer "F.Fab")
		)
		(fp_text user "License: Apache-2.0"
			(at -1.4224 3.599 90)
			(layer "F.Fab")
			(hide yes)
			(effects
				(font
					(size 0.7 0.7)
					(thickness 0.15)
				)
				(justify right top)
			)
		)
		(fp_text user "${REFERENCE}"
			(at -1.4224 5.999 90)
			(layer "F.Fab")
			(hide yes)
			(effects
				(font
					(size 0.7 0.7)
					(thickness 0.15)
				)
				(justify right top)
			)
		)
		(fp_text user "Author: Antmicro"
			(at -1.4224 4.799 90)
			(layer "F.Fab")
			(hide yes)
			(effects
				(font
					(size 0.7 0.7)
					(thickness 0.15)
				)
				(justify right top)
			)
		)
		(pad "1" smd roundrect
			(at -0.7 0 90)
			(size 0.8 1)
			(layers "F.Cu" "F.Paste" "F.Mask")
			(roundrect_rratio 0.2)
			(net 95 "Net-(D11-C)")
			(pinfunction "C")
			(pintype "passive")
		)
		(pad "2" smd roundrect
			(at 0.7 0 90)
			(size 0.8 1)
			(layers "F.Cu" "F.Paste" "F.Mask")
			(roundrect_rratio 0.2)
			(net 10 "+3V3")
			(pinfunction "A")
			(pintype "passive")
		)
	)
	(footprint "antmicro-footprints:TP_SMD_1.5mm"
		(layer "F.Cu")
		(at 150.5 118)
		(property "Reference" "TP5"
			(at -0.4 -1 0)
			(layer "F.SilkS")
			(hide yes)
			(effects
				(font
					(size 0.7 0.7)
					(thickness 0.15)
				)
				(justify left bottom)
			)
		)
		(property "Value" "TP_1.5mm_SMD"
			(at 0 1.7 0)
			(layer "F.Fab")
			(effects
				(font
					(size 0.7 0.7)
					(thickness 0.15)
				)
				(justify left bottom)
			)
		)
		(property "Footprint" "antmicro-footprints:TP_SMD_1.5mm"
			(at 0 0 0)
			(layer "F.Fab")
			(hide yes)
			(effects
				(font
					(size 1.27 1.27)
					(thickness 0.15)
				)
			)
		)
		(property "Author" "Antmicro"
			(at 0 0 0)
			(layer "F.Fab")
			(hide yes)
			(effects
				(font
					(size 1 1)
					(thickness 0.15)
				)
			)
		)
		(property "License" "Apache-2.0"
			(at 0 0 0)
			(layer "F.Fab")
			(hide yes)
			(effects
				(font
					(size 1 1)
					(thickness 0.15)
				)
			)
		)
		(property "MPN" ""
			(at 0 0 0)
			(layer "F.Fab")
			(hide yes)
			(effects
				(font
					(size 1 1)
					(thickness 0.15)
				)
			)
		)
		(property "Manufacturer" ""
			(at 0 0 0)
			(layer "F.Fab")
			(hide yes)
			(effects
				(font
					(size 1 1)
					(thickness 0.15)
				)
			)
		)
		(sheetname "Supply")
		(sheetfile "supply.kicad_sch")
		(attr exclude_from_pos_files exclude_from_bom)
		(fp_circle
			(center 0 0)
			(end 0.85 0)
			(stroke
				(width 0.05)
				(type default)
			)
			(fill none)
			(layer "F.CrtYd")
		)
		(fp_text user "License: Apache-2.0"
			(at -0.7 5.301 0)
			(layer "F.Fab")
			(hide yes)
			(effects
				(font
					(size 0.7 0.7)
					(thickness 0.15)
				)
				(justify left bottom)
			)
		)
		(fp_text user "${REFERENCE}"
			(at -0.7 2.9 0)
			(layer "F.Fab")
			(hide yes)
			(effects
				(font
					(size 0.7 0.7)
					(thickness 0.15)
				)
				(justify left bottom)
			)
		)
		(fp_text user "Author: Antmicro"
			(at -0.7 4.101 0)
			(layer "F.Fab")
			(hide yes)
			(effects
				(font
					(size 0.7 0.7)
					(thickness 0.15)
				)
				(justify left bottom)
			)
		)
		(pad "1" smd circle
			(at 0 0 270)
			(size 1.5 1.5)
			(layers "F.Cu" "F.Mask")
			(net 12 "+1V2")
			(pinfunction "1")
			(pintype "passive")
		)
	)
	(footprint "antmicro-footprints:R_0402_1005Metric"
		(layer "F.Cu")
		(at 135.4 111.98)
		(descr "Resistor SMD 0402")
		(tags "resistor SMD 0402")
		(property "Reference" "R6"
			(at 0.9 0.37 0)
			(layer "F.SilkS")
			(effects
				(font
					(size 0.7 0.7)
					(thickness 0.15)
				)
				(justify left bottom)
			)
		)
		(property "Value" "R_4k7_0402"
			(at -1.011843 1.772047 0)
			(layer "F.Fab")
			(effects
				(font
					(size 0.7 0.7)
					(thickness 0.15)
				)
				(justify left bottom)
			)
		)
		(property "Footprint" "antmicro-footprints:R_0402_1005Metric"
			(at 0 0 0)
			(layer "F.Fab")
			(hide yes)
			(effects
				(font
					(size 1.27 1.27)
					(thickness 0.15)
				)
			)
		)
		(property "Datasheet" "https://www.bourns.com/docs/product-datasheets/cr.pdf"
			(at 0 0 0)
			(layer "F.Fab")
			(hide yes)
			(effects
				(font
					(size 1.27 1.27)
					(thickness 0.15)
				)
			)
		)
		(property "Author" "Antmicro"
			(at 0 0 0)
			(layer "F.Fab")
			(hide yes)
			(effects
				(font
					(size 1 1)
					(thickness 0.15)
				)
			)
		)
		(property "License" "Apache-2.0"
			(at 0 0 0)
			(layer "F.Fab")
			(hide yes)
			(effects
				(font
					(size 1 1)
					(thickness 0.15)
				)
			)
		)
		(property "MPN" "CR0402-FX-4701GLF"
			(at 0 0 0)
			(layer "F.Fab")
			(hide yes)
			(effects
				(font
					(size 1 1)
					(thickness 0.15)
				)
			)
		)
		(property "Manufacturer" "Bourns"
			(at 0 0 0)
			(layer "F.Fab")
			(hide yes)
			(effects
				(font
					(size 1 1)
					(thickness 0.15)
				)
			)
		)
		(property "Tolerance" "1%"
			(at 0 0 0)
			(layer "F.Fab")
			(hide yes)
			(effects
				(font
					(size 1 1)
					(thickness 0.15)
				)
			)
		)
		(property "Val" "4k7"
			(at 0 0 0)
			(layer "F.Fab")
			(hide yes)
			(effects
				(font
					(size 1 1)
					(thickness 0.15)
				)
			)
		)
		(sheetname "CSI Connector")
		(sheetfile "CSI.kicad_sch")
		(attr smd)
		(fp_rect
			(start -0.925 -0.47)
			(end 0.925 0.47)
			(stroke
				(width 0.05)
				(type default)
			)
			(fill none)
			(layer "F.CrtYd")
		)
		(fp_rect
			(start -0.5 -0.25)
			(end 0.5 0.25)
			(stroke
				(width 0.15)
				(type solid)
			)
			(fill none)
			(layer "F.Fab")
		)
		(fp_text user "Author: Antmicro"
			(at -0.95 4.169 0)
			(layer "F.Fab")
			(hide yes)
			(effects
				(font
					(size 0.7 0.7)
					(thickness 0.15)
				)
				(justify left bottom)
			)
		)
		(fp_text user "License: Apache-2.0"
			(at -0.95 5.169 0)
			(layer "F.Fab")
			(hide yes)
			(effects
				(font
					(size 0.7 0.7)
					(thickness 0.15)
				)
				(justify left bottom)
			)
		)
		(fp_text user "${REFERENCE}"
			(at -0.95 3.168 0)
			(layer "F.Fab")
			(hide yes)
			(effects
				(font
					(size 0.7 0.7)
					(thickness 0.15)
				)
				(justify left bottom)
			)
		)
		(pad "1" smd roundrect
			(at -0.48 0)
			(size 0.59 0.64)
			(layers "F.Cu" "F.Paste" "F.Mask")
			(roundrect_rratio 0.25)
			(net 89 "/CSI Connector/I2C.SCL")
			(pintype "passive")
		)
		(pad "2" smd roundrect
			(at 0.48 0)
			(size 0.59 0.64)
			(layers "F.Cu" "F.Paste" "F.Mask")
			(roundrect_rratio 0.25)
			(net 10 "+3V3")
			(pintype "passive")
		)
	)
	(footprint "antmicro-footprints:C_0402_1005Metric"
		(layer "F.Cu")
		(at 152.53 109.34)
		(descr "Capacitor SMD 0402")
		(tags "capacitor SMD 0402")
		(property "Reference" "C12"
			(at 0.94 0.39 0)
			(layer "F.SilkS")
			(effects
				(font
					(size 0.7 0.7)
					(thickness 0.15)
				)
				(justify left bottom)
			)
		)
		(property "Value" "C_1u_16V_0402"
			(at -1.022927 2.155213 0)
			(layer "F.Fab")
			(effects
				(font
					(size 0.7 0.7)
					(thickness 0.15)
				)
				(justify left bottom)
			)
		)
		(property "Footprint" "antmicro-footprints:C_0402_1005Metric"
			(at 0 0 0)
			(layer "F.Fab")
			(hide yes)
			(effects
				(font
					(size 1.27 1.27)
					(thickness 0.15)
				)
			)
		)
		(property "Datasheet" "https://www.kemet.com/en/us/capacitors/product/C0402C105M4PACTU.html"
			(at 0 0 0)
			(layer "F.Fab")
			(hide yes)
			(effects
				(font
					(size 1.27 1.27)
					(thickness 0.15)
				)
			)
		)
		(property "Author" "Antmicro"
			(at 0 0 0)
			(layer "F.Fab")
			(hide yes)
			(effects
				(font
					(size 1 1)
					(thickness 0.15)
				)
			)
		)
		(property "Dielectric" ""
			(at 0 0 0)
			(layer "F.Fab")
			(hide yes)
			(effects
				(font
					(size 1 1)
					(thickness 0.15)
				)
			)
		)
		(property "License" "Apache-2.0"
			(at 0 0 0)
			(layer "F.Fab")
			(hide yes)
			(effects
				(font
					(size 1 1)
					(thickness 0.15)
				)
			)
		)
		(property "MPN" "C0402C105M4PACTU"
			(at 0 0 0)
			(layer "F.Fab")
			(hide yes)
			(effects
				(font
					(size 1 1)
					(thickness 0.15)
				)
			)
		)
		(property "Manufacturer" "KEMET"
			(at 0 0 0)
			(layer "F.Fab")
			(hide yes)
			(effects
				(font
					(size 1 1)
					(thickness 0.15)
				)
			)
		)
		(property "Val" "1u"
			(at 0 0 0)
			(layer "F.Fab")
			(hide yes)
			(effects
				(font
					(size 1 1)
					(thickness 0.15)
				)
			)
		)
		(property "Voltage" "16V"
			(at 0 0 0)
			(layer "F.Fab")
			(hide yes)
			(effects
				(font
					(size 1 1)
					(thickness 0.15)
				)
			)
		)
		(sheetname "Supply")
		(sheetfile "supply.kicad_sch")
		(attr smd dnp)
		(fp_rect
			(start -0.925 -0.47)
			(end 0.925 0.47)
			(stroke
				(width 0.05)
				(type default)
			)
			(fill none)
			(layer "F.CrtYd")
		)
		(fp_line
			(start -0.494 -0.25)
			(end 0.504 -0.25)
			(stroke
				(width 0.15)
				(type solid)
			)
			(layer "F.Fab")
		)
		(fp_line
			(start -0.494 0.248)
			(end -0.494 -0.25)
			(stroke
				(width 0.15)
				(type solid)
			)
			(layer "F.Fab")
		)
		(fp_line
			(start 0.504 -0.25)
			(end 0.504 0.248)
			(stroke
				(width 0.15)
				(type solid)
			)
			(layer "F.Fab")
		)
		(fp_line
			(start 0.504 0.248)
			(end -0.494 0.248)
			(stroke
				(width 0.15)
				(type solid)
			)
			(layer "F.Fab")
		)
		(fp_text user "${REFERENCE}"
			(at -0.939 4.599 0)
			(layer "F.Fab")
			(hide yes)
			(effects
				(font
					(size 0.7 0.7)
					(thickness 0.15)
				)
				(justify left bottom)
			)
		)
		(fp_text user "License: Apache-2.0"
			(at -0.939 5.799 0)
			(layer "F.Fab")
			(hide yes)
			(effects
				(font
					(size 0.7 0.7)
					(thickness 0.15)
				)
				(justify left bottom)
			)
		)
		(fp_text user "Author: Antmicro"
			(at -0.939 3.399 0)
			(layer "F.Fab")
			(hide yes)
			(effects
				(font
					(size 0.7 0.7)
					(thickness 0.15)
				)
				(justify left bottom)
			)
		)
		(pad "1" smd roundrect
			(at -0.48 0)
			(size 0.59 0.64)
			(layers "F.Cu" "F.Paste" "F.Mask")
			(roundrect_rratio 0.25)
			(net 1 "GND")
			(pintype "passive")
		)
		(pad "2" smd roundrect
			(at 0.48 0)
			(size 0.59 0.64)
			(layers "F.Cu" "F.Paste" "F.Mask")
			(roundrect_rratio 0.25)
			(net 9 "+5V")
			(pintype "passive")
		)
	)
	(footprint "antmicro-footprints:R_0402_1005Metric"
		(layer "F.Cu")
		(at 149.345 115.95 90)
		(descr "Resistor SMD 0402")
		(tags "resistor SMD 0402")
		(property "Reference" "R35"
			(at -2.875 0.325 90)
			(layer "F.SilkS")
			(effects
				(font
					(size 0.7 0.7)
					(thickness 0.15)
				)
				(justify left bottom)
			)
		)
		(property "Value" "R_470R_0402"
			(at -1.011843 1.772047 90)
			(layer "F.Fab")
			(effects
				(font
					(size 0.7 0.7)
					(thickness 0.15)
				)
				(justify left bottom)
			)
		)
		(property "Footprint" "antmicro-footprints:R_0402_1005Metric"
			(at 0 0 90)
			(layer "F.Fab")
			(hide yes)
			(effects
				(font
					(size 1.27 1.27)
					(thickness 0.15)
				)
			)
		)
		(property "Datasheet" "https://www.bourns.com/docs/product-datasheets/cr.pdf"
			(at 0 0 90)
			(layer "F.Fab")
			(hide yes)
			(effects
				(font
					(size 1.27 1.27)
					(thickness 0.15)
				)
			)
		)
		(property "Author" "Antmicro"
			(at 265.295 -33.395 0)
			(layer "F.Fab")
			(hide yes)
			(effects
				(font
					(size 1 1)
					(thickness 0.15)
				)
			)
		)
		(property "License" "Apache-2.0"
			(at 265.295 -33.395 0)
			(layer "F.Fab")
			(hide yes)
			(effects
				(font
					(size 1 1)
					(thickness 0.15)
				)
			)
		)
		(property "MPN" "CR0402-FX-4700GLF"
			(at 265.295 -33.395 0)
			(layer "F.Fab")
			(hide yes)
			(effects
				(font
					(size 1 1)
					(thickness 0.15)
				)
			)
		)
		(property "Manufacturer" "Bourns"
			(at 265.295 -33.395 0)
			(layer "F.Fab")
			(hide yes)
			(effects
				(font
					(size 1 1)
					(thickness 0.15)
				)
			)
		)
		(property "Tolerance" "1%"
			(at 265.295 -33.395 0)
			(layer "F.Fab")
			(hide yes)
			(effects
				(font
					(size 1 1)
					(thickness 0.15)
				)
			)
		)
		(property "Val" "470R"
			(at 265.295 -33.395 0)
			(layer "F.Fab")
			(hide yes)
			(effects
				(font
					(size 1 1)
					(thickness 0.15)
				)
			)
		)
		(sheetname "Supply")
		(sheetfile "supply.kicad_sch")
		(attr smd)
		(fp_rect
			(start -0.925 -0.47)
			(end 0.925 0.47)
			(stroke
				(width 0.05)
				(type default)
			)
			(fill none)
			(layer "F.CrtYd")
		)
		(fp_rect
			(start -0.5 -0.25)
			(end 0.5 0.25)
			(stroke
				(width 0.15)
				(type solid)
			)
			(fill none)
			(layer "F.Fab")
		)
		(fp_text user "License: Apache-2.0"
			(at -0.95 5.169 90)
			(layer "F.Fab")
			(hide yes)
			(effects
				(font
					(size 0.7 0.7)
					(thickness 0.15)
				)
				(justify left bottom)
			)
		)
		(fp_text user "${REFERENCE}"
			(at -0.95 3.168 90)
			(layer "F.Fab")
			(hide yes)
			(effects
				(font
					(size 0.7 0.7)
					(thickness 0.15)
				)
				(justify left bottom)
			)
		)
		(fp_text user "Author: Antmicro"
			(at -0.95 4.169 90)
			(layer "F.Fab")
			(hide yes)
			(effects
				(font
					(size 0.7 0.7)
					(thickness 0.15)
				)
				(justify left bottom)
			)
		)
		(pad "1" smd roundrect
			(at -0.48 0 90)
			(size 0.59 0.64)
			(layers "F.Cu" "F.Paste" "F.Mask")
			(roundrect_rratio 0.25)
			(net 71 "Net-(D6-A)")
			(pintype "passive")
		)
		(pad "2" smd roundrect
			(at 0.48 0 90)
			(size 0.59 0.64)
			(layers "F.Cu" "F.Paste" "F.Mask")
			(roundrect_rratio 0.25)
			(net 9 "+5V")
			(pintype "passive")
		)
	)
	(footprint "antmicro-footprints:Resonator_SMD_Abracon_ABM8G_3.2x2.5mm"
		(layer "F.Cu")
		(at 154.686 101.854 45)
		(property "Reference" "Y1"
			(at 2.063338 1.562706 -135)
			(layer "F.SilkS")
			(effects
				(font
					(size 0.7 0.7)
					(thickness 0.15)
				)
				(justify left bottom)
			)
		)
		(property "Value" "Resonator_25MHz_ABM8G"
			(at -1.75 2.548 45)
			(layer "F.Fab")
			(effects
				(font
					(size 0.7 0.7)
					(thickness 0.15)
				)
				(justify left bottom)
			)
		)
		(property "Footprint" "antmicro-footprints:Resonator_SMD_Abracon_ABM8G_3.2x2.5mm"
			(at 0 0 45)
			(layer "F.Fab")
			(hide yes)
			(effects
				(font
					(size 1.27 1.27)
					(thickness 0.15)
				)
			)
		)
		(property "Datasheet" "https://abracon.com/Resonators/ABM8G.pdf"
			(at 0 0 45)
			(layer "F.Fab")
			(hide yes)
			(effects
				(font
					(size 1.27 1.27)
					(thickness 0.15)
				)
			)
		)
		(property "Author" "Antmicro"
			(at 117.328134 -79.547173 0)
			(layer "F.Fab")
			(hide yes)
			(effects
				(font
					(size 1 1)
					(thickness 0.15)
				)
			)
		)
		(property "License" "Apache-2.0"
			(at 117.328134 -79.547173 0)
			(layer "F.Fab")
			(hide yes)
			(effects
				(font
					(size 1 1)
					(thickness 0.15)
				)
			)
		)
		(property "MPN" "ABM8G-25.000MHZ-18-D2Y-T3"
			(at 117.328134 -79.547173 0)
			(layer "F.Fab")
			(hide yes)
			(effects
				(font
					(size 1 1)
					(thickness 0.15)
				)
			)
		)
		(property "Manufacturer" "Abracon"
			(at 117.328134 -79.547173 0)
			(layer "F.Fab")
			(hide yes)
			(effects
				(font
					(size 1 1)
					(thickness 0.15)
				)
			)
		)
		(property "Val" "25 MHz"
			(at 117.328134 -79.547173 0)
			(layer "F.Fab")
			(hide yes)
			(effects
				(font
					(size 1 1)
					(thickness 0.15)
				)
			)
		)
		(sheetname "Serializer")
		(sheetfile "serializer.kicad_sch")
		(attr smd)
		(fp_line
			(start -0.35 -1.25)
			(end 0.450001 -1.25)
			(stroke
				(width 0.15)
				(type solid)
			)
			(layer "F.SilkS")
		)
		(fp_line
			(start -1.6 0.3)
			(end -1.6 -0.2)
			(stroke
				(width 0.15)
				(type solid)
			)
			(layer "F.SilkS")
		)
		(fp_line
			(start -0.35 1.25)
			(end 0.450001 1.25)
			(stroke
				(width 0.15)
				(type solid)
			)
			(layer "F.SilkS")
		)
		(fp_line
			(start 1.6 0.3)
			(end 1.6 -0.2)
			(stroke
				(width 0.15)
				(type solid)
			)
			(layer "F.SilkS")
		)
		(fp_circle
			(center -1.75 1.5)
			(end -1.7 1.5)
			(stroke
				(width 0.15)
				(type solid)
			)
			(fill none)
			(layer "F.SilkS")
		)
		(fp_poly
			(pts
				(xy -1.907 -1.55) (xy 2.006 -1.55) (xy 2.006 1.649) (xy -1.907001 1.649)
			)
			(stroke
				(width 0.05)
				(type solid)
			)
			(fill none)
			(layer "F.CrtYd")
		)
		(fp_text user "Author: Antmicro"
			(at -1.75 5 45)
			(layer "F.Fab")
			(hide yes)
			(effects
				(font
					(size 0.7 0.7)
					(thickness 0.15)
				)
				(justify left bottom)
			)
		)
		(fp_text user "${REFERENCE}"
			(at -1.749999 3.75 45)
			(layer "F.Fab")
			(hide yes)
			(effects
				(font
					(size 0.7 0.7)
					(thickness 0.15)
				)
				(justify left bottom)
			)
		)
		(fp_text user "License: Apache-2.0"
			(at -1.75 6.5 45)
			(layer "F.Fab")
			(hide yes)
			(effects
				(font
					(size 0.7 0.7)
					(thickness 0.15)
				)
				(justify left bottom)
			)
		)
		(pad "1" smd roundrect
			(at -1.101 0.949 45)
			(size 1.3 1.1)
			(layers "F.Cu" "F.Paste" "F.Mask")
			(roundrect_rratio 0)
			(chamfer_ratio 0.2)
			(chamfer bottom_left)
			(net 13 "/Serializer/X1")
			(pintype "passive")
		)
		(pad "2" smd rect
			(at 1.199 0.949 45)
			(size 1.3 1.1)
			(layers "F.Cu" "F.Paste" "F.Mask")
			(net 1 "GND")
			(pinfunction "SH")
			(pintype "passive")
		)
		(pad "3" smd rect
			(at 1.199 -0.85 45)
			(size 1.3 1.1)
			(layers "F.Cu" "F.Paste" "F.Mask")
			(net 14 "/Serializer/X2_R")
			(pintype "passive")
		)
		(pad "4" smd rect
			(at -1.101 -0.85 45)
			(size 1.3 1.1)
			(layers "F.Cu" "F.Paste" "F.Mask")
			(net 1 "GND")
			(pinfunction "SH")
			(pintype "passive")
		)
	)
	(footprint "antmicro-footprints:C_0402_1005Metric"
		(layer "F.Cu")
		(at 163.851 93.735)
		(descr "Capacitor SMD 0402")
		(tags "capacitor SMD 0402")
		(property "Reference" "C11"
			(at -1.006 1.32 0)
			(layer "F.SilkS")
			(effects
				(font
					(size 0.7 0.7)
					(thickness 0.15)
				)
				(justify left bottom)
			)
		)
		(property "Value" "C_10n_0402"
			(at -1.022927 2.155213 0)
			(layer "F.Fab")
			(effects
				(font
					(size 0.7 0.7)
					(thickness 0.15)
				)
				(justify left bottom)
			)
		)
		(property "Footprint" "antmicro-footprints:C_0402_1005Metric"
			(at 0 0 0)
			(layer "F.Fab")
			(hide yes)
			(effects
				(font
					(size 1.27 1.27)
					(thickness 0.15)
				)
			)
		)
		(property "Datasheet" "https://www.murata.com/products/productdetail?partno=GRM155R71H103KA88%23"
			(at 0 0 0)
			(layer "F.Fab")
			(hide yes)
			(effects
				(font
					(size 1.27 1.27)
					(thickness 0.15)
				)
			)
		)
		(property "Author" "Antmicro"
			(at 0 0 0)
			(layer "F.Fab")
			(hide yes)
			(effects
				(font
					(size 1 1)
					(thickness 0.15)
				)
			)
		)
		(property "Dielectric" "X7R"
			(at 0 0 0)
			(layer "F.Fab")
			(hide yes)
			(effects
				(font
					(size 1 1)
					(thickness 0.15)
				)
			)
		)
		(property "License" "Apache-2.0"
			(at 0 0 0)
			(layer "F.Fab")
			(hide yes)
			(effects
				(font
					(size 1 1)
					(thickness 0.15)
				)
			)
		)
		(property "MPN" "GRM155R71H103KA88D"
			(at 0 0 0)
			(layer "F.Fab")
			(hide yes)
			(effects
				(font
					(size 1 1)
					(thickness 0.15)
				)
			)
		)
		(property "Manufacturer" "Murata"
			(at 0 0 0)
			(layer "F.Fab")
			(hide yes)
			(effects
				(font
					(size 1 1)
					(thickness 0.15)
				)
			)
		)
		(property "Val" "10n"
			(at 0 0 0)
			(layer "F.Fab")
			(hide yes)
			(effects
				(font
					(size 1 1)
					(thickness 0.15)
				)
			)
		)
		(property "Voltage" "50V"
			(at 0 0 0)
			(layer "F.Fab")
			(hide yes)
			(effects
				(font
					(size 1 1)
					(thickness 0.15)
				)
			)
		)
		(sheetname "GMSL Connector")
		(sheetfile "GMSL.kicad_sch")
		(attr smd)
		(fp_rect
			(start -0.925 -0.47)
			(end 0.925 0.47)
			(stroke
				(width 0.05)
				(type default)
			)
			(fill none)
			(layer "F.CrtYd")
		)
		(fp_line
			(start -0.494 -0.25)
			(end 0.504 -0.25)
			(stroke
				(width 0.15)
				(type solid)
			)
			(layer "F.Fab")
		)
		(fp_line
			(start -0.494 0.248)
			(end -0.494 -0.25)
			(stroke
				(width 0.15)
				(type solid)
			)
			(layer "F.Fab")
		)
		(fp_line
			(start 0.504 -0.25)
			(end 0.504 0.248)
			(stroke
				(width 0.15)
				(type solid)
			)
			(layer "F.Fab")
		)
		(fp_line
			(start 0.504 0.248)
			(end -0.494 0.248)
			(stroke
				(width 0.15)
				(type solid)
			)
			(layer "F.Fab")
		)
		(fp_text user "License: Apache-2.0"
			(at -0.939 5.799 0)
			(layer "F.Fab")
			(hide yes)
			(effects
				(font
					(size 0.7 0.7)
					(thickness 0.15)
				)
				(justify left bottom)
			)
		)
		(fp_text user "${REFERENCE}"
			(at -0.939 4.599 0)
			(layer "F.Fab")
			(hide yes)
			(effects
				(font
					(size 0.7 0.7)
					(thickness 0.15)
				)
				(justify left bottom)
			)
		)
		(fp_text user "Author: Antmicro"
			(at -0.939 3.399 0)
			(layer "F.Fab")
			(hide yes)
			(effects
				(font
					(size 0.7 0.7)
					(thickness 0.15)
				)
				(justify left bottom)
			)
		)
		(pad "1" smd roundrect
			(at -0.48 0)
			(size 0.59 0.64)
			(layers "F.Cu" "F.Paste" "F.Mask")
			(roundrect_rratio 0.25)
			(net 1 "GND")
			(pintype "passive")
		)
		(pad "2" smd roundrect
			(at 0.48 0)
			(size 0.59 0.64)
			(layers "F.Cu" "F.Paste" "F.Mask")
			(roundrect_rratio 0.25)
			(net 2 "+12V")
			(pintype "passive")
		)
	)
	(footprint "antmicro-footprints:R_0402_1005Metric"
		(layer "F.Cu")
		(at 150.15 110.28 180)
		(descr "Resistor SMD 0402")
		(tags "resistor SMD 0402")
		(property "Reference" "R19"
			(at -3.03 -0.4 0)
			(layer "F.SilkS")
			(effects
				(font
					(size 0.7 0.7)
					(thickness 0.15)
				)
				(justify right bottom)
			)
		)
		(property "Value" "R_10k_0402"
			(at -1.011843 1.772047 0)
			(layer "F.Fab")
			(effects
				(font
					(size 0.7 0.7)
					(thickness 0.15)
				)
				(justify right bottom)
			)
		)
		(property "Footprint" "antmicro-footprints:R_0402_1005Metric"
			(at 0 0 180)
			(layer "F.Fab")
			(hide yes)
			(effects
				(font
					(size 1.27 1.27)
					(thickness 0.15)
				)
			)
		)
		(property "Datasheet" "https://www.bourns.com/docs/product-datasheets/cr.pdf"
			(at 0 0 180)
			(layer "F.Fab")
			(hide yes)
			(effects
				(font
					(size 1.27 1.27)
					(thickness 0.15)
				)
			)
		)
		(property "Author" "Antmicro"
			(at 300.3 220.56 0)
			(layer "F.Fab")
			(hide yes)
			(effects
				(font
					(size 1 1)
					(thickness 0.15)
				)
			)
		)
		(property "License" "Apache-2.0"
			(at 300.3 220.56 0)
			(layer "F.Fab")
			(hide yes)
			(effects
				(font
					(size 1 1)
					(thickness 0.15)
				)
			)
		)
		(property "MPN" "CR0402-FX-1002GLF"
			(at 300.3 220.56 0)
			(layer "F.Fab")
			(hide yes)
			(effects
				(font
					(size 1 1)
					(thickness 0.15)
				)
			)
		)
		(property "Manufacturer" "Bourns"
			(at 300.3 220.56 0)
			(layer "F.Fab")
			(hide yes)
			(effects
				(font
					(size 1 1)
					(thickness 0.15)
				)
			)
		)
		(property "Tolerance" "1%"
			(at 300.3 220.56 0)
			(layer "F.Fab")
			(hide yes)
			(effects
				(font
					(size 1 1)
					(thickness 0.15)
				)
			)
		)
		(property "Val" "10k"
			(at 300.3 220.56 0)
			(layer "F.Fab")
			(hide yes)
			(effects
				(font
					(size 1 1)
					(thickness 0.15)
				)
			)
		)
		(sheetname "Serializer")
		(sheetfile "serializer.kicad_sch")
		(attr smd)
		(fp_rect
			(start -0.925 -0.47)
			(end 0.925 0.47)
			(stroke
				(width 0.05)
				(type default)
			)
			(fill none)
			(layer "F.CrtYd")
		)
		(fp_rect
			(start -0.5 -0.25)
			(end 0.5 0.25)
			(stroke
				(width 0.15)
				(type solid)
			)
			(fill none)
			(layer "F.Fab")
		)
		(fp_text user "License: Apache-2.0"
			(at -0.95 5.169 0)
			(layer "F.Fab")
			(hide yes)
			(effects
				(font
					(size 0.7 0.7)
					(thickness 0.15)
				)
				(justify right bottom)
			)
		)
		(fp_text user "Author: Antmicro"
			(at -0.95 4.169 0)
			(layer "F.Fab")
			(hide yes)
			(effects
				(font
					(size 0.7 0.7)
					(thickness 0.15)
				)
				(justify right bottom)
			)
		)
		(fp_text user "${REFERENCE}"
			(at -0.95 3.168 0)
			(layer "F.Fab")
			(hide yes)
			(effects
				(font
					(size 0.7 0.7)
					(thickness 0.15)
				)
				(justify right bottom)
			)
		)
		(pad "1" smd roundrect
			(at -0.48 0 180)
			(size 0.59 0.64)
			(layers "F.Cu" "F.Paste" "F.Mask")
			(roundrect_rratio 0.25)
			(net 1 "GND")
			(pintype "passive")
		)
		(pad "2" smd roundrect
			(at 0.48 0 180)
			(size 0.59 0.64)
			(layers "F.Cu" "F.Paste" "F.Mask")
			(roundrect_rratio 0.25)
			(net 66 "/Serializer/CFG0")
			(pintype "passive")
		)
	)
	(footprint "antmicro-footprints:R_0402_1005Metric"
		(layer "F.Cu")
		(at 148.15 109.205 180)
		(descr "Resistor SMD 0402")
		(tags "resistor SMD 0402")
		(property "Reference" "R28"
			(at 0.88 -0.47 0)
			(layer "F.SilkS")
			(effects
				(font
					(size 0.7 0.7)
					(thickness 0.15)
				)
				(justify right bottom)
			)
		)
		(property "Value" "R_10k_0402"
			(at -1.011843 1.772047 0)
			(layer "F.Fab")
			(effects
				(font
					(size 0.7 0.7)
					(thickness 0.15)
				)
				(justify right bottom)
			)
		)
		(property "Footprint" "antmicro-footprints:R_0402_1005Metric"
			(at 0 0 180)
			(layer "F.Fab")
			(hide yes)
			(effects
				(font
					(size 1.27 1.27)
					(thickness 0.15)
				)
			)
		)
		(property "Datasheet" "https://www.bourns.com/docs/product-datasheets/cr.pdf"
			(at 0 0 180)
			(layer "F.Fab")
			(hide yes)
			(effects
				(font
					(size 1.27 1.27)
					(thickness 0.15)
				)
			)
		)
		(property "Author" "Antmicro"
			(at 296.3 218.41 0)
			(layer "F.Fab")
			(hide yes)
			(effects
				(font
					(size 1 1)
					(thickness 0.15)
				)
			)
		)
		(property "License" "Apache-2.0"
			(at 296.3 218.41 0)
			(layer "F.Fab")
			(hide yes)
			(effects
				(font
					(size 1 1)
					(thickness 0.15)
				)
			)
		)
		(property "MPN" "CR0402-FX-1002GLF"
			(at 296.3 218.41 0)
			(layer "F.Fab")
			(hide yes)
			(effects
				(font
					(size 1 1)
					(thickness 0.15)
				)
			)
		)
		(property "Manufacturer" "Bourns"
			(at 296.3 218.41 0)
			(layer "F.Fab")
			(hide yes)
			(effects
				(font
					(size 1 1)
					(thickness 0.15)
				)
			)
		)
		(property "Tolerance" "1%"
			(at 296.3 218.41 0)
			(layer "F.Fab")
			(hide yes)
			(effects
				(font
					(size 1 1)
					(thickness 0.15)
				)
			)
		)
		(property "Val" "10k"
			(at 296.3 218.41 0)
			(layer "F.Fab")
			(hide yes)
			(effects
				(font
					(size 1 1)
					(thickness 0.15)
				)
			)
		)
		(sheetname "Serializer")
		(sheetfile "serializer.kicad_sch")
		(attr smd)
		(fp_rect
			(start -0.925 -0.47)
			(end 0.925 0.47)
			(stroke
				(width 0.05)
				(type default)
			)
			(fill none)
			(layer "F.CrtYd")
		)
		(fp_rect
			(start -0.5 -0.25)
			(end 0.5 0.25)
			(stroke
				(width 0.15)
				(type solid)
			)
			(fill none)
			(layer "F.Fab")
		)
		(fp_text user "${REFERENCE}"
			(at -0.95 3.168 0)
			(layer "F.Fab")
			(hide yes)
			(effects
				(font
					(size 0.7 0.7)
					(thickness 0.15)
				)
				(justify right bottom)
			)
		)
		(fp_text user "License: Apache-2.0"
			(at -0.95 5.169 0)
			(layer "F.Fab")
			(hide yes)
			(effects
				(font
					(size 0.7 0.7)
					(thickness 0.15)
				)
				(justify right bottom)
			)
		)
		(fp_text user "Author: Antmicro"
			(at -0.95 4.169 0)
			(layer "F.Fab")
			(hide yes)
			(effects
				(font
					(size 0.7 0.7)
					(thickness 0.15)
				)
				(justify right bottom)
			)
		)
		(pad "1" smd roundrect
			(at -0.48 0 180)
			(size 0.59 0.64)
			(layers "F.Cu" "F.Paste" "F.Mask")
			(roundrect_rratio 0.25)
			(net 77 "Net-(U6-PWDNB)")
			(pintype "passive")
		)
		(pad "2" smd roundrect
			(at 0.48 0 180)
			(size 0.59 0.64)
			(layers "F.Cu" "F.Paste" "F.Mask")
			(roundrect_rratio 0.25)
			(net 10 "+3V3")
			(pintype "passive")
		)
	)
	(footprint "antmicro-footprints:SOT-23-3"
		(layer "F.Cu")
		(at 152.33 107.14 180)
		(property "Reference" "U4"
			(at -0.833 1.754 0)
			(layer "F.SilkS")
			(effects
				(font
					(size 0.7 0.7)
					(thickness 0.15)
				)
				(justify right bottom)
			)
		)
		(property "Value" "REF3012AIDBZT"
			(at -1.9 2.7 0)
			(layer "F.Fab")
			(effects
				(font
					(size 0.7 0.7)
					(thickness 0.15)
				)
				(justify right bottom)
			)
		)
		(property "Footprint" "antmicro-footprints:SOT-23-3"
			(at 0 0 180)
			(layer "F.Fab")
			(hide yes)
			(effects
				(font
					(size 1.27 1.27)
					(thickness 0.15)
				)
			)
		)
		(property "Datasheet" "https://www.ti.com/lit/gpn/REF3012"
			(at 0 0 180)
			(layer "F.Fab")
			(hide yes)
			(effects
				(font
					(size 1.27 1.27)
					(thickness 0.15)
				)
			)
		)
		(property "Author" "Antmicro"
			(at 304.66 214.28 0)
			(layer "F.Fab")
			(hide yes)
			(effects
				(font
					(size 1 1)
					(thickness 0.15)
				)
			)
		)
		(property "License" "Apache-2.0"
			(at 304.66 214.28 0)
			(layer "F.Fab")
			(hide yes)
			(effects
				(font
					(size 1 1)
					(thickness 0.15)
				)
			)
		)
		(property "MPN" "REF3012AIDBZT"
			(at 304.66 214.28 0)
			(layer "F.Fab")
			(hide yes)
			(effects
				(font
					(size 1 1)
					(thickness 0.15)
				)
			)
		)
		(property "Manufacturer" "Texas Instruments"
			(at 304.66 214.28 0)
			(layer "F.Fab")
			(hide yes)
			(effects
				(font
					(size 1 1)
					(thickness 0.15)
				)
			)
		)
		(sheetname "Supply")
		(sheetfile "supply.kicad_sch")
		(attr smd dnp)
		(fp_line
			(start 0.7 1.5)
			(end -0.7 1.5)
			(stroke
				(width 0.15)
				(type solid)
			)
			(layer "F.SilkS")
		)
		(fp_line
			(start 0.7 0.4)
			(end 0.7 1.5)
			(stroke
				(width 0.15)
				(type solid)
			)
			(layer "F.SilkS")
		)
		(fp_line
			(start 0.7 -0.4)
			(end 0.7 -1.5)
			(stroke
				(width 0.15)
				(type solid)
			)
			(layer "F.SilkS")
		)
		(fp_line
			(start 0.7 -1.5)
			(end -0.7 -1.5)
			(stroke
				(width 0.15)
				(type solid)
			)
			(layer "F.SilkS")
		)
		(fp_line
			(start -0.7 1.5)
			(end -0.7 1.35)
			(stroke
				(width 0.15)
				(type solid)
			)
			(layer "F.SilkS")
		)
		(fp_line
			(start -0.85 -1.35)
			(end -0.7 -1.5)
			(stroke
				(width 0.15)
				(type solid)
			)
			(layer "F.SilkS")
		)
		(fp_line
			(start -1.45 -1.35)
			(end -0.85 -1.35)
			(stroke
				(width 0.15)
				(type solid)
			)
			(layer "F.SilkS")
		)
		(fp_line
			(start 1.75 0.45)
			(end 0.85 0.45)
			(stroke
				(width 0.05)
				(type solid)
			)
			(layer "F.CrtYd")
		)
		(fp_line
			(start 1.75 -0.45)
			(end 1.75 0.45)
			(stroke
				(width 0.05)
				(type solid)
			)
			(layer "F.CrtYd")
		)
		(fp_line
			(start 0.85 1.65)
			(end -0.85 1.65)
			(stroke
				(width 0.05)
				(type solid)
			)
			(layer "F.CrtYd")
		)
		(fp_line
			(start 0.85 0.45)
			(end 0.85 1.65)
			(stroke
				(width 0.05)
				(type solid)
			)
			(layer "F.CrtYd")
		)
		(fp_line
			(start 0.825 -0.45)
			(end 1.75 -0.45)
			(stroke
				(width 0.05)
				(type solid)
			)
			(layer "F.CrtYd")
		)
		(fp_line
			(start 0.825 -1.6)
			(end 0.825 -0.45)
			(stroke
				(width 0.05)
				(type solid)
			)
			(layer "F.CrtYd")
		)
		(fp_line
			(start -0.85 1.65)
			(end -0.85 1.4)
			(stroke
				(width 0.05)
				(type solid)
			)
			(layer "F.CrtYd")
		)
		(fp_line
			(start -0.85 1.4)
			(end -1.75 1.4)
			(stroke
				(width 0.05)
				(type solid)
			)
			(layer "F.CrtYd")
		)
		(fp_line
			(start -0.85 0.5)
			(end -0.85 -0.5)
			(stroke
				(width 0.05)
				(type solid)
			)
			(layer "F.CrtYd")
		)
		(fp_line
			(start -0.85 -0.5)
			(end -1.75 -0.5)
			(stroke
				(width 0.05)
				(type solid)
			)
			(layer "F.CrtYd")
		)
		(fp_line
			(start -0.9 -1.4)
			(end -1.75 -1.4)
			(stroke
				(width 0.05)
				(type solid)
			)
			(layer "F.CrtYd")
		)
		(fp_line
			(start -0.9 -1.6)
			(end 0.825 -1.6)
			(stroke
				(width 0.05)
				(type solid)
			)
			(layer "F.CrtYd")
		)
		(fp_line
			(start -0.9 -1.6)
			(end -0.9 -1.4)
			(stroke
				(width 0.05)
				(type solid)
			)
			(layer "F.CrtYd")
		)
		(fp_line
			(start -1.75 1.4)
			(end -1.75 0.5)
			(stroke
				(width 0.05)
				(type solid)
			)
			(layer "F.CrtYd")
		)
		(fp_line
			(start -1.75 0.5)
			(end -0.85 0.5)
			(stroke
				(width 0.05)
				(type solid)
			)
			(layer "F.CrtYd")
		)
		(fp_line
			(start -1.75 -0.5)
			(end -1.75 -1.4)
			(stroke
				(width 0.05)
				(type solid)
			)
			(layer "F.CrtYd")
		)
		(fp_line
			(start 0.688 1.519)
			(end 0.688 -1.52)
			(stroke
				(width 0.15)
				(type solid)
			)
			(layer "F.Fab")
		)
		(fp_line
			(start -0.437 -1.526)
			(end 0.688 -1.526)
			(stroke
				(width 0.15)
				(type solid)
			)
			(layer "F.Fab")
		)
		(fp_line
			(start -0.437 -1.526)
			(end -0.712 -1.325)
			(stroke
				(width 0.15)
				(type solid)
			)
			(layer "F.Fab")
		)
		(fp_line
			(start -0.712 1.519)
			(end 0.688 1.519)
			(stroke
				(width 0.15)
				(type solid)
			)
			(layer "F.Fab")
		)
		(fp_line
			(start -0.712 -1.325)
			(end -0.712 1.523)
			(stroke
				(width 0.15)
				(type solid)
			)
			(layer "F.Fab")
		)
		(fp_text user "${REFERENCE}"
			(at -1.837 4 0)
			(layer "F.Fab")
			(hide yes)
			(effects
				(font
					(size 0.7 0.7)
					(thickness 0.15)
				)
				(justify right bottom)
			)
		)
		(fp_text user "License: Apache-2.0"
			(at -1.8 6.8 0)
			(layer "F.Fab")
			(hide yes)
			(effects
				(font
					(size 0.7 0.7)
					(thickness 0.15)
				)
				(justify right bottom)
			)
		)
		(fp_text user "Author: Antmicro"
			(at -1.837 5.3 0)
			(layer "F.Fab")
			(hide yes)
			(effects
				(font
					(size 0.7 0.7)
					(thickness 0.15)
				)
				(justify right bottom)
			)
		)
		(pad "1" smd roundrect
			(at -1.1 -0.951 180)
			(size 1 0.6)
			(layers "F.Cu" "F.Paste" "F.Mask")
			(roundrect_rratio 0.15)
			(net 9 "+5V")
			(pinfunction "IN")
			(pintype "power_in")
		)
		(pad "2" smd roundrect
			(at -1.1 0.949 180)
			(size 1 0.6)
			(layers "F.Cu" "F.Paste" "F.Mask")
			(roundrect_rratio 0.15)
			(net 90 "/Serializer/VREF")
			(pinfunction "OUT")
			(pintype "output")
		)
		(pad "3" smd roundrect
			(at 1.1 -0.0005 180)
			(size 1 0.6)
			(layers "F.Cu" "F.Paste" "F.Mask")
			(roundrect_rratio 0.15)
			(net 1 "GND")
			(pinfunction "GND")
			(pintype "passive")
		)
	)
	(footprint "antmicro-footprints:R_0402_1005Metric"
		(layer "F.Cu")
		(at 146.55 115.995 90)
		(descr "Resistor SMD 0402")
		(tags "resistor SMD 0402")
		(property "Reference" "R39"
			(at -2.955 0.275 90)
			(layer "F.SilkS")
			(effects
				(font
					(size 0.7 0.7)
					(thickness 0.15)
				)
				(justify left bottom)
			)
		)
		(property "Value" "R_470R_0402"
			(at -1.011843 1.772047 90)
			(layer "F.Fab")
			(effects
				(font
					(size 0.7 0.7)
					(thickness 0.15)
				)
				(justify left bottom)
			)
		)
		(property "Footprint" "antmicro-footprints:R_0402_1005Metric"
			(at 0 0 90)
			(layer "F.Fab")
			(hide yes)
			(effects
				(font
					(size 1.27 1.27)
					(thickness 0.15)
				)
			)
		)
		(property "Datasheet" "https://www.bourns.com/docs/product-datasheets/cr.pdf"
			(at 0 0 90)
			(layer "F.Fab")
			(hide yes)
			(effects
				(font
					(size 1.27 1.27)
					(thickness 0.15)
				)
			)
		)
		(property "Author" "Antmicro"
			(at 262.545 -30.555 0)
			(layer "F.Fab")
			(hide yes)
			(effects
				(font
					(size 1 1)
					(thickness 0.15)
				)
			)
		)
		(property "License" "Apache-2.0"
			(at 262.545 -30.555 0)
			(layer "F.Fab")
			(hide yes)
			(effects
				(font
					(size 1 1)
					(thickness 0.15)
				)
			)
		)
		(property "MPN" "CR0402-FX-4700GLF"
			(at 262.545 -30.555 0)
			(layer "F.Fab")
			(hide yes)
			(effects
				(font
					(size 1 1)
					(thickness 0.15)
				)
			)
		)
		(property "Manufacturer" "Bourns"
			(at 262.545 -30.555 0)
			(layer "F.Fab")
			(hide yes)
			(effects
				(font
					(size 1 1)
					(thickness 0.15)
				)
			)
		)
		(property "Tolerance" "1%"
			(at 262.545 -30.555 0)
			(layer "F.Fab")
			(hide yes)
			(effects
				(font
					(size 1 1)
					(thickness 0.15)
				)
			)
		)
		(property "Val" "470R"
			(at 262.545 -30.555 0)
			(layer "F.Fab")
			(hide yes)
			(effects
				(font
					(size 1 1)
					(thickness 0.15)
				)
			)
		)
		(sheetname "Supply")
		(sheetfile "supply.kicad_sch")
		(attr smd)
		(fp_rect
			(start -0.925 -0.47)
			(end 0.925 0.47)
			(stroke
				(width 0.05)
				(type default)
			)
			(fill none)
			(layer "F.CrtYd")
		)
		(fp_rect
			(start -0.5 -0.25)
			(end 0.5 0.25)
			(stroke
				(width 0.15)
				(type solid)
			)
			(fill none)
			(layer "F.Fab")
		)
		(fp_text user "Author: Antmicro"
			(at -0.95 4.169 90)
			(layer "F.Fab")
			(hide yes)
			(effects
				(font
					(size 0.7 0.7)
					(thickness 0.15)
				)
				(justify left bottom)
			)
		)
		(fp_text user "License: Apache-2.0"
			(at -0.95 5.169 90)
			(layer "F.Fab")
			(hide yes)
			(effects
				(font
					(size 0.7 0.7)
					(thickness 0.15)
				)
				(justify left bottom)
			)
		)
		(fp_text user "${REFERENCE}"
			(at -0.95 3.168 90)
			(layer "F.Fab")
			(hide yes)
			(effects
				(font
					(size 0.7 0.7)
					(thickness 0.15)
				)
				(justify left bottom)
			)
		)
		(pad "1" smd roundrect
			(at -0.48 0 90)
			(size 0.59 0.64)
			(layers "F.Cu" "F.Paste" "F.Mask")
			(roundrect_rratio 0.25)
			(net 74 "Net-(D8-A)")
			(pintype "passive")
		)
		(pad "2" smd roundrect
			(at 0.48 0 90)
			(size 0.59 0.64)
			(layers "F.Cu" "F.Paste" "F.Mask")
			(roundrect_rratio 0.25)
			(net 9 "+5V")
			(pintype "passive")
		)
	)
	(footprint "antmicro-footprints:R_0402_1005Metric"
		(layer "F.Cu")
		(at 151.775 96.675 -135)
		(descr "Resistor SMD 0402")
		(tags "resistor SMD 0402")
		(property "Reference" "R29"
			(at -2.821356 -0.445477 45)
			(layer "F.SilkS")
			(effects
				(font
					(size 0.7 0.7)
					(thickness 0.15)
				)
				(justify left bottom)
			)
		)
		(property "Value" "R_51R_0402"
			(at -1.011843 1.772046 45)
			(layer "F.Fab")
			(effects
				(font
					(size 0.7 0.7)
					(thickness 0.15)
				)
				(justify right bottom)
			)
		)
		(property "Footprint" "antmicro-footprints:R_0402_1005Metric"
			(at 0 0 -135)
			(layer "F.Fab")
			(hide yes)
			(effects
				(font
					(size 1.27 1.27)
					(thickness 0.15)
				)
			)
		)
		(property "Datasheet" "https://www.bourns.com/docs/product-datasheets/cr.pdf"
			(at 0 0 -135)
			(layer "F.Fab")
			(hide yes)
			(effects
				(font
					(size 1.27 1.27)
					(thickness 0.15)
				)
			)
		)
		(property "Author" "Antmicro"
			(at 190.736584 272.35568 0)
			(layer "F.Fab")
			(hide yes)
			(effects
				(font
					(size 1 1)
					(thickness 0.15)
				)
			)
		)
		(property "License" "Apache-2.0"
			(at 190.736584 272.35568 0)
			(layer "F.Fab")
			(hide yes)
			(effects
				(font
					(size 1 1)
					(thickness 0.15)
				)
			)
		)
		(property "MPN" "CR0402-FX-51R0GLF"
			(at 190.736584 272.35568 0)
			(layer "F.Fab")
			(hide yes)
			(effects
				(font
					(size 1 1)
					(thickness 0.15)
				)
			)
		)
		(property "Manufacturer" "Bourns"
			(at 190.736584 272.35568 0)
			(layer "F.Fab")
			(hide yes)
			(effects
				(font
					(size 1 1)
					(thickness 0.15)
				)
			)
		)
		(property "Tolerance" "1%"
			(at 190.736584 272.35568 0)
			(layer "F.Fab")
			(hide yes)
			(effects
				(font
					(size 1 1)
					(thickness 0.15)
				)
			)
		)
		(property "Val" "51R"
			(at 190.736584 272.35568 0)
			(layer "F.Fab")
			(hide yes)
			(effects
				(font
					(size 1 1)
					(thickness 0.15)
				)
			)
		)
		(sheetname "Serializer")
		(sheetfile "serializer.kicad_sch")
		(attr smd)
		(fp_poly
			(pts
				(xy -0.925 -0.47) (xy 0.925 -0.47) (xy 0.925 0.47) (xy -0.925 0.47)
			)
			(stroke
				(width 0.05)
				(type default)
			)
			(fill none)
			(layer "F.CrtYd")
		)
		(fp_poly
			(pts
				(xy -0.5 -0.25) (xy 0.5 -0.25) (xy 0.5 0.25) (xy -0.5 0.25)
			)
			(stroke
				(width 0.15)
				(type solid)
			)
			(fill none)
			(layer "F.Fab")
		)
		(fp_text user "Author: Antmicro"
			(at -0.95 4.169 45)
			(layer "F.Fab")
			(hide yes)
			(effects
				(font
					(size 0.7 0.7)
					(thickness 0.15)
				)
				(justify right bottom)
			)
		)
		(fp_text user "License: Apache-2.0"
			(at -0.949999 5.169 45)
			(layer "F.Fab")
			(hide yes)
			(effects
				(font
					(size 0.7 0.7)
					(thickness 0.15)
				)
				(justify right bottom)
			)
		)
		(fp_text user "${REFERENCE}"
			(at -0.95 3.168 45)
			(layer "F.Fab")
			(hide yes)
			(effects
				(font
					(size 0.7 0.7)
					(thickness 0.15)
				)
				(justify right bottom)
			)
		)
		(pad "1" smd roundrect
			(at -0.48 0 225)
			(size 0.59 0.64)
			(layers "F.Cu" "F.Paste" "F.Mask")
			(roundrect_rratio 0.25)
			(net 1 "GND")
			(pintype "passive")
		)
		(pad "2" smd roundrect
			(at 0.48 0 225)
			(size 0.59 0.64)
			(layers "F.Cu" "F.Paste" "F.Mask")
			(roundrect_rratio 0.25)
			(net 16 "Net-(C31-Pad2)")
			(pintype "passive")
		)
	)
	(footprint "antmicro-footprints:LED_0603_1608Metric_G"
		(layer "F.Cu")
		(at 139.5 115.75 -90)
		(descr "LED SMD 0603 Green")
		(tags "LED SMD 0603 Green")
		(property "Reference" "D9"
			(at -2.7 -0.5 90)
			(layer "F.SilkS")
			(effects
				(font
					(size 0.7 0.7)
					(thickness 0.15)
				)
				(justify right bottom)
			)
		)
		(property "Value" "LED_G_0603_LTST-C190GKT"
			(at -0.001 1.599 90)
			(layer "F.Fab")
			(effects
				(font
					(size 0.7 0.7)
					(thickness 0.15)
				)
				(justify right bottom)
			)
		)
		(property "Footprint" "antmicro-footprints:LED_0603_1608Metric_G"
			(at 0 0 -90)
			(layer "F.Fab")
			(hide yes)
			(effects
				(font
					(size 1.27 1.27)
					(thickness 0.15)
				)
			)
		)
		(property "Datasheet" "https://media.digikey.com/pdf/Data%20Sheets/Lite-On%20PDFs/LTST-C190GKT.pdf"
			(at 0 0 -90)
			(layer "F.Fab")
			(hide yes)
			(effects
				(font
					(size 1.27 1.27)
					(thickness 0.15)
				)
			)
		)
		(property "Author" "Antmicro"
			(at 23.75 255.25 0)
			(layer "F.Fab")
			(hide yes)
			(effects
				(font
					(size 1 1)
					(thickness 0.15)
				)
			)
		)
		(property "Color" "Green"
			(at 23.75 255.25 0)
			(layer "F.Fab")
			(hide yes)
			(effects
				(font
					(size 1 1)
					(thickness 0.15)
				)
			)
		)
		(property "License" "Apache-2.0"
			(at 23.75 255.25 0)
			(layer "F.Fab")
			(hide yes)
			(effects
				(font
					(size 1 1)
					(thickness 0.15)
				)
			)
		)
		(property "MPN" "LTST-C190GKT"
			(at 23.75 255.25 0)
			(layer "F.Fab")
			(hide yes)
			(effects
				(font
					(size 1 1)
					(thickness 0.15)
				)
			)
		)
		(property "Manufacturer" "Lite-On"
			(at 23.75 255.25 0)
			(layer "F.Fab")
			(hide yes)
			(effects
				(font
					(size 1 1)
					(thickness 0.15)
				)
			)
		)
		(property "VSD_class" "LED"
			(at 23.75 255.25 0)
			(layer "F.Fab")
			(hide yes)
			(effects
				(font
					(size 1 1)
					(thickness 0.15)
				)
			)
		)
		(sheetname "Supply")
		(sheetfile "supply.kicad_sch")
		(attr smd)
		(fp_line
			(start 0.22 0.35)
			(end -0.22 0.35)
			(stroke
				(width 0.15)
				(type solid)
			)
			(layer "F.SilkS")
		)
		(fp_line
			(start -0.094672 0.201008)
			(end -0.094672 -0.198992)
			(stroke
				(width 0.1)
				(type solid)
			)
			(layer "F.SilkS")
		)
		(fp_line
			(start 0.105328 0.201008)
			(end -0.094672 0.001008)
			(stroke
				(width 0.1)
				(type solid)
			)
			(layer "F.SilkS")
		)
		(fp_line
			(start 0.105328 0.201008)
			(end 0.105328 -0.198992)
			(stroke
				(width 0.1)
				(type solid)
			)
			(layer "F.SilkS")
		)
		(fp_line
			(start -0.094672 0.001008)
			(end -0.24 0.001008)
			(stroke
				(width 0.1)
				(type solid)
			)
			(layer "F.SilkS")
		)
		(fp_line
			(start -0.094672 0.001008)
			(end 0.105328 -0.198992)
			(stroke
				(width 0.1)
				(type solid)
			)
			(layer "F.SilkS")
		)
		(fp_line
			(start 0.105328 0.001008)
			(end 0.24 0.001)
			(stroke
				(width 0.1)
				(type solid)
			)
			(layer "F.SilkS")
		)
		(fp_line
			(start -1.18 -0.319)
			(end -1.18 0.321)
			(stroke
				(width 0.15)
				(type solid)
			)
			(layer "F.SilkS")
		)
		(fp_line
			(start 0.22 -0.35)
			(end -0.22 -0.35)
			(stroke
				(width 0.15)
				(type solid)
			)
			(layer "F.SilkS")
		)
		(fp_rect
			(start 1.25 0.65)
			(end -1.25 -0.65)
			(stroke
				(width 0.05)
				(type solid)
			)
			(fill none)
			(layer "F.CrtYd")
		)
		(fp_line
			(start -0.199 0.2)
			(end -0.199 0.1)
			(stroke
				(width 0.15)
				(type solid)
			)
			(layer "F.Fab")
		)
		(fp_line
			(start 0.201 0.2)
			(end 0.201 0)
			(stroke
				(width 0.15)
				(type solid)
			)
			(layer "F.Fab")
		)
		(fp_line
			(start -0.199 0)
			(end -0.597 0)
			(stroke
				(width 0.15)
				(type solid)
			)
			(layer "F.Fab")
		)
		(fp_line
			(start -0.101 0)
			(end 0.201 0.2)
			(stroke
				(width 0.15)
				(type solid)
			)
			(layer "F.Fab")
		)
		(fp_line
			(start 0.201 0)
			(end 0.201 -0.202)
			(stroke
				(width 0.15)
				(type solid)
			)
			(layer "F.Fab")
		)
		(fp_line
			(start 0.599 0)
			(end 0.201 0)
			(stroke
				(width 0.15)
				(type solid)
			)
			(layer "F.Fab")
		)
		(fp_line
			(start -0.199 -0.202)
			(end -0.199 0.1)
			(stroke
				(width 0.15)
				(type solid)
			)
			(layer "F.Fab")
		)
		(fp_line
			(start 0.201 -0.202)
			(end -0.101 0)
			(stroke
				(width 0.15)
				(type solid)
			)
			(layer "F.Fab")
		)
		(fp_rect
			(start 0.848 0.4)
			(end -0.85 -0.402)
			(stroke
				(width 0.15)
				(type solid)
			)
			(fill none)
			(layer "F.Fab")
		)
		(fp_text user "Author: Antmicro"
			(at -1.4224 4.799 90)
			(layer "F.Fab")
			(hide yes)
			(effects
				(font
					(size 0.7 0.7)
					(thickness 0.15)
				)
				(justify right bottom)
			)
		)
		(fp_text user "${REFERENCE}"
			(at -1.4224 5.999 90)
			(layer "F.Fab")
			(hide yes)
			(effects
				(font
					(size 0.7 0.7)
					(thickness 0.15)
				)
				(justify right bottom)
			)
		)
		(fp_text user "License: Apache-2.0"
			(at -1.4224 3.599 90)
			(layer "F.Fab")
			(hide yes)
			(effects
				(font
					(size 0.7 0.7)
					(thickness 0.15)
				)
				(justify right bottom)
			)
		)
		(pad "1" smd roundrect
			(at -0.7 0 90)
			(size 0.8 1)
			(layers "F.Cu" "F.Paste" "F.Mask")
			(roundrect_rratio 0.2)
			(net 75 "Net-(D9-C)")
			(pinfunction "C")
			(pintype "passive")
		)
		(pad "2" smd roundrect
			(at 0.7 0 90)
			(size 0.8 1)
			(layers "F.Cu" "F.Paste" "F.Mask")
			(roundrect_rratio 0.2)
			(net 2 "+12V")
			(pinfunction "A")
			(pintype "passive")
		)
	)
	(footprint "antmicro-footprints:Conn_FFC_WE_68715014x22"
		(locked yes)
		(layer "F.Cu")
		(at 126.2 101.85 -90)
		(property "Reference" "J1"
			(at -16.45 0 180)
			(layer "F.SilkS")
			(effects
				(font
					(size 0.7 0.7)
					(thickness 0.15)
				)
				(justify right bottom)
			)
		)
		(property "Value" "Conn_FFC_WE_68715014022"
			(at 0 4.5 90)
			(layer "F.Fab")
			(effects
				(font
					(size 0.7 0.7)
					(thickness 0.15)
				)
				(justify right bottom)
			)
		)
		(property "Footprint" "antmicro-footprints:Conn_FFC_WE_68715014x22"
			(at 0 0 -90)
			(layer "F.Fab")
			(hide yes)
			(effects
				(font
					(size 1.27 1.27)
					(thickness 0.15)
				)
			)
		)
		(property "Datasheet" "https://www.we-online.com/components/products/datasheet/68715014022.pdf"
			(at 0 0 -90)
			(layer "F.Fab")
			(hide yes)
			(effects
				(font
					(size 1.27 1.27)
					(thickness 0.15)
				)
			)
		)
		(property "Author" "Antmicro"
			(at 24.35 228.05 0)
			(layer "F.Fab")
			(hide yes)
			(effects
				(font
					(size 1 1)
					(thickness 0.15)
				)
			)
		)
		(property "License" "Apache-2.0"
			(at 24.35 228.05 0)
			(layer "F.Fab")
			(hide yes)
			(effects
				(font
					(size 1 1)
					(thickness 0.15)
				)
			)
		)
		(property "MPN" "68715014022"
			(at 24.35 228.05 0)
			(layer "F.Fab")
			(hide yes)
			(effects
				(font
					(size 1 1)
					(thickness 0.15)
				)
			)
		)
		(property "Manufacturer" "Würth Elektronik"
			(at 24.35 228.05 0)
			(layer "F.Fab")
			(hide yes)
			(effects
				(font
					(size 1 1)
					(thickness 0.15)
				)
			)
		)
		(sheetname "CSI Connector")
		(sheetfile "CSI.kicad_sch")
		(attr smd)
		(fp_line
			(start -15.85 2.7)
			(end -15.85 -2.15)
			(stroke
				(width 0.15)
				(type solid)
			)
			(layer "F.SilkS")
		)
		(fp_line
			(start 15.85 2.7)
			(end -15.85 2.7)
			(stroke
				(width 0.15)
				(type solid)
			)
			(layer "F.SilkS")
		)
		(fp_line
			(start 15.85 2.7)
			(end 15.85 -2.15)
			(stroke
				(width 0.15)
				(type solid)
			)
			(layer "F.SilkS")
		)
		(fp_line
			(start -15.85 -2.15)
			(end -12.5 -2.15)
			(stroke
				(width 0.15)
				(type solid)
			)
			(layer "F.SilkS")
		)
		(fp_line
			(start -12.5 -2.15)
			(end -12.5 -2.976)
			(stroke
				(width 0.15)
				(type solid)
			)
			(layer "F.SilkS")
		)
		(fp_line
			(start 12.499 -2.15)
			(end 12.499 -2.976)
			(stroke
				(width 0.15)
				(type solid)
			)
			(layer "F.SilkS")
		)
		(fp_line
			(start 15.85 -2.15)
			(end 12.499 -2.15)
			(stroke
				(width 0.15)
				(type solid)
			)
			(layer "F.SilkS")
		)
		(fp_line
			(start -12.5 -2.976)
			(end 12.499 -2.976)
			(stroke
				(width 0.15)
				(type solid)
			)
			(layer "F.SilkS")
		)
		(fp_circle
			(center -12.9 -2.9)
			(end -12.85 -2.85)
			(stroke
				(width 0.15)
				(type solid)
			)
			(fill solid)
			(layer "F.SilkS")
		)
		(fp_rect
			(start -16.2 -3.25)
			(end 16.2 3.55)
			(stroke
				(width 0.05)
				(type solid)
			)
			(fill none)
			(layer "F.CrtYd")
		)
		(fp_text user "License: Apache-2.0"
			(at -16.2 7.9 90)
			(layer "F.Fab")
			(hide yes)
			(effects
				(font
					(size 0.7 0.7)
					(thickness 0.15)
				)
				(justify right bottom)
			)
		)
		(fp_text user "${REFERENCE}"
			(at -16.2 5.9 90)
			(layer "F.Fab")
			(hide yes)
			(effects
				(font
					(size 0.7 0.7)
					(thickness 0.15)
				)
				(justify right bottom)
			)
		)
		(fp_text user "Author: Antmicro"
			(at -16.2 6.9 90)
			(layer "F.Fab")
			(hide yes)
			(effects
				(font
					(size 0.7 0.7)
					(thickness 0.15)
				)
				(justify right bottom)
			)
		)
		(pad "1" smd roundrect
			(at -12.25 -2.15 270)
			(size 0.3 1.2)
			(layers "F.Cu" "F.Paste" "F.Mask")
			(roundrect_rratio 0.25)
			(net 19 "unconnected-(J1-Pad1)")
			(pintype "passive+no_connect")
		)
		(pad "2" smd roundrect
			(at -11.75 -2.15 270)
			(size 0.3 1.2)
			(layers "F.Cu" "F.Paste" "F.Mask")
			(roundrect_rratio 0.25)
			(net 20 "unconnected-(J1-Pad2)")
			(pintype "passive+no_connect")
		)
		(pad "3" smd roundrect
			(at -11.25 -2.15 270)
			(size 0.3 1.2)
			(layers "F.Cu" "F.Paste" "F.Mask")
			(roundrect_rratio 0.25)
			(net 21 "unconnected-(J1-Pad3)")
			(pintype "passive+no_connect")
		)
		(pad "4" smd roundrect
			(at -10.75 -2.15 270)
			(size 0.3 1.2)
			(layers "F.Cu" "F.Paste" "F.Mask")
			(roundrect_rratio 0.25)
			(net 22 "unconnected-(J1-Pad4)")
			(pintype "passive+no_connect")
		)
		(pad "5" smd roundrect
			(at -10.25 -2.15 270)
			(size 0.3 1.2)
			(layers "F.Cu" "F.Paste" "F.Mask")
			(roundrect_rratio 0.25)
			(net 23 "unconnected-(J1-Pad5)")
			(pintype "passive+no_connect")
		)
		(pad "6" smd roundrect
			(at -9.75 -2.15 270)
			(size 0.3 1.2)
			(layers "F.Cu" "F.Paste" "F.Mask")
			(roundrect_rratio 0.25)
			(net 24 "unconnected-(J1-Pad6)")
			(pintype "passive+no_connect")
		)
		(pad "7" smd roundrect
			(at -9.25 -2.15 270)
			(size 0.3 1.2)
			(layers "F.Cu" "F.Paste" "F.Mask")
			(roundrect_rratio 0.25)
			(net 25 "unconnected-(J1-Pad7)")
			(pintype "passive+no_connect")
		)
		(pad "8" smd roundrect
			(at -8.75 -2.15 270)
			(size 0.3 1.2)
			(layers "F.Cu" "F.Paste" "F.Mask")
			(roundrect_rratio 0.25)
			(net 26 "unconnected-(J1-Pad8)")
			(pintype "passive+no_connect")
		)
		(pad "9" smd roundrect
			(at -8.25 -2.15 270)
			(size 0.3 1.2)
			(layers "F.Cu" "F.Paste" "F.Mask")
			(roundrect_rratio 0.25)
			(net 1 "GND")
			(pintype "passive")
		)
		(pad "10" smd roundrect
			(at -7.75 -2.15 270)
			(size 0.3 1.2)
			(layers "F.Cu" "F.Paste" "F.Mask")
			(roundrect_rratio 0.25)
			(net 27 "unconnected-(J1-Pad10)")
			(pintype "passive+no_connect")
		)
		(pad "11" smd roundrect
			(at -7.25 -2.15 270)
			(size 0.3 1.2)
			(layers "F.Cu" "F.Paste" "F.Mask")
			(roundrect_rratio 0.25)
			(net 28 "unconnected-(J1-Pad11)")
			(pintype "passive+no_connect")
		)
		(pad "12" smd roundrect
			(at -6.75 -2.15 270)
			(size 0.3 1.2)
			(layers "F.Cu" "F.Paste" "F.Mask")
			(roundrect_rratio 0.25)
			(net 1 "GND")
			(pintype "passive")
		)
		(pad "13" smd roundrect
			(at -6.25 -2.15 270)
			(size 0.3 1.2)
			(layers "F.Cu" "F.Paste" "F.Mask")
			(roundrect_rratio 0.25)
			(net 29 "unconnected-(J1-Pad13)")
			(pintype "passive+no_connect")
		)
		(pad "14" smd roundrect
			(at -5.75 -2.15 270)
			(size 0.3 1.2)
			(layers "F.Cu" "F.Paste" "F.Mask")
			(roundrect_rratio 0.25)
			(net 30 "unconnected-(J1-Pad14)")
			(pintype "passive+no_connect")
		)
		(pad "15" smd roundrect
			(at -5.25 -2.15 270)
			(size 0.3 1.2)
			(layers "F.Cu" "F.Paste" "F.Mask")
			(roundrect_rratio 0.25)
			(net 1 "GND")
			(pintype "passive")
		)
		(pad "16" smd roundrect
			(at -4.75 -2.15 270)
			(size 0.3 1.2)
			(layers "F.Cu" "F.Paste" "F.Mask")
			(roundrect_rratio 0.25)
			(net 31 "unconnected-(J1-Pad16)")
			(pintype "passive+no_connect")
		)
		(pad "17" smd roundrect
			(at -4.25 -2.15 270)
			(size 0.3 1.2)
			(layers "F.Cu" "F.Paste" "F.Mask")
			(roundrect_rratio 0.25)
			(net 32 "unconnected-(J1-Pad17)")
			(pintype "passive+no_connect")
		)
		(pad "18" smd roundrect
			(at -3.75 -2.15 270)
			(size 0.3 1.2)
			(layers "F.Cu" "F.Paste" "F.Mask")
			(roundrect_rratio 0.25)
			(net 1 "GND")
			(pintype "passive")
		)
		(pad "19" smd roundrect
			(at -3.25 -2.15 270)
			(size 0.3 1.2)
			(layers "F.Cu" "F.Paste" "F.Mask")
			(roundrect_rratio 0.25)
			(net 40 "/CSI Connector/CSI.D3_N")
			(pintype "passive")
		)
		(pad "20" smd roundrect
			(at -2.75 -2.15 270)
			(size 0.3 1.2)
			(layers "F.Cu" "F.Paste" "F.Mask")
			(roundrect_rratio 0.25)
			(net 41 "/CSI Connector/CSI.D3_P")
			(pintype "passive")
		)
		(pad "21" smd roundrect
			(at -2.25 -2.15 270)
			(size 0.3 1.2)
			(layers "F.Cu" "F.Paste" "F.Mask")
			(roundrect_rratio 0.25)
			(net 42 "/CSI Connector/CSI.D2_N")
			(pintype "passive")
		)
		(pad "22" smd roundrect
			(at -1.75 -2.15 270)
			(size 0.3 1.2)
			(layers "F.Cu" "F.Paste" "F.Mask")
			(roundrect_rratio 0.25)
			(net 44 "/CSI Connector/CSI.D2_P")
			(pintype "passive")
		)
		(pad "23" smd roundrect
			(at -1.25 -2.15 270)
			(size 0.3 1.2)
			(layers "F.Cu" "F.Paste" "F.Mask")
			(roundrect_rratio 0.25)
			(net 50 "/CSI Connector/CSI.D1_N")
			(pintype "passive")
		)
		(pad "24" smd roundrect
			(at -0.75 -2.15 270)
			(size 0.3 1.2)
			(layers "F.Cu" "F.Paste" "F.Mask")
			(roundrect_rratio 0.25)
			(net 51 "/CSI Connector/CSI.D1_P")
			(pintype "passive")
		)
		(pad "25" smd roundrect
			(at -0.25 -2.15 270)
			(size 0.3 1.2)
			(layers "F.Cu" "F.Paste" "F.Mask")
			(roundrect_rratio 0.25)
			(net 56 "/CSI Connector/CSI.D0_N")
			(pintype "passive")
		)
		(pad "26" smd roundrect
			(at 0.248 -2.15 270)
			(size 0.3 1.2)
			(layers "F.Cu" "F.Paste" "F.Mask")
			(roundrect_rratio 0.25)
			(net 57 "/CSI Connector/CSI.D0_P")
			(pintype "passive")
		)
		(pad "27" smd roundrect
			(at 0.748 -2.15 270)
			(size 0.3 1.2)
			(layers "F.Cu" "F.Paste" "F.Mask")
			(roundrect_rratio 0.25)
			(net 1 "GND")
			(pintype "passive")
		)
		(pad "28" smd roundrect
			(at 1.249 -2.15 270)
			(size 0.3 1.2)
			(layers "F.Cu" "F.Paste" "F.Mask")
			(roundrect_rratio 0.25)
			(net 61 "/CSI Connector/CSI.CLK_N")
			(pintype "passive")
		)
		(pad "29" smd roundrect
			(at 1.749 -2.15 270)
			(size 0.3 1.2)
			(layers "F.Cu" "F.Paste" "F.Mask")
			(roundrect_rratio 0.25)
			(net 80 "/CSI Connector/CSI.CLK_P")
			(pintype "passive")
		)
		(pad "30" smd roundrect
			(at 2.249 -2.15 270)
			(size 0.3 1.2)
			(layers "F.Cu" "F.Paste" "F.Mask")
			(roundrect_rratio 0.25)
			(net 1 "GND")
			(pintype "passive")
		)
		(pad "31" smd roundrect
			(at 2.749 -2.15 270)
			(size 0.3 1.2)
			(layers "F.Cu" "F.Paste" "F.Mask")
			(roundrect_rratio 0.25)
			(net 43 "unconnected-(J1-Pad31)")
			(pintype "passive+no_connect")
		)
		(pad "32" smd roundrect
			(at 3.249 -2.15 270)
			(size 0.3 1.2)
			(layers "F.Cu" "F.Paste" "F.Mask")
			(roundrect_rratio 0.25)
			(net 38 "/CSI Connector/GPIO3")
			(pintype "passive")
		)
		(pad "33" smd roundrect
			(at 3.749 -2.15 270)
			(size 0.3 1.2)
			(layers "F.Cu" "F.Paste" "F.Mask")
			(roundrect_rratio 0.25)
			(net 45 "unconnected-(J1-Pad33)")
			(pintype "passive+no_connect")
		)
		(pad "34" smd roundrect
			(at 4.248 -2.15 270)
			(size 0.3 1.2)
			(layers "F.Cu" "F.Paste" "F.Mask")
			(roundrect_rratio 0.25)
			(net 39 "/CSI Connector/GPIO4_1V8")
			(pintype "passive")
		)
		(pad "35" smd roundrect
			(at 4.748 -2.15 270)
			(size 0.3 1.2)
			(layers "F.Cu" "F.Paste" "F.Mask")
			(roundrect_rratio 0.25)
			(net 46 "unconnected-(J1-Pad35)")
			(pintype "passive+no_connect")
		)
		(pad "36" smd roundrect
			(at 5.248 -2.15 270)
			(size 0.3 1.2)
			(layers "F.Cu" "F.Paste" "F.Mask")
			(roundrect_rratio 0.25)
			(net 47 "unconnected-(J1-Pad36)")
			(pintype "passive+no_connect")
		)
		(pad "37" smd roundrect
			(at 5.749 -2.15 270)
			(size 0.3 1.2)
			(layers "F.Cu" "F.Paste" "F.Mask")
			(roundrect_rratio 0.25)
			(net 48 "unconnected-(J1-Pad37)")
			(pintype "passive+no_connect")
		)
		(pad "38" smd roundrect
			(at 6.249 -2.15 270)
			(size 0.3 1.2)
			(layers "F.Cu" "F.Paste" "F.Mask")
			(roundrect_rratio 0.25)
			(net 49 "unconnected-(J1-Pad38)")
			(pintype "passive+no_connect")
		)
		(pad "39" smd roundrect
			(at 6.749 -2.15 270)
			(size 0.3 1.2)
			(layers "F.Cu" "F.Paste" "F.Mask")
			(roundrect_rratio 0.25)
			(net 34 "/CSI Connector/SDA_CAM0")
			(pintype "passive")
		)
		(pad "40" smd roundrect
			(at 7.249 -2.15 270)
			(size 0.3 1.2)
			(layers "F.Cu" "F.Paste" "F.Mask")
			(roundrect_rratio 0.25)
			(net 35 "/CSI Connector/SCL_CAM0")
			(pintype "passive")
		)
		(pad "41" smd roundrect
			(at 7.749 -2.15 270)
			(size 0.3 1.2)
			(layers "F.Cu" "F.Paste" "F.Mask")
			(roundrect_rratio 0.25)
			(net 36 "/CSI Connector/SDA_CAM1")
			(pintype "passive")
		)
		(pad "42" smd roundrect
			(at 8.249 -2.15 270)
			(size 0.3 1.2)
			(layers "F.Cu" "F.Paste" "F.Mask")
			(roundrect_rratio 0.25)
			(net 37 "/CSI Connector/SCL_CAM1")
			(pintype "passive")
		)
		(pad "43" smd roundrect
			(at 8.749 -2.15 270)
			(size 0.3 1.2)
			(layers "F.Cu" "F.Paste" "F.Mask")
			(roundrect_rratio 0.25)
			(net 52 "unconnected-(J1-Pad43)")
			(pintype "passive+no_connect")
		)
		(pad "44" smd roundrect
			(at 9.249 -2.15 270)
			(size 0.3 1.2)
			(layers "F.Cu" "F.Paste" "F.Mask")
			(roundrect_rratio 0.25)
			(net 53 "unconnected-(J1-Pad44)")
			(pintype "passive+no_connect")
		)
		(pad "45" smd roundrect
			(at 9.749 -2.15 270)
			(size 0.3 1.2)
			(layers "F.Cu" "F.Paste" "F.Mask")
			(roundrect_rratio 0.25)
			(net 54 "unconnected-(J1-Pad45)")
			(pintype "passive+no_connect")
		)
		(pad "46" smd roundrect
			(at 10.249 -2.15 270)
			(size 0.3 1.2)
			(layers "F.Cu" "F.Paste" "F.Mask")
			(roundrect_rratio 0.25)
			(net 55 "unconnected-(J1-Pad46)")
			(pintype "passive+no_connect")
		)
		(pad "47" smd roundrect
			(at 10.749 -2.15 270)
			(size 0.3 1.2)
			(layers "F.Cu" "F.Paste" "F.Mask")
			(roundrect_rratio 0.25)
			(net 10 "+3V3")
			(pintype "passive")
		)
		(pad "48" smd roundrect
			(at 11.249 -2.15 270)
			(size 0.3 1.2)
			(layers "F.Cu" "F.Paste" "F.Mask")
			(roundrect_rratio 0.25)
			(net 10 "+3V3")
			(pintype "passive")
		)
		(pad "49" smd roundrect
			(at 11.749 -2.15 270)
			(size 0.3 1.2)
			(layers "F.Cu" "F.Paste" "F.Mask")
			(roundrect_rratio 0.25)
			(net 9 "+5V")
			(pintype "passive")
		)
		(pad "50" smd roundrect
			(at 12.249 -2.15 270)
			(size 0.3 1.2)
			(layers "F.Cu" "F.Paste" "F.Mask")
			(roundrect_rratio 0.25)
			(net 9 "+5V")
			(pintype "passive")
		)
		(pad "MP1" smd roundrect
			(at -14.198 -0.3 270)
			(size 2.7 3)
			(layers "F.Cu" "F.Paste" "F.Mask")
			(roundrect_rratio 0.05)
			(net 1 "GND")
			(pinfunction "MP")
			(pintype "passive")
		)
		(pad "MP2" smd roundrect
			(at 14.198 -0.3 270)
			(size 2.7 3)
			(layers "F.Cu" "F.Paste" "F.Mask")
			(roundrect_rratio 0.05)
			(net 1 "GND")
			(pinfunction "MP")
			(pintype "passive")
		)
	)
	(footprint "antmicro-footprints:C_0402_1005Metric"
		(layer "F.Cu")
		(at 150.22 96.22 -45)
		(descr "Capacitor SMD 0402")
		(tags "capacitor SMD 0402")
		(property "Reference" "C18"
			(at 0.954594 -2.439518 -45)
			(unlocked yes)
			(layer "F.SilkS")
			(effects
				(font
					(size 0.7 0.7)
					(thickness 0.15)
				)
				(justify right bottom)
			)
		)
		(property "Value" "C_10u_0402"
			(at -1.022927 2.155213 135)
			(layer "F.Fab")
			(effects
				(font
					(size 0.7 0.7)
					(thickness 0.15)
				)
				(justify right bottom)
			)
		)
		(property "Footprint" "antmicro-footprints:C_0402_1005Metric"
			(at 0 0 -45)
			(layer "F.Fab")
			(hide yes)
			(effects
				(font
					(size 1.27 1.27)
					(thickness 0.15)
				)
			)
		)
		(property "Datasheet" "https://www.yageo.com/en/Chart/Download/pdf/CC0402MRX5R5BB106"
			(at 0 0 -45)
			(layer "F.Fab")
			(hide yes)
			(effects
				(font
					(size 1.27 1.27)
					(thickness 0.15)
				)
			)
		)
		(property "Author" "Antmicro"
			(at -24.039395 134.403766 0)
			(layer "F.Fab")
			(hide yes)
			(effects
				(font
					(size 1 1)
					(thickness 0.15)
				)
			)
		)
		(property "Dielectric" ""
			(at -24.039395 134.403766 0)
			(layer "F.Fab")
			(hide yes)
			(effects
				(font
					(size 1 1)
					(thickness 0.15)
				)
			)
		)
		(property "License" "Apache-2.0"
			(at -24.039395 134.403766 0)
			(layer "F.Fab")
			(hide yes)
			(effects
				(font
					(size 1 1)
					(thickness 0.15)
				)
			)
		)
		(property "MPN" "CC0402MRX5R5BB106"
			(at -24.039395 134.403766 0)
			(layer "F.Fab")
			(hide yes)
			(effects
				(font
					(size 1 1)
					(thickness 0.15)
				)
			)
		)
		(property "Manufacturer" "YAGEO"
			(at -24.039395 134.403766 0)
			(layer "F.Fab")
			(hide yes)
			(effects
				(font
					(size 1 1)
					(thickness 0.15)
				)
			)
		)
		(property "Val" "10u"
			(at -24.039395 134.403766 0)
			(layer "F.Fab")
			(hide yes)
			(effects
				(font
					(size 1 1)
					(thickness 0.15)
				)
			)
		)
		(property "Voltage" ""
			(at -24.039395 134.403766 0)
			(layer "F.Fab")
			(hide yes)
			(effects
				(font
					(size 1 1)
					(thickness 0.15)
				)
			)
		)
		(sheetname "Serializer")
		(sheetfile "serializer.kicad_sch")
		(attr smd)
		(fp_poly
			(pts
				(xy -0.925 -0.47) (xy 0.925 -0.47) (xy 0.925 0.47) (xy -0.925 0.47)
			)
			(stroke
				(width 0.05)
				(type default)
			)
			(fill none)
			(layer "F.CrtYd")
		)
		(fp_line
			(start -0.494 0.248)
			(end -0.494 -0.25)
			(stroke
				(width 0.15)
				(type solid)
			)
			(layer "F.Fab")
		)
		(fp_line
			(start -0.494 -0.25)
			(end 0.504 -0.25)
			(stroke
				(width 0.15)
				(type solid)
			)
			(layer "F.Fab")
		)
		(fp_line
			(start 0.504 0.248)
			(end -0.494 0.248)
			(stroke
				(width 0.15)
				(type solid)
			)
			(layer "F.Fab")
		)
		(fp_line
			(start 0.504 -0.25)
			(end 0.504 0.248)
			(stroke
				(width 0.15)
				(type solid)
			)
			(layer "F.Fab")
		)
		(fp_text user "${REFERENCE}"
			(at -0.939 4.599 135)
			(layer "F.Fab")
			(hide yes)
			(effects
				(font
					(size 0.7 0.7)
					(thickness 0.15)
				)
				(justify right bottom)
			)
		)
		(fp_text user "License: Apache-2.0"
			(at -0.939 5.799 135)
			(layer "F.Fab")
			(hide yes)
			(effects
				(font
					(size 0.7 0.7)
					(thickness 0.15)
				)
				(justify right bottom)
			)
		)
		(fp_text user "Author: Antmicro"
			(at -0.939 3.399 135)
			(layer "F.Fab")
			(hide yes)
			(effects
				(font
					(size 0.7 0.7)
					(thickness 0.15)
				)
				(justify right bottom)
			)
		)
		(pad "1" smd roundrect
			(at -0.48 0 315)
			(size 0.59 0.64)
			(layers "F.Cu" "F.Paste" "F.Mask")
			(roundrect_rratio 0.25)
			(net 1 "GND")
			(pintype "passive")
		)
		(pad "2" smd roundrect
			(at 0.48 0 315)
			(size 0.59 0.64)
			(layers "F.Cu" "F.Paste" "F.Mask")
			(roundrect_rratio 0.25)
			(net 12 "+1V2")
			(pintype "passive")
		)
	)
	(footprint "antmicro-footprints:C_0402_1005Metric"
		(layer "F.Cu")
		(at 165.425 103.2 -90)
		(descr "Capacitor SMD 0402")
		(tags "capacitor SMD 0402")
		(property "Reference" "C8"
			(at 0.67 -0.49 90)
			(layer "F.SilkS")
			(effects
				(font
					(size 0.7 0.7)
					(thickness 0.15)
				)
				(justify right bottom)
			)
		)
		(property "Value" "C_22u_0402"
			(at -1.022927 2.155213 90)
			(layer "F.Fab")
			(effects
				(font
					(size 0.7 0.7)
					(thickness 0.15)
				)
				(justify right bottom)
			)
		)
		(property "Footprint" "antmicro-footprints:C_0402_1005Metric"
			(at 0 0 -90)
			(layer "F.Fab")
			(hide yes)
			(effects
				(font
					(size 1.27 1.27)
					(thickness 0.15)
				)
			)
		)
		(property "Datasheet" "https://www.murata.com/products/productdetail?partno=GRM158R60J226ME01%23"
			(at 0 0 -90)
			(layer "F.Fab")
			(hide yes)
			(effects
				(font
					(size 1.27 1.27)
					(thickness 0.15)
				)
			)
		)
		(property "Author" "Antmicro"
			(at 62.225 268.625 0)
			(layer "F.Fab")
			(hide yes)
			(effects
				(font
					(size 1 1)
					(thickness 0.15)
				)
			)
		)
		(property "Dielectric" ""
			(at 62.225 268.625 0)
			(layer "F.Fab")
			(hide yes)
			(effects
				(font
					(size 1 1)
					(thickness 0.15)
				)
			)
		)
		(property "License" "Apache-2.0"
			(at 62.225 268.625 0)
			(layer "F.Fab")
			(hide yes)
			(effects
				(font
					(size 1 1)
					(thickness 0.15)
				)
			)
		)
		(property "MPN" "GRM158R60J226ME01D"
			(at 62.225 268.625 0)
			(layer "F.Fab")
			(hide yes)
			(effects
				(font
					(size 1 1)
					(thickness 0.15)
				)
			)
		)
		(property "Manufacturer" "Murata"
			(at 62.225 268.625 0)
			(layer "F.Fab")
			(hide yes)
			(effects
				(font
					(size 1 1)
					(thickness 0.15)
				)
			)
		)
		(property "Val" "22u"
			(at 62.225 268.625 0)
			(layer "F.Fab")
			(hide yes)
			(effects
				(font
					(size 1 1)
					(thickness 0.15)
				)
			)
		)
		(property "Voltage" ""
			(at 62.225 268.625 0)
			(layer "F.Fab")
			(hide yes)
			(effects
				(font
					(size 1 1)
					(thickness 0.15)
				)
			)
		)
		(sheetname "Supply")
		(sheetfile "supply.kicad_sch")
		(attr smd)
		(fp_rect
			(start -0.925 -0.47)
			(end 0.925 0.47)
			(stroke
				(width 0.05)
				(type default)
			)
			(fill none)
			(layer "F.CrtYd")
		)
		(fp_line
			(start -0.494 0.248)
			(end -0.494 -0.25)
			(stroke
				(width 0.15)
				(type solid)
			)
			(layer "F.Fab")
		)
		(fp_line
			(start 0.504 0.248)
			(end -0.494 0.248)
			(stroke
				(width 0.15)
				(type solid)
			)
			(layer "F.Fab")
		)
		(fp_line
			(start -0.494 -0.25)
			(end 0.504 -0.25)
			(stroke
				(width 0.15)
				(type solid)
			)
			(layer "F.Fab")
		)
		(fp_line
			(start 0.504 -0.25)
			(end 0.504 0.248)
			(stroke
				(width 0.15)
				(type solid)
			)
			(layer "F.Fab")
		)
		(fp_text user "License: Apache-2.0"
			(at -0.939 5.799 90)
			(layer "F.Fab")
			(hide yes)
			(effects
				(font
					(size 0.7 0.7)
					(thickness 0.15)
				)
				(justify right bottom)
			)
		)
		(fp_text user "${REFERENCE}"
			(at -0.939 4.599 90)
			(layer "F.Fab")
			(hide yes)
			(effects
				(font
					(size 0.7 0.7)
					(thickness 0.15)
				)
				(justify right bottom)
			)
		)
		(fp_text user "Author: Antmicro"
			(at -0.939 3.399 90)
			(layer "F.Fab")
			(hide yes)
			(effects
				(font
					(size 0.7 0.7)
					(thickness 0.15)
				)
				(justify right bottom)
			)
		)
		(pad "1" smd roundrect
			(at -0.48 0 270)
			(size 0.59 0.64)
			(layers "F.Cu" "F.Paste" "F.Mask")
			(roundrect_rratio 0.25)
			(net 1 "GND")
			(pintype "passive")
		)
		(pad "2" smd roundrect
			(at 0.48 0 270)
			(size 0.59 0.64)
			(layers "F.Cu" "F.Paste" "F.Mask")
			(roundrect_rratio 0.25)
			(net 8 "/Supply/OUT_1V8")
			(pintype "passive")
		)
	)
	(footprint "antmicro-footprints:R_0402_1005Metric"
		(layer "F.Cu")
		(at 158.267 96.878 180)
		(descr "Resistor SMD 0402")
		(tags "resistor SMD 0402")
		(property "Reference" "R17"
			(at 0.882 -0.352 0)
			(layer "F.SilkS")
			(effects
				(font
					(size 0.7 0.7)
					(thickness 0.15)
				)
				(justify right bottom)
			)
		)
		(property "Value" "R_5k1_0402"
			(at -1.011843 1.772047 0)
			(layer "F.Fab")
			(effects
				(font
					(size 0.7 0.7)
					(thickness 0.15)
				)
				(justify right bottom)
			)
		)
		(property "Footprint" "antmicro-footprints:R_0402_1005Metric"
			(at 0 0 180)
			(layer "F.Fab")
			(hide yes)
			(effects
				(font
					(size 1.27 1.27)
					(thickness 0.15)
				)
			)
		)
		(property "Datasheet" "https://www.bourns.com/docs/product-datasheets/cr.pdf"
			(at 0 0 180)
			(layer "F.Fab")
			(hide yes)
			(effects
				(font
					(size 1.27 1.27)
					(thickness 0.15)
				)
			)
		)
		(property "Author" "Antmicro"
			(at 316.534 193.756 0)
			(layer "F.Fab")
			(hide yes)
			(effects
				(font
					(size 1 1)
					(thickness 0.15)
				)
			)
		)
		(property "License" "Apache-2.0"
			(at 316.534 193.756 0)
			(layer "F.Fab")
			(hide yes)
			(effects
				(font
					(size 1 1)
					(thickness 0.15)
				)
			)
		)
		(property "MPN" "CR0402-FX-5101GLF"
			(at 316.534 193.756 0)
			(layer "F.Fab")
			(hide yes)
			(effects
				(font
					(size 1 1)
					(thickness 0.15)
				)
			)
		)
		(property "Manufacturer" "Bourns"
			(at 316.534 193.756 0)
			(layer "F.Fab")
			(hide yes)
			(effects
				(font
					(size 1 1)
					(thickness 0.15)
				)
			)
		)
		(property "Tolerance" "1%"
			(at 316.534 193.756 0)
			(layer "F.Fab")
			(hide yes)
			(effects
				(font
					(size 1 1)
					(thickness 0.15)
				)
			)
		)
		(property "Val" "5k1"
			(at 316.534 193.756 0)
			(layer "F.Fab")
			(hide yes)
			(effects
				(font
					(size 1 1)
					(thickness 0.15)
				)
			)
		)
		(sheetname "GMSL Connector")
		(sheetfile "GMSL.kicad_sch")
		(attr smd)
		(fp_rect
			(start -0.925 -0.47)
			(end 0.925 0.47)
			(stroke
				(width 0.05)
				(type default)
			)
			(fill none)
			(layer "F.CrtYd")
		)
		(fp_rect
			(start -0.5 -0.25)
			(end 0.5 0.25)
			(stroke
				(width 0.15)
				(type solid)
			)
			(fill none)
			(layer "F.Fab")
		)
		(fp_text user "License: Apache-2.0"
			(at -0.95 5.169 0)
			(layer "F.Fab")
			(hide yes)
			(effects
				(font
					(size 0.7 0.7)
					(thickness 0.15)
				)
				(justify right bottom)
			)
		)
		(fp_text user "${REFERENCE}"
			(at -0.95 3.168 0)
			(layer "F.Fab")
			(hide yes)
			(effects
				(font
					(size 0.7 0.7)
					(thickness 0.15)
				)
				(justify right bottom)
			)
		)
		(fp_text user "Author: Antmicro"
			(at -0.95 4.169 0)
			(layer "F.Fab")
			(hide yes)
			(effects
				(font
					(size 0.7 0.7)
					(thickness 0.15)
				)
				(justify right bottom)
			)
		)
		(pad "1" smd roundrect
			(at -0.48 0 180)
			(size 0.59 0.64)
			(layers "F.Cu" "F.Paste" "F.Mask")
			(roundrect_rratio 0.25)
			(net 58 "Net-(L3-Pad2)")
			(pintype "passive")
		)
		(pad "2" smd roundrect
			(at 0.48 0 180)
			(size 0.59 0.64)
			(layers "F.Cu" "F.Paste" "F.Mask")
			(roundrect_rratio 0.25)
			(net 59 "Net-(L4-Pad2)")
			(pintype "passive")
		)
	)
	(footprint "antmicro-footprints:C_0603_1608Metric"
		(layer "F.Cu")
		(at 164.775 100.625 90)
		(descr "Capacitor SMD 0603")
		(tags "capacitor 0603")
		(property "Reference" "C2"
			(at -0.7 1.5 90)
			(layer "F.SilkS")
			(effects
				(font
					(size 0.7 0.7)
					(thickness 0.15)
				)
				(justify left bottom)
			)
		)
		(property "Value" "C_10u_25V_0603"
			(at -1.42757 1.770288 90)
			(layer "F.Fab")
			(effects
				(font
					(size 0.7 0.7)
					(thickness 0.15)
				)
				(justify left bottom)
			)
		)
		(property "Footprint" "antmicro-footprints:C_0603_1608Metric"
			(at 0 0 90)
			(layer "F.Fab")
			(hide yes)
			(effects
				(font
					(size 1.27 1.27)
					(thickness 0.15)
				)
			)
		)
		(property "Datasheet" "https://product.tdk.com/en/search/capacitor/ceramic/mlcc/info?part_no=C1608X5R1E106M080AC"
			(at 0 0 90)
			(layer "F.Fab")
			(hide yes)
			(effects
				(font
					(size 1.27 1.27)
					(thickness 0.15)
				)
			)
		)
		(property "Author" "Antmicro"
			(at 265.4 -64.15 0)
			(layer "F.Fab")
			(hide yes)
			(effects
				(font
					(size 1 1)
					(thickness 0.15)
				)
			)
		)
		(property "Dielectric" ""
			(at 265.4 -64.15 0)
			(layer "F.Fab")
			(hide yes)
			(effects
				(font
					(size 1 1)
					(thickness 0.15)
				)
			)
		)
		(property "License" "Apache-2.0"
			(at 265.4 -64.15 0)
			(layer "F.Fab")
			(hide yes)
			(effects
				(font
					(size 1 1)
					(thickness 0.15)
				)
			)
		)
		(property "MPN" "C1608X5R1E106M080AC"
			(at 265.4 -64.15 0)
			(layer "F.Fab")
			(hide yes)
			(effects
				(font
					(size 1 1)
					(thickness 0.15)
				)
			)
		)
		(property "Manufacturer" "TDK"
			(at 265.4 -64.15 0)
			(layer "F.Fab")
			(hide yes)
			(effects
				(font
					(size 1 1)
					(thickness 0.15)
				)
			)
		)
		(property "Val" "10u"
			(at 265.4 -64.15 0)
			(layer "F.Fab")
			(hide yes)
			(effects
				(font
					(size 1 1)
					(thickness 0.15)
				)
			)
		)
		(property "Voltage" "25V"
			(at 265.4 -64.15 0)
			(layer "F.Fab")
			(hide yes)
			(effects
				(font
					(size 1 1)
					(thickness 0.15)
				)
			)
		)
		(sheetname "Supply")
		(sheetfile "supply.kicad_sch")
		(attr smd)
		(fp_line
			(start -0.15 -0.4)
			(end 0.15 -0.4)
			(stroke
				(width 0.15)
				(type solid)
			)
			(layer "F.SilkS")
		)
		(fp_line
			(start -0.15 0.4)
			(end 0.15 0.4)
			(stroke
				(width 0.15)
				(type solid)
			)
			(layer "F.SilkS")
		)
		(fp_rect
			(start -1.25 -0.65)
			(end 1.25 0.65)
			(stroke
				(width 0.05)
				(type solid)
			)
			(fill none)
			(layer "F.CrtYd")
		)
		(fp_rect
			(start -0.8 -0.4)
			(end 0.8 0.4)
			(stroke
				(width 0.15)
				(type solid)
			)
			(fill none)
			(layer "F.Fab")
		)
		(fp_text user "Author: Antmicro"
			(at -1.682 4.894 90)
			(layer "F.Fab")
			(hide yes)
			(effects
				(font
					(size 0.7 0.7)
					(thickness 0.15)
				)
				(justify left bottom)
			)
		)
		(fp_text user "License: Apache-2.0"
			(at -1.682 5.895 90)
			(layer "F.Fab")
			(hide yes)
			(effects
				(font
					(size 0.7 0.7)
					(thickness 0.15)
				)
				(justify left bottom)
			)
		)
		(fp_text user "${REFERENCE}"
			(at -1.682 3.895 90)
			(layer "F.Fab")
			(hide yes)
			(effects
				(font
					(size 0.7 0.7)
					(thickness 0.15)
				)
				(justify left bottom)
			)
		)
		(pad "1" smd roundrect
			(at -0.7 0 90)
			(size 0.8 1)
			(layers "F.Cu" "F.Paste" "F.Mask")
			(roundrect_rratio 0.2)
			(net 1 "GND")
			(pintype "passive")
		)
		(pad "2" smd roundrect
			(at 0.7 0 90)
			(size 0.8 1)
			(layers "F.Cu" "F.Paste" "F.Mask")
			(roundrect_rratio 0.2)
			(net 2 "+12V")
			(pintype "passive")
		)
	)
	(footprint "antmicro-footprints:C_0402_1005Metric"
		(layer "F.Cu")
		(at 146.15 85.75 -90)
		(descr "Capacitor SMD 0402")
		(tags "capacitor SMD 0402")
		(property "Reference" "C34"
			(at 0.85 -0.95 90)
			(layer "F.SilkS")
			(effects
				(font
					(size 0.7 0.7)
					(thickness 0.15)
				)
				(justify right top)
			)
		)
		(property "Value" "C_22u_0402"
			(at -1.022927 2.155213 90)
			(layer "F.Fab")
			(effects
				(font
					(size 0.7 0.7)
					(thickness 0.15)
				)
				(justify right top)
			)
		)
		(property "Footprint" "antmicro-footprints:C_0402_1005Metric"
			(at 0 0 90)
			(layer "F.Fab")
			(hide yes)
			(effects
				(font
					(size 1.27 1.27)
					(thickness 0.15)
				)
			)
		)
		(property "Datasheet" "https://www.murata.com/products/productdetail?partno=GRM158R60J226ME01%23"
			(at 0 0 90)
			(layer "F.Fab")
			(hide yes)
			(effects
				(font
					(size 1.27 1.27)
					(thickness 0.15)
				)
			)
		)
		(property "MPN" "GRM158R60J226ME01D"
			(at 0 0 -90)
			(unlocked yes)
			(layer "F.Fab")
			(hide yes)
			(effects
				(font
					(size 1 1)
					(thickness 0.15)
				)
			)
		)
		(property "Manufacturer" "Murata"
			(at 0 0 -90)
			(unlocked yes)
			(layer "F.Fab")
			(hide yes)
			(effects
				(font
					(size 1 1)
					(thickness 0.15)
				)
			)
		)
		(property "License" "Apache-2.0"
			(at 0 0 -90)
			(unlocked yes)
			(layer "F.Fab")
			(hide yes)
			(effects
				(font
					(size 1 1)
					(thickness 0.15)
				)
			)
		)
		(property "Author" "Antmicro"
			(at 0 0 -90)
			(unlocked yes)
			(layer "F.Fab")
			(hide yes)
			(effects
				(font
					(size 1 1)
					(thickness 0.15)
				)
			)
		)
		(property "Val" "22u"
			(at 0 0 -90)
			(unlocked yes)
			(layer "F.Fab")
			(hide yes)
			(effects
				(font
					(size 1 1)
					(thickness 0.15)
				)
			)
		)
		(property "Voltage" ""
			(at 0 0 -90)
			(unlocked yes)
			(layer "F.Fab")
			(hide yes)
			(effects
				(font
					(size 1 1)
					(thickness 0.15)
				)
			)
		)
		(property "Dielectric" ""
			(at 0 0 -90)
			(unlocked yes)
			(layer "F.Fab")
			(hide yes)
			(effects
				(font
					(size 1 1)
					(thickness 0.15)
				)
			)
		)
		(sheetname "Supply")
		(sheetfile "supply.kicad_sch")
		(attr smd)
		(fp_rect
			(start -0.925 -0.47)
			(end 0.925 0.47)
			(stroke
				(width 0.05)
				(type default)
			)
			(fill none)
			(layer "F.CrtYd")
		)
		(fp_line
			(start -0.494 0.248)
			(end -0.494 -0.25)
			(stroke
				(width 0.15)
				(type solid)
			)
			(layer "F.Fab")
		)
		(fp_line
			(start 0.504 0.248)
			(end -0.494 0.248)
			(stroke
				(width 0.15)
				(type solid)
			)
			(layer "F.Fab")
		)
		(fp_line
			(start -0.494 -0.25)
			(end 0.504 -0.25)
			(stroke
				(width 0.15)
				(type solid)
			)
			(layer "F.Fab")
		)
		(fp_line
			(start 0.504 -0.25)
			(end 0.504 0.248)
			(stroke
				(width 0.15)
				(type solid)
			)
			(layer "F.Fab")
		)
		(fp_text user "Author: Antmicro"
			(at -0.939 3.399 90)
			(layer "F.Fab")
			(hide yes)
			(effects
				(font
					(size 0.7 0.7)
					(thickness 0.15)
				)
				(justify right top)
			)
		)
		(fp_text user "License: Apache-2.0"
			(at -0.939 5.799 90)
			(layer "F.Fab")
			(hide yes)
			(effects
				(font
					(size 0.7 0.7)
					(thickness 0.15)
				)
				(justify right top)
			)
		)
		(fp_text user "${REFERENCE}"
			(at -0.939 4.599 90)
			(layer "F.Fab")
			(hide yes)
			(effects
				(font
					(size 0.7 0.7)
					(thickness 0.15)
				)
				(justify right top)
			)
		)
		(pad "1" smd roundrect
			(at -0.48 0 270)
			(size 0.59 0.64)
			(layers "F.Cu" "F.Paste" "F.Mask")
			(roundrect_rratio 0.25)
			(net 1 "GND")
			(pintype "passive")
		)
		(pad "2" smd roundrect
			(at 0.48 0 270)
			(size 0.59 0.64)
			(layers "F.Cu" "F.Paste" "F.Mask")
			(roundrect_rratio 0.25)
			(net 94 "/Supply/OUT_3V3")
			(pintype "passive")
		)
	)
	(footprint "antmicro-footprints:C_0402_1005Metric"
		(layer "F.Cu")
		(at 164.475 103.2 -90)
		(descr "Capacitor SMD 0402")
		(tags "capacitor SMD 0402")
		(property "Reference" "C6"
			(at 0.51 0.3 90)
			(layer "F.SilkS")
			(effects
				(font
					(size 0.7 0.7)
					(thickness 0.15)
				)
				(justify right bottom)
			)
		)
		(property "Value" "C_22u_0402"
			(at -1.022927 2.155213 90)
			(layer "F.Fab")
			(effects
				(font
					(size 0.7 0.7)
					(thickness 0.15)
				)
				(justify right bottom)
			)
		)
		(property "Footprint" "antmicro-footprints:C_0402_1005Metric"
			(at 0 0 -90)
			(layer "F.Fab")
			(hide yes)
			(effects
				(font
					(size 1.27 1.27)
					(thickness 0.15)
				)
			)
		)
		(property "Datasheet" "https://www.murata.com/products/productdetail?partno=GRM158R60J226ME01%23"
			(at 0 0 -90)
			(layer "F.Fab")
			(hide yes)
			(effects
				(font
					(size 1.27 1.27)
					(thickness 0.15)
				)
			)
		)
		(property "Author" "Antmicro"
			(at 61.275 267.675 0)
			(layer "F.Fab")
			(hide yes)
			(effects
				(font
					(size 1 1)
					(thickness 0.15)
				)
			)
		)
		(property "Dielectric" ""
			(at 61.275 267.675 0)
			(layer "F.Fab")
			(hide yes)
			(effects
				(font
					(size 1 1)
					(thickness 0.15)
				)
			)
		)
		(property "License" "Apache-2.0"
			(at 61.275 267.675 0)
			(layer "F.Fab")
			(hide yes)
			(effects
				(font
					(size 1 1)
					(thickness 0.15)
				)
			)
		)
		(property "MPN" "GRM158R60J226ME01D"
			(at 61.275 267.675 0)
			(layer "F.Fab")
			(hide yes)
			(effects
				(font
					(size 1 1)
					(thickness 0.15)
				)
			)
		)
		(property "Manufacturer" "Murata"
			(at 61.275 267.675 0)
			(layer "F.Fab")
			(hide yes)
			(effects
				(font
					(size 1 1)
					(thickness 0.15)
				)
			)
		)
		(property "Val" "22u"
			(at 61.275 267.675 0)
			(layer "F.Fab")
			(hide yes)
			(effects
				(font
					(size 1 1)
					(thickness 0.15)
				)
			)
		)
		(property "Voltage" ""
			(at 61.275 267.675 0)
			(layer "F.Fab")
			(hide yes)
			(effects
				(font
					(size 1 1)
					(thickness 0.15)
				)
			)
		)
		(sheetname "Supply")
		(sheetfile "supply.kicad_sch")
		(attr smd)
		(fp_rect
			(start -0.925 -0.47)
			(end 0.925 0.47)
			(stroke
				(width 0.05)
				(type default)
			)
			(fill none)
			(layer "F.CrtYd")
		)
		(fp_line
			(start -0.494 0.248)
			(end -0.494 -0.25)
			(stroke
				(width 0.15)
				(type solid)
			)
			(layer "F.Fab")
		)
		(fp_line
			(start 0.504 0.248)
			(end -0.494 0.248)
			(stroke
				(width 0.15)
				(type solid)
			)
			(layer "F.Fab")
		)
		(fp_line
			(start -0.494 -0.25)
			(end 0.504 -0.25)
			(stroke
				(width 0.15)
				(type solid)
			)
			(layer "F.Fab")
		)
		(fp_line
			(start 0.504 -0.25)
			(end 0.504 0.248)
			(stroke
				(width 0.15)
				(type solid)
			)
			(layer "F.Fab")
		)
		(fp_text user "License: Apache-2.0"
			(at -0.939 5.799 90)
			(layer "F.Fab")
			(hide yes)
			(effects
				(font
					(size 0.7 0.7)
					(thickness 0.15)
				)
				(justify right bottom)
			)
		)
		(fp_text user "${REFERENCE}"
			(at -0.939 4.599 90)
			(layer "F.Fab")
			(hide yes)
			(effects
				(font
					(size 0.7 0.7)
					(thickness 0.15)
				)
				(justify right bottom)
			)
		)
		(fp_text user "Author: Antmicro"
			(at -0.939 3.399 90)
			(layer "F.Fab")
			(hide yes)
			(effects
				(font
					(size 0.7 0.7)
					(thickness 0.15)
				)
				(justify right bottom)
			)
		)
		(pad "1" smd roundrect
			(at -0.48 0 270)
			(size 0.59 0.64)
			(layers "F.Cu" "F.Paste" "F.Mask")
			(roundrect_rratio 0.25)
			(net 1 "GND")
			(pintype "passive")
		)
		(pad "2" smd roundrect
			(at 0.48 0 270)
			(size 0.59 0.64)
			(layers "F.Cu" "F.Paste" "F.Mask")
			(roundrect_rratio 0.25)
			(net 8 "/Supply/OUT_1V8")
			(pintype "passive")
		)
	)
	(footprint "antmicro-footprints:R_0402_1005Metric"
		(layer "F.Cu")
		(at 143.82 115.57 90)
		(descr "Resistor SMD 0402")
		(tags "resistor SMD 0402")
		(property "Reference" "R46"
			(at 0.79 0.43 90)
			(layer "F.SilkS")
			(effects
				(font
					(size 0.7 0.7)
					(thickness 0.15)
				)
				(justify left bottom)
			)
		)
		(property "Value" "R_200R_0402"
			(at -1.011843 1.772047 90)
			(layer "F.Fab")
			(effects
				(font
					(size 0.7 0.7)
					(thickness 0.15)
				)
				(justify left bottom)
			)
		)
		(property "Footprint" "antmicro-footprints:R_0402_1005Metric"
			(at 0 0 90)
			(layer "F.Fab")
			(hide yes)
			(effects
				(font
					(size 1.27 1.27)
					(thickness 0.15)
				)
			)
		)
		(property "Datasheet" "https://www.bourns.com/docs/product-datasheets/cr.pdf"
			(at 0 0 90)
			(layer "F.Fab")
			(hide yes)
			(effects
				(font
					(size 1.27 1.27)
					(thickness 0.15)
				)
			)
		)
		(property "MPN" "CR0402-FX-2000GLF"
			(at 0 0 90)
			(unlocked yes)
			(layer "F.Fab")
			(hide yes)
			(effects
				(font
					(size 1 1)
					(thickness 0.15)
				)
			)
		)
		(property "Manufacturer" "Bourns"
			(at 0 0 90)
			(unlocked yes)
			(layer "F.Fab")
			(hide yes)
			(effects
				(font
					(size 1 1)
					(thickness 0.15)
				)
			)
		)
		(property "License" "Apache-2.0"
			(at 0 0 90)
			(unlocked yes)
			(layer "F.Fab")
			(hide yes)
			(effects
				(font
					(size 1 1)
					(thickness 0.15)
				)
			)
		)
		(property "Author" "Antmicro"
			(at 0 0 90)
			(unlocked yes)
			(layer "F.Fab")
			(hide yes)
			(effects
				(font
					(size 1 1)
					(thickness 0.15)
				)
			)
		)
		(property "Val" "200R"
			(at 0 0 90)
			(unlocked yes)
			(layer "F.Fab")
			(hide yes)
			(effects
				(font
					(size 1 1)
					(thickness 0.15)
				)
			)
		)
		(property "Tolerance" "1%"
			(at 0 0 90)
			(unlocked yes)
			(layer "F.Fab")
			(hide yes)
			(effects
				(font
					(size 1 1)
					(thickness 0.15)
				)
			)
		)
		(property "Public" ""
			(at 0 0 90)
			(unlocked yes)
			(layer "F.Fab")
			(hide yes)
			(effects
				(font
					(size 1 1)
					(thickness 0.15)
				)
			)
		)
		(sheetname "Supply")
		(sheetfile "supply.kicad_sch")
		(attr smd)
		(fp_rect
			(start -0.925 -0.47)
			(end 0.925 0.47)
			(stroke
				(width 0.05)
				(type default)
			)
			(fill none)
			(layer "F.CrtYd")
		)
		(fp_rect
			(start -0.5 -0.25)
			(end 0.5 0.25)
			(stroke
				(width 0.15)
				(type solid)
			)
			(fill none)
			(layer "F.Fab")
		)
		(fp_text user "${REFERENCE}"
			(at -0.95 3.168 90)
			(layer "F.Fab")
			(hide yes)
			(effects
				(font
					(size 0.7 0.7)
					(thickness 0.15)
				)
				(justify left bottom)
			)
		)
		(fp_text user "Author: Antmicro"
			(at -0.95 4.169 90)
			(layer "F.Fab")
			(hide yes)
			(effects
				(font
					(size 0.7 0.7)
					(thickness 0.15)
				)
				(justify left bottom)
			)
		)
		(fp_text user "License: Apache-2.0"
			(at -0.95 5.169 90)
			(layer "F.Fab")
			(hide yes)
			(effects
				(font
					(size 0.7 0.7)
					(thickness 0.15)
				)
				(justify left bottom)
			)
		)
		(pad "1" smd roundrect
			(at -0.48 0 90)
			(size 0.59 0.64)
			(layers "F.Cu" "F.Paste" "F.Mask")
			(roundrect_rratio 0.25)
			(net 1 "GND")
			(pintype "passive")
		)
		(pad "2" smd roundrect
			(at 0.48 0 90)
			(size 0.59 0.64)
			(layers "F.Cu" "F.Paste" "F.Mask")
			(roundrect_rratio 0.25)
			(net 95 "Net-(D11-C)")
			(pintype "passive")
		)
	)
	(footprint "antmicro-footprints:L_Coilcraft-MSS6132T"
		(layer "F.Cu")
		(at 161.6 89.662 180)
		(property "Reference" "L3"
			(at 0.65 -4.1 180)
			(layer "F.SilkS")
			(effects
				(font
					(size 0.7 0.7)
					(thickness 0.15)
				)
				(justify left bottom)
			)
		)
		(property "Value" "L_22u_1.12A_Coilcraft-MSS6132T"
			(at -0.508 4.826 180)
			(layer "F.Fab")
			(effects
				(font
					(size 0.7 0.7)
					(thickness 0.15)
				)
				(justify left bottom)
			)
		)
		(property "Footprint" "antmicro-footprints:L_Coilcraft-MSS6132T"
			(at 0 0 180)
			(layer "F.Fab")
			(hide yes)
			(effects
				(font
					(size 1.27 1.27)
					(thickness 0.15)
				)
			)
		)
		(property "Datasheet" "https://www.coilcraft.com/getmedia/d035c9b3-191d-46aa-ab3f-5c1a849157c1/mss6132t.pdf"
			(at 0 0 180)
			(layer "F.Fab")
			(hide yes)
			(effects
				(font
					(size 1.27 1.27)
					(thickness 0.15)
				)
			)
		)
		(property "Author" "Antmicro"
			(at 323.2 179.324 0)
			(layer "F.Fab")
			(hide yes)
			(effects
				(font
					(size 1 1)
					(thickness 0.15)
				)
			)
		)
		(property "IMax" "1.45A"
			(at 323.2 179.324 0)
			(layer "F.Fab")
			(hide yes)
			(effects
				(font
					(size 1 1)
					(thickness 0.15)
				)
			)
		)
		(property "ISat" "1.12A"
			(at 323.2 179.324 0)
			(layer "F.Fab")
			(hide yes)
			(effects
				(font
					(size 1 1)
					(thickness 0.15)
				)
			)
		)
		(property "License" "Apache-2.0"
			(at 323.2 179.324 0)
			(layer "F.Fab")
			(hide yes)
			(effects
				(font
					(size 1 1)
					(thickness 0.15)
				)
			)
		)
		(property "MPN" "MSS6132T-223"
			(at 323.2 179.324 0)
			(layer "F.Fab")
			(hide yes)
			(effects
				(font
					(size 1 1)
					(thickness 0.15)
				)
			)
		)
		(property "Manufacturer" "Coilcraft"
			(at 323.2 179.324 0)
			(layer "F.Fab")
			(hide yes)
			(effects
				(font
					(size 1 1)
					(thickness 0.15)
				)
			)
		)
		(property "Size" "6.1x6.1"
			(at 323.2 179.324 0)
			(layer "F.Fab")
			(hide yes)
			(effects
				(font
					(size 1 1)
					(thickness 0.15)
				)
			)
		)
		(property "Val" "22u/1.12A"
			(at 323.2 179.324 0)
			(layer "F.Fab")
			(hide yes)
			(effects
				(font
					(size 1 1)
					(thickness 0.15)
				)
			)
		)
		(sheetname "GMSL Connector")
		(sheetfile "GMSL.kicad_sch")
		(attr smd)
		(fp_line
			(start -0.8 3.05)
			(end 0.8 3.05)
			(stroke
				(width 0.15)
				(type solid)
			)
			(layer "F.SilkS")
		)
		(fp_line
			(start -0.8 -3.05)
			(end 0.8 -3.05)
			(stroke
				(width 0.15)
				(type solid)
			)
			(layer "F.SilkS")
		)
		(fp_rect
			(start -3.35 -3.35)
			(end 3.35 3.35)
			(stroke
				(width 0.05)
				(type solid)
			)
			(fill none)
			(layer "F.CrtYd")
		)
		(fp_rect
			(start -3.1 -3.1)
			(end 3.1 3.1)
			(stroke
				(width 0.15)
				(type solid)
			)
			(fill none)
			(layer "F.Fab")
		)
		(fp_text user "Author: Antmicro"
			(at -3.35 9.226 180)
			(layer "F.Fab")
			(hide yes)
			(effects
				(font
					(size 0.7 0.7)
					(thickness 0.15)
				)
				(justify left bottom)
			)
		)
		(fp_text user "License: Apache-2.0"
			(at -3.35 8.026 180)
			(layer "F.Fab")
			(hide yes)
			(effects
				(font
					(size 0.7 0.7)
					(thickness 0.15)
				)
				(justify left bottom)
			)
		)
		(fp_text user "${REFERENCE}"
			(at -3.35 6.826 180)
			(layer "F.Fab")
			(hide yes)
			(effects
				(font
					(size 0.7 0.7)
					(thickness 0.15)
				)
				(justify left bottom)
			)
		)
		(pad "1" smd custom
			(at -2.71 0 270)
			(size 6 0.575)
			(layers "F.Cu" "F.Paste" "F.Mask")
			(net 2 "+12V")
			(pintype "passive")
			(options
				(clearance outline)
				(anchor rect)
			)
			(primitives
				(gr_poly
					(pts
						(xy 2.4 1.71) (xy 2.117646 1.21) (xy 1.9 0.96) (xy 1.65 0.71) (xy 1.2 0.41) (xy 0.4 0.11) (xy 0.4 0.01)
						(xy 2.9 0) (xy 2.9 1.71)
					)
					(width 0.2)
					(fill yes)
				)
				(gr_poly
					(pts
						(xy -2.4 1.731128) (xy -2.117646 1.231128) (xy -1.9 0.981128) (xy -1.65 0.731128) (xy -1.2 0.431128)
						(xy -0.4 0.131128) (xy -0.4 0.031128) (xy -2.9 0.021128) (xy -2.9 1.731128)
					)
					(width 0.2)
					(fill yes)
				)
			)
		)
		(pad "2" smd custom
			(at 2.71 0 90)
			(size 6 0.575)
			(layers "F.Cu" "F.Paste" "F.Mask")
			(net 58 "Net-(L3-Pad2)")
			(pintype "passive")
			(options
				(clearance outline)
				(anchor rect)
			)
			(primitives
				(gr_poly
					(pts
						(xy -2.4 1.731128) (xy -2.117646 1.231128) (xy -1.9 0.981128) (xy -1.65 0.731128) (xy -1.2 0.431128)
						(xy -0.4 0.131128) (xy -0.4 0.031128) (xy -2.9 0.021128) (xy -2.9 1.731128)
					)
					(width 0.2)
					(fill yes)
				)
				(gr_poly
					(pts
						(xy 2.4 1.71) (xy 2.117646 1.21) (xy 1.9 0.96) (xy 1.65 0.71) (xy 1.2 0.41) (xy 0.4 0.11) (xy 0.4 0.01)
						(xy 2.9 0) (xy 2.9 1.71)
					)
					(width 0.2)
					(fill yes)
				)
			)
		)
	)
	(footprint "antmicro-footprints:C_0402_1005Metric"
		(layer "F.Cu")
		(at 146.72 97.36 -45)
		(descr "Capacitor SMD 0402")
		(tags "capacitor SMD 0402")
		(property "Reference" "C32"
			(at 0.59397 -2.545584 -45)
			(unlocked yes)
			(layer "F.SilkS")
			(effects
				(font
					(size 0.7 0.7)
					(thickness 0.15)
				)
				(justify right bottom)
			)
		)
		(property "Value" "C_10n_0402"
			(at -1.022927 2.155213 135)
			(layer "F.Fab")
			(effects
				(font
					(size 0.7 0.7)
					(thickness 0.15)
				)
				(justify right bottom)
			)
		)
		(property "Footprint" "antmicro-footprints:C_0402_1005Metric"
			(at 0 0 -45)
			(layer "F.Fab")
			(hide yes)
			(effects
				(font
					(size 1.27 1.27)
					(thickness 0.15)
				)
			)
		)
		(property "Datasheet" "https://www.murata.com/products/productdetail?partno=GRM155R71H103KA88%23"
			(at 0 0 -45)
			(layer "F.Fab")
			(hide yes)
			(effects
				(font
					(size 1.27 1.27)
					(thickness 0.15)
				)
			)
		)
		(property "Author" "Antmicro"
			(at -25.870623 132.26279 0)
			(layer "F.Fab")
			(hide yes)
			(effects
				(font
					(size 1 1)
					(thickness 0.15)
				)
			)
		)
		(property "Dielectric" "X7R"
			(at -25.870623 132.26279 0)
			(layer "F.Fab")
			(hide yes)
			(effects
				(font
					(size 1 1)
					(thickness 0.15)
				)
			)
		)
		(property "License" "Apache-2.0"
			(at -25.870623 132.26279 0)
			(layer "F.Fab")
			(hide yes)
			(effects
				(font
					(size 1 1)
					(thickness 0.15)
				)
			)
		)
		(property "MPN" "GRM155R71H103KA88D"
			(at -25.870623 132.26279 0)
			(layer "F.Fab")
			(hide yes)
			(effects
				(font
					(size 1 1)
					(thickness 0.15)
				)
			)
		)
		(property "Manufacturer" "Murata"
			(at -25.870623 132.26279 0)
			(layer "F.Fab")
			(hide yes)
			(effects
				(font
					(size 1 1)
					(thickness 0.15)
				)
			)
		)
		(property "Val" "10n"
			(at -25.870623 132.26279 0)
			(layer "F.Fab")
			(hide yes)
			(effects
				(font
					(size 1 1)
					(thickness 0.15)
				)
			)
		)
		(property "Voltage" "50V"
			(at -25.870623 132.26279 0)
			(layer "F.Fab")
			(hide yes)
			(effects
				(font
					(size 1 1)
					(thickness 0.15)
				)
			)
		)
		(sheetname "Serializer")
		(sheetfile "serializer.kicad_sch")
		(attr smd)
		(fp_poly
			(pts
				(xy -0.925 -0.47) (xy 0.925 -0.47) (xy 0.925 0.47) (xy -0.925 0.47)
			)
			(stroke
				(width 0.05)
				(type default)
			)
			(fill none)
			(layer "F.CrtYd")
		)
		(fp_line
			(start -0.494 0.248)
			(end -0.494 -0.25)
			(stroke
				(width 0.15)
				(type solid)
			)
			(layer "F.Fab")
		)
		(fp_line
			(start -0.494 -0.25)
			(end 0.504 -0.25)
			(stroke
				(width 0.15)
				(type solid)
			)
			(layer "F.Fab")
		)
		(fp_line
			(start 0.504 0.248)
			(end -0.494 0.248)
			(stroke
				(width 0.15)
				(type solid)
			)
			(layer "F.Fab")
		)
		(fp_line
			(start 0.504 -0.25)
			(end 0.504 0.248)
			(stroke
				(width 0.15)
				(type solid)
			)
			(layer "F.Fab")
		)
		(fp_text user "License: Apache-2.0"
			(at -0.939 5.799 135)
			(layer "F.Fab")
			(hide yes)
			(effects
				(font
					(size 0.7 0.7)
					(thickness 0.15)
				)
				(justify right bottom)
			)
		)
		(fp_text user "Author: Antmicro"
			(at -0.939 3.399 135)
			(layer "F.Fab")
			(hide yes)
			(effects
				(font
					(size 0.7 0.7)
					(thickness 0.15)
				)
				(justify right bottom)
			)
		)
		(fp_text user "${REFERENCE}"
			(at -0.939 4.599 135)
			(layer "F.Fab")
			(hide yes)
			(effects
				(font
					(size 0.7 0.7)
					(thickness 0.15)
				)
				(justify right bottom)
			)
		)
		(pad "1" smd roundrect
			(at -0.48 0 315)
			(size 0.59 0.64)
			(layers "F.Cu" "F.Paste" "F.Mask")
			(roundrect_rratio 0.25)
			(net 1 "GND")
			(pintype "passive")
		)
		(pad "2" smd roundrect
			(at 0.48 0 315)
			(size 0.59 0.64)
			(layers "F.Cu" "F.Paste" "F.Mask")
			(roundrect_rratio 0.25)
			(net 10 "+3V3")
			(pintype "passive")
		)
	)
	(footprint "antmicro-footprints:C_0402_1005Metric"
		(layer "F.Cu")
		(at 159.3 102.431 -90)
		(descr "Capacitor SMD 0402")
		(tags "capacitor SMD 0402")
		(property "Reference" "C4"
			(at -0.692 0.577 90)
			(layer "F.SilkS")
			(effects
				(font
					(size 0.7 0.7)
					(thickness 0.15)
				)
				(justify right bottom)
			)
		)
		(property "Value" "C_100n_0402"
			(at -1.022927 2.155213 90)
			(layer "F.Fab")
			(effects
				(font
					(size 0.7 0.7)
					(thickness 0.15)
				)
				(justify right bottom)
			)
		)
		(property "Footprint" "antmicro-footprints:C_0402_1005Metric"
			(at 0 0 -90)
			(layer "F.Fab")
			(hide yes)
			(effects
				(font
					(size 1.27 1.27)
					(thickness 0.15)
				)
			)
		)
		(property "Datasheet" "https://www.murata.com/products/productdetail?partno=GRM155R61H104KE14%23"
			(at 0 0 -90)
			(layer "F.Fab")
			(hide yes)
			(effects
				(font
					(size 1.27 1.27)
					(thickness 0.15)
				)
			)
		)
		(property "Author" "Antmicro"
			(at 56.869 261.731 0)
			(layer "F.Fab")
			(hide yes)
			(effects
				(font
					(size 1 1)
					(thickness 0.15)
				)
			)
		)
		(property "Dielectric" "X5R"
			(at 56.869 261.731 0)
			(layer "F.Fab")
			(hide yes)
			(effects
				(font
					(size 1 1)
					(thickness 0.15)
				)
			)
		)
		(property "License" "Apache-2.0"
			(at 56.869 261.731 0)
			(layer "F.Fab")
			(hide yes)
			(effects
				(font
					(size 1 1)
					(thickness 0.15)
				)
			)
		)
		(property "MPN" "GRM155R61H104KE14D"
			(at 56.869 261.731 0)
			(layer "F.Fab")
			(hide yes)
			(effects
				(font
					(size 1 1)
					(thickness 0.15)
				)
			)
		)
		(property "Manufacturer" "Murata"
			(at 56.869 261.731 0)
			(layer "F.Fab")
			(hide yes)
			(effects
				(font
					(size 1 1)
					(thickness 0.15)
				)
			)
		)
		(property "Val" "100n"
			(at 56.869 261.731 0)
			(layer "F.Fab")
			(hide yes)
			(effects
				(font
					(size 1 1)
					(thickness 0.15)
				)
			)
		)
		(property "Voltage" "50V"
			(at 56.869 261.731 0)
			(layer "F.Fab")
			(hide yes)
			(effects
				(font
					(size 1 1)
					(thickness 0.15)
				)
			)
		)
		(sheetname "Supply")
		(sheetfile "supply.kicad_sch")
		(attr smd)
		(fp_rect
			(start -0.925 -0.47)
			(end 0.925 0.47)
			(stroke
				(width 0.05)
				(type default)
			)
			(fill none)
			(layer "F.CrtYd")
		)
		(fp_line
			(start -0.494 0.248)
			(end -0.494 -0.25)
			(stroke
				(width 0.15)
				(type solid)
			)
			(layer "F.Fab")
		)
		(fp_line
			(start 0.504 0.248)
			(end -0.494 0.248)
			(stroke
				(width 0.15)
				(type solid)
			)
			(layer "F.Fab")
		)
		(fp_line
			(start -0.494 -0.25)
			(end 0.504 -0.25)
			(stroke
				(width 0.15)
				(type solid)
			)
			(layer "F.Fab")
		)
		(fp_line
			(start 0.504 -0.25)
			(end 0.504 0.248)
			(stroke
				(width 0.15)
				(type solid)
			)
			(layer "F.Fab")
		)
		(fp_text user "Author: Antmicro"
			(at -0.939 3.399 90)
			(layer "F.Fab")
			(hide yes)
			(effects
				(font
					(size 0.7 0.7)
					(thickness 0.15)
				)
				(justify right bottom)
			)
		)
		(fp_text user "${REFERENCE}"
			(at -0.939 4.599 90)
			(layer "F.Fab")
			(hide yes)
			(effects
				(font
					(size 0.7 0.7)
					(thickness 0.15)
				)
				(justify right bottom)
			)
		)
		(fp_text user "License: Apache-2.0"
			(at -0.939 5.799 90)
			(layer "F.Fab")
			(hide yes)
			(effects
				(font
					(size 0.7 0.7)
					(thickness 0.15)
				)
				(justify right bottom)
			)
		)
		(pad "1" smd roundrect
			(at -0.48 0 270)
			(size 0.59 0.64)
			(layers "F.Cu" "F.Paste" "F.Mask")
			(roundrect_rratio 0.25)
			(net 5 "Net-(U2-BST)")
			(pintype "passive")
		)
		(pad "2" smd roundrect
			(at 0.48 0 270)
			(size 0.59 0.64)
			(layers "F.Cu" "F.Paste" "F.Mask")
			(roundrect_rratio 0.25)
			(net 6 "/Supply/SW_1V8")
			(pintype "passive")
		)
	)
	(footprint "antmicro-footprints:R_0402_1005Metric"
		(layer "F.Cu")
		(at 133.1 110.95)
		(descr "Resistor SMD 0402")
		(tags "resistor SMD 0402")
		(property "Reference" "R25"
			(at 1.05 -5.558334 0)
			(layer "F.SilkS")
			(effects
				(font
					(size 0.7 0.7)
					(thickness 0.15)
				)
				(justify left bottom)
			)
		)
		(property "Value" "R_100R_0402"
			(at -1.011843 1.772047 0)
			(layer "F.Fab")
			(effects
				(font
					(size 0.7 0.7)
					(thickness 0.15)
				)
				(justify left bottom)
			)
		)
		(property "Footprint" "antmicro-footprints:R_0402_1005Metric"
			(at 0 0 0)
			(layer "F.Fab")
			(hide yes)
			(effects
				(font
					(size 1.27 1.27)
					(thickness 0.15)
				)
			)
		)
		(property "Datasheet" "https://www.bourns.com/docs/product-datasheets/cr.pdf"
			(at 0 0 0)
			(layer "F.Fab")
			(hide yes)
			(effects
				(font
					(size 1.27 1.27)
					(thickness 0.15)
				)
			)
		)
		(property "Author" "Antmicro"
			(at 0 0 0)
			(layer "F.Fab")
			(hide yes)
			(effects
				(font
					(size 1 1)
					(thickness 0.15)
				)
			)
		)
		(property "License" "Apache-2.0"
			(at 0 0 0)
			(layer "F.Fab")
			(hide yes)
			(effects
				(font
					(size 1 1)
					(thickness 0.15)
				)
			)
		)
		(property "MPN" "CR0402-FX-1000GLF"
			(at 0 0 0)
			(layer "F.Fab")
			(hide yes)
			(effects
				(font
					(size 1 1)
					(thickness 0.15)
				)
			)
		)
		(property "Manufacturer" "Bourns"
			(at 0 0 0)
			(layer "F.Fab")
			(hide yes)
			(effects
				(font
					(size 1 1)
					(thickness 0.15)
				)
			)
		)
		(property "Tolerance" "1%"
			(at 0 0 0)
			(layer "F.Fab")
			(hide yes)
			(effects
				(font
					(size 1 1)
					(thickness 0.15)
				)
			)
		)
		(property "Val" "100R"
			(at 0 0 0)
			(layer "F.Fab")
			(hide yes)
			(effects
				(font
					(size 1 1)
					(thickness 0.15)
				)
			)
		)
		(sheetname "CSI Connector")
		(sheetfile "CSI.kicad_sch")
		(attr smd)
		(fp_rect
			(start -0.925 -0.47)
			(end 0.925 0.47)
			(stroke
				(width 0.05)
				(type default)
			)
			(fill none)
			(layer "F.CrtYd")
		)
		(fp_rect
			(start -0.5 -0.25)
			(end 0.5 0.25)
			(stroke
				(width 0.15)
				(type solid)
			)
			(fill none)
			(layer "F.Fab")
		)
		(fp_text user "License: Apache-2.0"
			(at -0.95 5.169 0)
			(layer "F.Fab")
			(hide yes)
			(effects
				(font
					(size 0.7 0.7)
					(thickness 0.15)
				)
				(justify left bottom)
			)
		)
		(fp_text user "Author: Antmicro"
			(at -0.95 4.169 0)
			(layer "F.Fab")
			(hide yes)
			(effects
				(font
					(size 0.7 0.7)
					(thickness 0.15)
				)
				(justify left bottom)
			)
		)
		(fp_text user "${REFERENCE}"
			(at -0.95 3.168 0)
			(layer "F.Fab")
			(hide yes)
			(effects
				(font
					(size 0.7 0.7)
					(thickness 0.15)
				)
				(justify left bottom)
			)
		)
		(pad "1" smd roundrect
			(at -0.48 0)
			(size 0.59 0.64)
			(layers "F.Cu" "F.Paste" "F.Mask")
			(roundrect_rratio 0.25)
			(net 37 "/CSI Connector/SCL_CAM1")
			(pintype "passive")
		)
		(pad "2" smd roundrect
			(at 0.48 0)
			(size 0.59 0.64)
			(layers "F.Cu" "F.Paste" "F.Mask")
			(roundrect_rratio 0.25)
			(net 89 "/CSI Connector/I2C.SCL")
			(pintype "passive")
		)
	)
	(footprint "antmicro-footprints:D_0402_1005Metric"
		(layer "F.Cu")
		(at 152.497391 98.049759 -45)
		(property "Reference" "D2"
			(at -0.740447 -2.830102 -45)
			(unlocked yes)
			(layer "F.SilkS")
			(effects
				(font
					(size 0.7 0.7)
					(thickness 0.15)
				)
				(justify left bottom)
			)
		)
		(property "Value" "AXGD10402KR"
			(at -2.54 2.54 -45)
			(layer "F.Fab")
			(effects
				(font
					(size 0.7 0.7)
					(thickness 0.15)
				)
				(justify left bottom)
			)
		)
		(property "Footprint" "antmicro-footprints:D_0402_1005Metric"
			(at 0 0 -45)
			(layer "F.Fab")
			(hide yes)
			(effects
				(font
					(size 1.27 1.27)
					(thickness 0.15)
				)
			)
		)
		(property "Datasheet" "https://www.littelfuse.com/media?resourcetype=datasheets&itemid=020b2bf2-064c-4ff1-a898-b4ec805b2fea&filename=littelfuse-xtremeguard-axgd-datasheet"
			(at 0 0 -45)
			(layer "F.Fab")
			(hide yes)
			(effects
				(font
					(size 1.27 1.27)
					(thickness 0.15)
				)
			)
		)
		(property "Author" "Antmicro"
			(at -24.666197 136.550049 0)
			(layer "F.Fab")
			(hide yes)
			(effects
				(font
					(size 1 1)
					(thickness 0.15)
				)
			)
		)
		(property "License" "Apache-2.0"
			(at -24.666197 136.550049 0)
			(layer "F.Fab")
			(hide yes)
			(effects
				(font
					(size 1 1)
					(thickness 0.15)
				)
			)
		)
		(property "MPN" "AXGD10402KR"
			(at -24.666197 136.550049 0)
			(layer "F.Fab")
			(hide yes)
			(effects
				(font
					(size 1 1)
					(thickness 0.15)
				)
			)
		)
		(property "Manufacturer" "Littelfuse"
			(at -24.666197 136.550049 0)
			(layer "F.Fab")
			(hide yes)
			(effects
				(font
					(size 1 1)
					(thickness 0.15)
				)
			)
		)
		(sheetname "GMSL Connector")
		(sheetfile "GMSL.kicad_sch")
		(attr smd)
		(fp_line
			(start -0.875 -0.25)
			(end -0.875 0.25)
			(stroke
				(width 0.15)
				(type solid)
			)
			(layer "F.SilkS")
		)
		(fp_line
			(start -0.1 0.255)
			(end 0.1 0.255)
			(stroke
				(width 0.15)
				(type solid)
			)
			(layer "F.SilkS")
		)
		(fp_line
			(start 0.1 -0.255)
			(end -0.1 -0.255)
			(stroke
				(width 0.15)
				(type solid)
			)
			(layer "F.SilkS")
		)
		(fp_poly
			(pts
				(xy -0.925 -0.47) (xy 0.925 -0.47) (xy 0.925 0.47) (xy -0.925 0.47)
			)
			(stroke
				(width 0.05)
				(type default)
			)
			(fill none)
			(layer "F.CrtYd")
		)
		(fp_line
			(start -0.51 0.255)
			(end -0.51 -0.255)
			(stroke
				(width 0.15)
				(type solid)
			)
			(layer "F.Fab")
		)
		(fp_line
			(start -0.51 -0.255)
			(end 0.51 -0.255)
			(stroke
				(width 0.15)
				(type solid)
			)
			(layer "F.Fab")
		)
		(fp_line
			(start -0.2 -0.25)
			(end -0.5 0.05)
			(stroke
				(width 0.15)
				(type solid)
			)
			(layer "F.Fab")
		)
		(fp_line
			(start 0.51 0.255)
			(end -0.51 0.255)
			(stroke
				(width 0.15)
				(type solid)
			)
			(layer "F.Fab")
		)
		(fp_line
			(start 0.51 -0.255)
			(end 0.51 0.255)
			(stroke
				(width 0.15)
				(type solid)
			)
			(layer "F.Fab")
		)
		(fp_text user "Author: Antmicro"
			(at -2.54 6.94 -45)
			(layer "F.Fab")
			(hide yes)
			(effects
				(font
					(size 0.7 0.7)
					(thickness 0.15)
				)
				(justify left bottom)
			)
		)
		(fp_text user "${REFERENCE}"
			(at -2.54 4.54 -45)
			(layer "F.Fab")
			(hide yes)
			(effects
				(font
					(size 0.7 0.7)
					(thickness 0.15)
				)
				(justify left bottom)
			)
		)
		(fp_text user "License: Apache-2.0"
			(at -2.54 5.74 -45)
			(layer "F.Fab")
			(hide yes)
			(effects
				(font
					(size 0.7 0.7)
					(thickness 0.15)
				)
				(justify left bottom)
			)
		)
		(pad "1" smd roundrect
			(at -0.48 0 315)
			(size 0.59 0.64)
			(layers "F.Cu" "F.Paste" "F.Mask")
			(roundrect_rratio 0.25)
			(net 18 "/GMSL Connector/SIO_P")
			(pinfunction "C")
			(pintype "passive")
		)
		(pad "2" smd roundrect
			(at 0.48 0 315)
			(size 0.59 0.64)
			(layers "F.Cu" "F.Paste" "F.Mask")
			(roundrect_rratio 0.25)
			(net 1 "GND")
			(pinfunction "A")
			(pintype "passive")
		)
	)
	(footprint "antmicro-footprints:R_0402_1005Metric"
		(layer "F.Cu")
		(at 133.1 107.7)
		(descr "Resistor SMD 0402")
		(tags "resistor SMD 0402")
		(property "Reference" "R3"
			(at 1.05 -5.133332 0)
			(layer "F.SilkS")
			(effects
				(font
					(size 0.7 0.7)
					(thickness 0.15)
				)
				(justify left bottom)
			)
		)
		(property "Value" "R_100R_0402"
			(at -1.011843 1.772047 0)
			(layer "F.Fab")
			(effects
				(font
					(size 0.7 0.7)
					(thickness 0.15)
				)
				(justify left bottom)
			)
		)
		(property "Footprint" "antmicro-footprints:R_0402_1005Metric"
			(at 0 0 0)
			(layer "F.Fab")
			(hide yes)
			(effects
				(font
					(size 1.27 1.27)
					(thickness 0.15)
				)
			)
		)
		(property "Datasheet" "https://www.bourns.com/docs/product-datasheets/cr.pdf"
			(at 0 0 0)
			(layer "F.Fab")
			(hide yes)
			(effects
				(font
					(size 1.27 1.27)
					(thickness 0.15)
				)
			)
		)
		(property "Author" "Antmicro"
			(at 0 0 0)
			(layer "F.Fab")
			(hide yes)
			(effects
				(font
					(size 1 1)
					(thickness 0.15)
				)
			)
		)
		(property "License" "Apache-2.0"
			(at 0 0 0)
			(layer "F.Fab")
			(hide yes)
			(effects
				(font
					(size 1 1)
					(thickness 0.15)
				)
			)
		)
		(property "MPN" "CR0402-FX-1000GLF"
			(at 0 0 0)
			(layer "F.Fab")
			(hide yes)
			(effects
				(font
					(size 1 1)
					(thickness 0.15)
				)
			)
		)
		(property "Manufacturer" "Bourns"
			(at 0 0 0)
			(layer "F.Fab")
			(hide yes)
			(effects
				(font
					(size 1 1)
					(thickness 0.15)
				)
			)
		)
		(property "Tolerance" "1%"
			(at 0 0 0)
			(layer "F.Fab")
			(hide yes)
			(effects
				(font
					(size 1 1)
					(thickness 0.15)
				)
			)
		)
		(property "Val" "100R"
			(at 0 0 0)
			(layer "F.Fab")
			(hide yes)
			(effects
				(font
					(size 1 1)
					(thickness 0.15)
				)
			)
		)
		(sheetname "CSI Connector")
		(sheetfile "CSI.kicad_sch")
		(attr smd)
		(fp_rect
			(start -0.925 -0.47)
			(end 0.925 0.47)
			(stroke
				(width 0.05)
				(type default)
			)
			(fill none)
			(layer "F.CrtYd")
		)
		(fp_rect
			(start -0.5 -0.25)
			(end 0.5 0.25)
			(stroke
				(width 0.15)
				(type solid)
			)
			(fill none)
			(layer "F.Fab")
		)
		(fp_text user "${REFERENCE}"
			(at -0.95 3.168 0)
			(layer "F.Fab")
			(hide yes)
			(effects
				(font
					(size 0.7 0.7)
					(thickness 0.15)
				)
				(justify left bottom)
			)
		)
		(fp_text user "Author: Antmicro"
			(at -0.95 4.169 0)
			(layer "F.Fab")
			(hide yes)
			(effects
				(font
					(size 0.7 0.7)
					(thickness 0.15)
				)
				(justify left bottom)
			)
		)
		(fp_text user "License: Apache-2.0"
			(at -0.95 5.169 0)
			(layer "F.Fab")
			(hide yes)
			(effects
				(font
					(size 0.7 0.7)
					(thickness 0.15)
				)
				(justify left bottom)
			)
		)
		(pad "1" smd roundrect
			(at -0.48 0)
			(size 0.59 0.64)
			(layers "F.Cu" "F.Paste" "F.Mask")
			(roundrect_rratio 0.25)
			(net 34 "/CSI Connector/SDA_CAM0")
			(pintype "passive")
		)
		(pad "2" smd roundrect
			(at 0.48 0)
			(size 0.59 0.64)
			(layers "F.Cu" "F.Paste" "F.Mask")
			(roundrect_rratio 0.25)
			(net 88 "/CSI Connector/I2C.SDA")
			(pintype "passive")
		)
	)
	(footprint "antmicro-footprints:C_0402_1005Metric"
		(layer "F.Cu")
		(at 155.2 107.362 90)
		(descr "Capacitor SMD 0402")
		(tags "capacitor SMD 0402")
		(property "Reference" "C15"
			(at -1.088 -0.4 90)
			(layer "F.SilkS")
			(effects
				(font
					(size 0.7 0.7)
					(thickness 0.15)
				)
				(justify left bottom)
			)
		)
		(property "Value" "C_1u_16V_0402"
			(at -1.022927 2.155213 90)
			(layer "F.Fab")
			(effects
				(font
					(size 0.7 0.7)
					(thickness 0.15)
				)
				(justify left bottom)
			)
		)
		(property "Footprint" "antmicro-footprints:C_0402_1005Metric"
			(at 0 0 90)
			(layer "F.Fab")
			(hide yes)
			(effects
				(font
					(size 1.27 1.27)
					(thickness 0.15)
				)
			)
		)
		(property "Datasheet" "https://www.kemet.com/en/us/capacitors/product/C0402C105M4PACTU.html"
			(at 0 0 90)
			(layer "F.Fab")
			(hide yes)
			(effects
				(font
					(size 1.27 1.27)
					(thickness 0.15)
				)
			)
		)
		(property "Author" "Antmicro"
			(at 262.562 -47.838 0)
			(layer "F.Fab")
			(hide yes)
			(effects
				(font
					(size 1 1)
					(thickness 0.15)
				)
			)
		)
		(property "Dielectric" ""
			(at 262.562 -47.838 0)
			(layer "F.Fab")
			(hide yes)
			(effects
				(font
					(size 1 1)
					(thickness 0.15)
				)
			)
		)
		(property "License" "Apache-2.0"
			(at 262.562 -47.838 0)
			(layer "F.Fab")
			(hide yes)
			(effects
				(font
					(size 1 1)
					(thickness 0.15)
				)
			)
		)
		(property "MPN" "C0402C105M4PACTU"
			(at 262.562 -47.838 0)
			(layer "F.Fab")
			(hide yes)
			(effects
				(font
					(size 1 1)
					(thickness 0.15)
				)
			)
		)
		(property "Manufacturer" "KEMET"
			(at 262.562 -47.838 0)
			(layer "F.Fab")
			(hide yes)
			(effects
				(font
					(size 1 1)
					(thickness 0.15)
				)
			)
		)
		(property "Val" "1u"
			(at 262.562 -47.838 0)
			(layer "F.Fab")
			(hide yes)
			(effects
				(font
					(size 1 1)
					(thickness 0.15)
				)
			)
		)
		(property "Voltage" "16V"
			(at 262.562 -47.838 0)
			(layer "F.Fab")
			(hide yes)
			(effects
				(font
					(size 1 1)
					(thickness 0.15)
				)
			)
		)
		(sheetname "Supply")
		(sheetfile "supply.kicad_sch")
		(attr smd)
		(fp_rect
			(start -0.925 -0.47)
			(end 0.925 0.47)
			(stroke
				(width 0.05)
				(type default)
			)
			(fill none)
			(layer "F.CrtYd")
		)
		(fp_line
			(start 0.504 -0.25)
			(end 0.504 0.248)
			(stroke
				(width 0.15)
				(type solid)
			)
			(layer "F.Fab")
		)
		(fp_line
			(start -0.494 -0.25)
			(end 0.504 -0.25)
			(stroke
				(width 0.15)
				(type solid)
			)
			(layer "F.Fab")
		)
		(fp_line
			(start 0.504 0.248)
			(end -0.494 0.248)
			(stroke
				(width 0.15)
				(type solid)
			)
			(layer "F.Fab")
		)
		(fp_line
			(start -0.494 0.248)
			(end -0.494 -0.25)
			(stroke
				(width 0.15)
				(type solid)
			)
			(layer "F.Fab")
		)
		(fp_text user "${REFERENCE}"
			(at -0.939 4.599 90)
			(layer "F.Fab")
			(hide yes)
			(effects
				(font
					(size 0.7 0.7)
					(thickness 0.15)
				)
				(justify left bottom)
			)
		)
		(fp_text user "License: Apache-2.0"
			(at -0.939 5.799 90)
			(layer "F.Fab")
			(hide yes)
			(effects
				(font
					(size 0.7 0.7)
					(thickness 0.15)
				)
				(justify left bottom)
			)
		)
		(fp_text user "Author: Antmicro"
			(at -0.939 3.399 90)
			(layer "F.Fab")
			(hide yes)
			(effects
				(font
					(size 0.7 0.7)
					(thickness 0.15)
				)
				(justify left bottom)
			)
		)
		(pad "1" smd roundrect
			(at -0.48 0 90)
			(size 0.59 0.64)
			(layers "F.Cu" "F.Paste" "F.Mask")
			(roundrect_rratio 0.25)
			(net 1 "GND")
			(pintype "passive")
		)
		(pad "2" smd roundrect
			(at 0.48 0 90)
			(size 0.59 0.64)
			(layers "F.Cu" "F.Paste" "F.Mask")
			(roundrect_rratio 0.25)
			(net 12 "+1V2")
			(pintype "passive")
		)
	)
	(footprint "antmicro-footprints:TP_SMD_1.5mm"
		(layer "F.Cu")
		(at 156 118)
		(property "Reference" "TP8"
			(at -0.4 -1 0)
			(layer "F.SilkS")
			(hide yes)
			(effects
				(font
					(size 0.7 0.7)
					(thickness 0.15)
				)
				(justify left bottom)
			)
		)
		(property "Value" "TP_1.5mm_SMD"
			(at 0 1.7 0)
			(layer "F.Fab")
			(effects
				(font
					(size 0.7 0.7)
					(thickness 0.15)
				)
				(justify left bottom)
			)
		)
		(property "Footprint" "antmicro-footprints:TP_SMD_1.5mm"
			(at 0 0 0)
			(layer "F.Fab")
			(hide yes)
			(effects
				(font
					(size 1.27 1.27)
					(thickness 0.15)
				)
			)
		)
		(property "Author" "Antmicro"
			(at 0 0 0)
			(layer "F.Fab")
			(hide yes)
			(effects
				(font
					(size 1 1)
					(thickness 0.15)
				)
			)
		)
		(property "License" "Apache-2.0"
			(at 0 0 0)
			(layer "F.Fab")
			(hide yes)
			(effects
				(font
					(size 1 1)
					(thickness 0.15)
				)
			)
		)
		(property "MPN" ""
			(at 0 0 0)
			(layer "F.Fab")
			(hide yes)
			(effects
				(font
					(size 1 1)
					(thickness 0.15)
				)
			)
		)
		(property "Manufacturer" ""
			(at 0 0 0)
			(layer "F.Fab")
			(hide yes)
			(effects
				(font
					(size 1 1)
					(thickness 0.15)
				)
			)
		)
		(sheetname "Serializer")
		(sheetfile "serializer.kicad_sch")
		(attr exclude_from_pos_files exclude_from_bom)
		(fp_circle
			(center 0 0)
			(end 0.85 0)
			(stroke
				(width 0.05)
				(type default)
			)
			(fill none)
			(layer "F.CrtYd")
		)
		(fp_text user "${REFERENCE}"
			(at -0.7 2.9 0)
			(layer "F.Fab")
			(hide yes)
			(effects
				(font
					(size 0.7 0.7)
					(thickness 0.15)
				)
				(justify left bottom)
			)
		)
		(fp_text user "Author: Antmicro"
			(at -0.7 4.101 0)
			(layer "F.Fab")
			(hide yes)
			(effects
				(font
					(size 0.7 0.7)
					(thickness 0.15)
				)
				(justify left bottom)
			)
		)
		(fp_text user "License: Apache-2.0"
			(at -0.7 5.301 0)
			(layer "F.Fab")
			(hide yes)
			(effects
				(font
					(size 0.7 0.7)
					(thickness 0.15)
				)
				(justify left bottom)
			)
		)
		(pad "1" smd circle
			(at 0 0 270)
			(size 1.5 1.5)
			(layers "F.Cu" "F.Mask")
			(net 85 "Net-(U6-MFP6)")
			(pinfunction "1")
			(pintype "passive")
		)
	)
	(footprint "antmicro-footprints:SOT-23-5"
		(layer "F.Cu")
		(at 157.686 105.927 180)
		(property "Reference" "U5"
			(at -0.642 1.875 0)
			(layer "F.SilkS")
			(effects
				(font
					(size 0.7 0.7)
					(thickness 0.15)
				)
				(justify right bottom)
			)
		)
		(property "Value" "TLV73312PDBVT"
			(at 0.002 2.799 0)
			(layer "F.Fab")
			(effects
				(font
					(size 0.7 0.7)
					(thickness 0.15)
				)
				(justify right bottom)
			)
		)
		(property "Footprint" "antmicro-footprints:SOT-23-5"
			(at 0 0 180)
			(layer "F.Fab")
			(hide yes)
			(effects
				(font
					(size 1.27 1.27)
					(thickness 0.15)
				)
			)
		)
		(property "Datasheet" "https://www.ti.com/lit/ds/symlink/tlv733p.pdf?HQS=dis-mous-null-mousermode-dsf-pf-null-wwe&ts=1676978230940&ref_url=https%253A%252F%252Fwww.mouser.com%252F"
			(at 0 0 180)
			(layer "F.Fab")
			(hide yes)
			(effects
				(font
					(size 1.27 1.27)
					(thickness 0.15)
				)
			)
		)
		(property "Author" "Antmicro"
			(at 315.372 211.854 0)
			(layer "F.Fab")
			(hide yes)
			(effects
				(font
					(size 1 1)
					(thickness 0.15)
				)
			)
		)
		(property "License" "Apache-2.0"
			(at 315.372 211.854 0)
			(layer "F.Fab")
			(hide yes)
			(effects
				(font
					(size 1 1)
					(thickness 0.15)
				)
			)
		)
		(property "MPN" "TLV73312PDBVT"
			(at 315.372 211.854 0)
			(layer "F.Fab")
			(hide yes)
			(effects
				(font
					(size 1 1)
					(thickness 0.15)
				)
			)
		)
		(property "Manufacturer" "Texas Instruments"
			(at 315.372 211.854 0)
			(layer "F.Fab")
			(hide yes)
			(effects
				(font
					(size 1 1)
					(thickness 0.15)
				)
			)
		)
		(sheetname "Supply")
		(sheetfile "supply.kicad_sch")
		(attr smd)
		(fp_line
			(start 0.8 1.599)
			(end 0.549 1.599)
			(stroke
				(width 0.15)
				(type solid)
			)
			(layer "F.SilkS")
		)
		(fp_line
			(start 0.8 1.3)
			(end 0.8 1.599)
			(stroke
				(width 0.15)
				(type solid)
			)
			(layer "F.SilkS")
		)
		(fp_line
			(start 0.8 0.55)
			(end 0.8 -0.55)
			(stroke
				(width 0.15)
				(type solid)
			)
			(layer "F.SilkS")
		)
		(fp_line
			(start 0.8 -1.3)
			(end 0.8 -1.6)
			(stroke
				(width 0.15)
				(type solid)
			)
			(layer "F.SilkS")
		)
		(fp_line
			(start 0.8 -1.6)
			(end 0.5 -1.6)
			(stroke
				(width 0.15)
				(type solid)
			)
			(layer "F.SilkS")
		)
		(fp_line
			(start -0.55 1.6)
			(end -0.85 1.6)
			(stroke
				(width 0.15)
				(type solid)
			)
			(layer "F.SilkS")
		)
		(fp_line
			(start -0.8 -1.6)
			(end -0.5 -1.6)
			(stroke
				(width 0.15)
				(type solid)
			)
			(layer "F.SilkS")
		)
		(fp_line
			(start -0.8 -1.6)
			(end -0.8 -1.3)
			(stroke
				(width 0.15)
				(type solid)
			)
			(layer "F.SilkS")
		)
		(fp_line
			(start -0.85 1.6)
			(end -0.85 1.301)
			(stroke
				(width 0.15)
				(type solid)
			)
			(layer "F.SilkS")
		)
		(fp_circle
			(center -1.25 -1.5)
			(end -1.2 -1.5)
			(stroke
				(width 0.15)
				(type solid)
			)
			(fill solid)
			(layer "F.SilkS")
		)
		(fp_rect
			(start 1.9 -1.76)
			(end -1.9 1.75)
			(stroke
				(width 0.05)
				(type solid)
			)
			(fill none)
			(layer "F.CrtYd")
		)
		(fp_line
			(start -0.398 -1.526)
			(end -0.874 -1.05)
			(stroke
				(width 0.15)
				(type solid)
			)
			(layer "F.Fab")
		)
		(fp_rect
			(start 0.874 1.523)
			(end -0.873 -1.525)
			(stroke
				(width 0.15)
				(type solid)
			)
			(fill none)
			(layer "F.Fab")
		)
		(fp_text user "Author: Antmicro"
			(at -1.898 5.499 0)
			(layer "F.Fab")
			(hide yes)
			(effects
				(font
					(size 0.7 0.7)
					(thickness 0.15)
				)
				(justify right bottom)
			)
		)
		(fp_text user "${REFERENCE}"
			(at -1.898 4.299 0)
			(layer "F.Fab")
			(hide yes)
			(effects
				(font
					(size 0.7 0.7)
					(thickness 0.15)
				)
				(justify right bottom)
			)
		)
		(fp_text user "License: Apache-2.0"
			(at -1.898 6.7 0)
			(layer "F.Fab")
			(hide yes)
			(effects
				(font
					(size 0.7 0.7)
					(thickness 0.15)
				)
				(justify right bottom)
			)
		)
		(pad "1" smd rect
			(at -1.351 -0.951 90)
			(size 0.55 1)
			(layers "F.Cu" "F.Paste" "F.Mask")
			(net 11 "+1V8")
			(pinfunction "VIN")
			(pintype "power_in")
		)
		(pad "2" smd rect
			(at -1.351 0 90)
			(size 0.55 1)
			(layers "F.Cu" "F.Paste" "F.Mask")
			(net 1 "GND")
			(pinfunction "GND")
			(pintype "power_in")
		)
		(pad "3" smd rect
			(at -1.351 0.949 90)
			(size 0.55 1)
			(layers "F.Cu" "F.Paste" "F.Mask")
			(net 11 "+1V8")
			(pinfunction "EN")
			(pintype "input")
		)
		(pad "4" smd rect
			(at 1.35 0.949 90)
			(size 0.55 1)
			(layers "F.Cu" "F.Paste" "F.Mask")
			(net 86 "unconnected-(U5-NC-Pad4)")
			(pinfunction "NC")
			(pintype "no_connect")
		)
		(pad "5" smd rect
			(at 1.35 -0.951 90)
			(size 0.55 1)
			(layers "F.Cu" "F.Paste" "F.Mask")
			(net 12 "+1V2")
			(pinfunction "VOUT")
			(pintype "power_out")
		)
	)
	(footprint "antmicro-footprints:C_0402_1005Metric"
		(layer "F.Cu")
		(at 149.53 96.91 -45)
		(descr "Capacitor SMD 0402")
		(tags "capacitor SMD 0402")
		(property "Reference" "C22"
			(at 0.982878 -2.510229 -45)
			(unlocked yes)
			(layer "F.SilkS")
			(effects
				(font
					(size 0.7 0.7)
					(thickness 0.15)
				)
				(justify right bottom)
			)
		)
		(property "Value" "C_100n_0402"
			(at -1.022927 2.155213 135)
			(layer "F.Fab")
			(effects
				(font
					(size 0.7 0.7)
					(thickness 0.15)
				)
				(justify right bottom)
			)
		)
		(property "Footprint" "antmicro-footprints:C_0402_1005Metric"
			(at 0 0 -45)
			(layer "F.Fab")
			(hide yes)
			(effects
				(font
					(size 1.27 1.27)
					(thickness 0.15)
				)
			)
		)
		(property "Datasheet" "https://www.murata.com/products/productdetail?partno=GRM155R61H104KE14%23"
			(at 0 0 -45)
			(layer "F.Fab")
			(hide yes)
			(effects
				(font
					(size 1.27 1.27)
					(thickness 0.15)
				)
			)
		)
		(property "Author" "Antmicro"
			(at -24.729395 134.117959 0)
			(layer "F.Fab")
			(hide yes)
			(effects
				(font
					(size 1 1)
					(thickness 0.15)
				)
			)
		)
		(property "Dielectric" "X5R"
			(at -24.729395 134.117959 0)
			(layer "F.Fab")
			(hide yes)
			(effects
				(font
					(size 1 1)
					(thickness 0.15)
				)
			)
		)
		(property "License" "Apache-2.0"
			(at -24.729395 134.117959 0)
			(layer "F.Fab")
			(hide yes)
			(effects
				(font
					(size 1 1)
					(thickness 0.15)
				)
			)
		)
		(property "MPN" "GRM155R61H104KE14D"
			(at -24.729395 134.117959 0)
			(layer "F.Fab")
			(hide yes)
			(effects
				(font
					(size 1 1)
					(thickness 0.15)
				)
			)
		)
		(property "Manufacturer" "Murata"
			(at -24.729395 134.117959 0)
			(layer "F.Fab")
			(hide yes)
			(effects
				(font
					(size 1 1)
					(thickness 0.15)
				)
			)
		)
		(property "Val" "100n"
			(at -24.729395 134.117959 0)
			(layer "F.Fab")
			(hide yes)
			(effects
				(font
					(size 1 1)
					(thickness 0.15)
				)
			)
		)
		(property "Voltage" "50V"
			(at -24.729395 134.117959 0)
			(layer "F.Fab")
			(hide yes)
			(effects
				(font
					(size 1 1)
					(thickness 0.15)
				)
			)
		)
		(sheetname "Serializer")
		(sheetfile "serializer.kicad_sch")
		(attr smd)
		(fp_poly
			(pts
				(xy -0.925 -0.47) (xy 0.925 -0.47) (xy 0.925 0.47) (xy -0.925 0.47)
			)
			(stroke
				(width 0.05)
				(type default)
			)
			(fill none)
			(layer "F.CrtYd")
		)
		(fp_line
			(start -0.494 0.248)
			(end -0.494 -0.25)
			(stroke
				(width 0.15)
				(type solid)
			)
			(layer "F.Fab")
		)
		(fp_line
			(start -0.494 -0.25)
			(end 0.504 -0.25)
			(stroke
				(width 0.15)
				(type solid)
			)
			(layer "F.Fab")
		)
		(fp_line
			(start 0.504 0.248)
			(end -0.494 0.248)
			(stroke
				(width 0.15)
				(type solid)
			)
			(layer "F.Fab")
		)
		(fp_line
			(start 0.504 -0.25)
			(end 0.504 0.248)
			(stroke
				(width 0.15)
				(type solid)
			)
			(layer "F.Fab")
		)
		(fp_text user "Author: Antmicro"
			(at -0.939 3.399 135)
			(layer "F.Fab")
			(hide yes)
			(effects
				(font
					(size 0.7 0.7)
					(thickness 0.15)
				)
				(justify right bottom)
			)
		)
		(fp_text user "License: Apache-2.0"
			(at -0.939 5.799 135)
			(layer "F.Fab")
			(hide yes)
			(effects
				(font
					(size 0.7 0.7)
					(thickness 0.15)
				)
				(justify right bottom)
			)
		)
		(fp_text user "${REFERENCE}"
			(at -0.939 4.599 135)
			(layer "F.Fab")
			(hide yes)
			(effects
				(font
					(size 0.7 0.7)
					(thickness 0.15)
				)
				(justify right bottom)
			)
		)
		(pad "1" smd roundrect
			(at -0.48 0 315)
			(size 0.59 0.64)
			(layers "F.Cu" "F.Paste" "F.Mask")
			(roundrect_rratio 0.25)
			(net 1 "GND")
			(pintype "passive")
		)
		(pad "2" smd roundrect
			(at 0.48 0 315)
			(size 0.59 0.64)
			(layers "F.Cu" "F.Paste" "F.Mask")
			(roundrect_rratio 0.25)
			(net 12 "+1V2")
			(pintype "passive")
		)
	)
	(footprint "antmicro-footprints:DFN-10_2.5x1mm"
		(layer "F.Cu")
		(at 130.5 113.349)
		(property "Reference" "D4"
			(at -0.75 2.551 0)
			(layer "F.SilkS")
			(effects
				(font
					(size 0.7 0.7)
					(thickness 0.15)
				)
				(justify left bottom)
			)
		)
		(property "Value" "PESD4USB5U-TTS"
			(at 2.032 1.524 0)
			(layer "F.Fab")
			(effects
				(font
					(size 0.7 0.7)
					(thickness 0.15)
				)
				(justify left bottom)
			)
		)
		(property "Footprint" "antmicro-footprints:DFN-10_2.5x1mm"
			(at 0 0 0)
			(layer "F.Fab")
			(hide yes)
			(effects
				(font
					(size 1.27 1.27)
					(thickness 0.15)
				)
			)
		)
		(property "Datasheet" "https://assets.nexperia.com/documents/data-sheet/PESD4USB5U-TTS.pdf"
			(at 0 0 0)
			(layer "F.Fab")
			(hide yes)
			(effects
				(font
					(size 1.27 1.27)
					(thickness 0.15)
				)
			)
		)
		(property "Author" "Antmicro"
			(at 0 0 0)
			(layer "F.Fab")
			(hide yes)
			(effects
				(font
					(size 1 1)
					(thickness 0.15)
				)
			)
		)
		(property "License" "Apache-2.0"
			(at 0 0 0)
			(layer "F.Fab")
			(hide yes)
			(effects
				(font
					(size 1 1)
					(thickness 0.15)
				)
			)
		)
		(property "MPN" "PESD4USB5U-TTS"
			(at 0 0 0)
			(layer "F.Fab")
			(hide yes)
			(effects
				(font
					(size 1 1)
					(thickness 0.15)
				)
			)
		)
		(property "Manufacturer" "Nexperia"
			(at 0 0 0)
			(layer "F.Fab")
			(hide yes)
			(effects
				(font
					(size 1 1)
					(thickness 0.15)
				)
			)
		)
		(sheetname "CSI Connector")
		(sheetfile "CSI.kicad_sch")
		(attr smd)
		(fp_line
			(start -0.4 1.4)
			(end 0.4 1.4)
			(stroke
				(width 0.15)
				(type solid)
			)
			(layer "F.SilkS")
		)
		(fp_line
			(start 0.4 -1.4)
			(end -0.4 -1.4)
			(stroke
				(width 0.15)
				(type solid)
			)
			(layer "F.SilkS")
		)
		(fp_circle
			(center -0.762 -1.27)
			(end -0.712 -1.27)
			(stroke
				(width 0.15)
				(type solid)
			)
			(fill solid)
			(layer "F.SilkS")
		)
		(fp_rect
			(start -0.85 -1.6)
			(end 0.85 1.6)
			(stroke
				(width 0.05)
				(type solid)
			)
			(fill none)
			(layer "F.CrtYd")
		)
		(fp_line
			(start -0.5 -0.9)
			(end -0.5 1.25)
			(stroke
				(width 0.15)
				(type solid)
			)
			(layer "F.Fab")
		)
		(fp_line
			(start -0.5 1.25)
			(end 0.5 1.25)
			(stroke
				(width 0.15)
				(type solid)
			)
			(layer "F.Fab")
		)
		(fp_line
			(start -0.15 -1.25)
			(end -0.5 -0.9)
			(stroke
				(width 0.15)
				(type solid)
			)
			(layer "F.Fab")
		)
		(fp_line
			(start 0.5 -1.25)
			(end -0.15 -1.25)
			(stroke
				(width 0.15)
				(type solid)
			)
			(layer "F.Fab")
		)
		(fp_line
			(start 0.5 1.25)
			(end 0.5 -1.25)
			(stroke
				(width 0.15)
				(type solid)
			)
			(layer "F.Fab")
		)
		(fp_text user "License: Apache-2.0"
			(at -0.95 5.924 0)
			(layer "F.Fab")
			(hide yes)
			(effects
				(font
					(size 0.7 0.7)
					(thickness 0.15)
				)
				(justify left bottom)
			)
		)
		(fp_text user "Author: Antmicro"
			(at -0.95 4.724 0)
			(layer "F.Fab")
			(hide yes)
			(effects
				(font
					(size 0.7 0.7)
					(thickness 0.15)
				)
				(justify left bottom)
			)
		)
		(fp_text user "${REFERENCE}"
			(at -0.95 3.524 0)
			(layer "F.Fab")
			(hide yes)
			(effects
				(font
					(size 0.7 0.7)
					(thickness 0.15)
				)
				(justify left bottom)
			)
		)
		(pad "1" smd roundrect
			(at -0.425 -1 270)
			(size 0.2 0.6)
			(layers "F.Cu" "F.Paste" "F.Mask")
			(roundrect_rratio 0.25)
			(net 10 "+3V3")
			(pinfunction "1")
			(pintype "passive")
			(solder_mask_margin 0.05)
		)
		(pad "2" smd roundrect
			(at -0.425 -0.5 270)
			(size 0.2 0.6)
			(layers "F.Cu" "F.Paste" "F.Mask")
			(roundrect_rratio 0.25)
			(net 10 "+3V3")
			(pinfunction "2")
			(pintype "passive")
			(solder_mask_margin 0.05)
		)
		(pad "3" smd roundrect
			(at -0.425 0 270)
			(size 0.4 0.6)
			(layers "F.Cu" "F.Paste" "F.Mask")
			(roundrect_rratio 0.25)
			(net 1 "GND")
			(pinfunction "3")
			(pintype "passive")
			(solder_mask_margin 0.05)
		)
		(pad "4" smd roundrect
			(at -0.425 0.5 270)
			(size 0.2 0.6)
			(layers "F.Cu" "F.Paste" "F.Mask")
			(roundrect_rratio 0.25)
			(net 9 "+5V")
			(pinfunction "4")
			(pintype "passive")
			(solder_mask_margin 0.05)
		)
		(pad "5" smd roundrect
			(at -0.425 1 270)
			(size 0.2 0.6)
			(layers "F.Cu" "F.Paste" "F.Mask")
			(roundrect_rratio 0.25)
			(net 9 "+5V")
			(pinfunction "5")
			(pintype "passive")
			(solder_mask_margin 0.05)
		)
		(pad "6" smd roundrect
			(at 0.425 1 270)
			(size 0.2 0.6)
			(layers "F.Cu" "F.Paste" "F.Mask")
			(roundrect_rratio 0.25)
			(net 9 "+5V")
			(pinfunction "6")
			(pintype "passive")
			(solder_mask_margin 0.05)
		)
		(pad "7" smd roundrect
			(at 0.425 0.5 270)
			(size 0.2 0.6)
			(layers "F.Cu" "F.Paste" "F.Mask")
			(roundrect_rratio 0.25)
			(net 9 "+5V")
			(pinfunction "7")
			(pintype "passive")
			(solder_mask_margin 0.05)
		)
		(pad "8" smd roundrect
			(at 0.425 0 270)
			(size 0.4 0.6)
			(layers "F.Cu" "F.Paste" "F.Mask")
			(roundrect_rratio 0.25)
			(net 1 "GND")
			(pinfunction "8")
			(pintype "passive")
			(solder_mask_margin 0.05)
		)
		(pad "9" smd roundrect
			(at 0.425 -0.5 270)
			(size 0.2 0.6)
			(layers "F.Cu" "F.Paste" "F.Mask")
			(roundrect_rratio 0.25)
			(net 10 "+3V3")
			(pinfunction "9")
			(pintype "passive")
			(solder_mask_margin 0.05)
		)
		(pad "10" smd roundrect
			(at 0.425 -1 270)
			(size 0.2 0.6)
			(layers "F.Cu" "F.Paste" "F.Mask")
			(roundrect_rratio 0.25)
			(net 10 "+3V3")
			(pinfunction "10")
			(pintype "passive")
			(solder_mask_margin 0.05)
		)
	)
	(footprint "antmicro-footprints:MP_Pad6mm_Drill3mm"
		(layer "F.Cu")
		(at 127.15 81.35)
		(property "Reference" "MP4"
			(at 0 -3.2 0)
			(layer "F.SilkS")
			(hide yes)
			(effects
				(font
					(size 0.7 0.7)
					(thickness 0.15)
				)
				(justify left bottom)
			)
		)
		(property "Value" "MP_Pad6mm_Drill3mm"
			(at 0 3.9 0)
			(layer "F.Fab")
			(effects
				(font
					(size 0.7 0.7)
					(thickness 0.15)
				)
				(justify left bottom)
			)
		)
		(property "Footprint" "antmicro-footprints:MP_Pad6mm_Drill3mm"
			(at 0 0 0)
			(layer "F.Fab")
			(hide yes)
			(effects
				(font
					(size 1.27 1.27)
					(thickness 0.15)
				)
			)
		)
		(property "Author" "Antmicro"
			(at 0 0 0)
			(layer "F.Fab")
			(hide yes)
			(effects
				(font
					(size 1 1)
					(thickness 0.15)
				)
			)
		)
		(property "License" "Apache-2.0"
			(at 0 0 0)
			(layer "F.Fab")
			(hide yes)
			(effects
				(font
					(size 1 1)
					(thickness 0.15)
				)
			)
		)
		(sheetname "Root")
		(sheetfile "gmsl-serializer.kicad_sch")
		(attr exclude_from_pos_files exclude_from_bom)
		(fp_circle
			(center 0 0)
			(end 3.25 0)
			(stroke
				(width 0.05)
				(type default)
			)
			(fill none)
			(layer "F.CrtYd")
		)
		(fp_text user "${REFERENCE}"
			(at -0.178 6.025 0)
			(layer "F.Fab")
			(hide yes)
			(effects
				(font
					(size 0.7 0.7)
					(thickness 0.15)
				)
				(justify left bottom)
			)
		)
		(fp_text user "Author: Antmicro"
			(at -0.178 7.225 0)
			(layer "F.Fab")
			(hide yes)
			(effects
				(font
					(size 0.7 0.7)
					(thickness 0.15)
				)
				(justify left bottom)
			)
		)
		(fp_text user "License: Apache-2.0"
			(at -0.178 8.425 0)
			(layer "F.Fab")
			(hide yes)
			(effects
				(font
					(size 0.7 0.7)
					(thickness 0.15)
				)
				(justify left bottom)
			)
		)
		(pad "1" thru_hole circle
			(at 0 0)
			(size 6 6)
			(drill 3)
			(layers "*.Cu" "*.Mask")
			(remove_unused_layers no)
			(net 1 "GND")
			(pintype "passive")
			(solder_paste_margin_ratio -1)
		)
	)
	(footprint "antmicro-footprints:TP_SMD_1.5mm"
		(layer "F.Cu")
		(at 142.25 118)
		(property "Reference" "TP1"
			(at -1 -0.964 0)
			(layer "F.SilkS")
			(hide yes)
			(effects
				(font
					(size 0.7 0.7)
					(thickness 0.15)
				)
				(justify left bottom)
			)
		)
		(property "Value" "TP_1.5mm_SMD"
			(at 0 1.7 0)
			(layer "F.Fab")
			(effects
				(font
					(size 0.7 0.7)
					(thickness 0.15)
				)
				(justify left bottom)
			)
		)
		(property "Footprint" "antmicro-footprints:TP_SMD_1.5mm"
			(at 0 0 0)
			(layer "F.Fab")
			(hide yes)
			(effects
				(font
					(size 1.27 1.27)
					(thickness 0.15)
				)
			)
		)
		(property "Author" "Antmicro"
			(at 0 0 0)
			(layer "F.Fab")
			(hide yes)
			(effects
				(font
					(size 1 1)
					(thickness 0.15)
				)
			)
		)
		(property "License" "Apache-2.0"
			(at 0 0 0)
			(layer "F.Fab")
			(hide yes)
			(effects
				(font
					(size 1 1)
					(thickness 0.15)
				)
			)
		)
		(property "MPN" ""
			(at 0 0 0)
			(layer "F.Fab")
			(hide yes)
			(effects
				(font
					(size 1 1)
					(thickness 0.15)
				)
			)
		)
		(property "Manufacturer" ""
			(at 0 0 0)
			(layer "F.Fab")
			(hide yes)
			(effects
				(font
					(size 1 1)
					(thickness 0.15)
				)
			)
		)
		(sheetname "Supply")
		(sheetfile "supply.kicad_sch")
		(attr exclude_from_pos_files exclude_from_bom)
		(fp_circle
			(center 0 0)
			(end 0.85 0)
			(stroke
				(width 0.05)
				(type default)
			)
			(fill none)
			(layer "F.CrtYd")
		)
		(fp_text user "License: Apache-2.0"
			(at -0.7 5.301 0)
			(layer "F.Fab")
			(hide yes)
			(effects
				(font
					(size 0.7 0.7)
					(thickness 0.15)
				)
				(justify left bottom)
			)
		)
		(fp_text user "${REFERENCE}"
			(at -0.7 2.9 0)
			(layer "F.Fab")
			(hide yes)
			(effects
				(font
					(size 0.7 0.7)
					(thickness 0.15)
				)
				(justify left bottom)
			)
		)
		(fp_text user "Author: Antmicro"
			(at -0.7 4.101 0)
			(layer "F.Fab")
			(hide yes)
			(effects
				(font
					(size 0.7 0.7)
					(thickness 0.15)
				)
				(justify left bottom)
			)
		)
		(pad "1" smd circle
			(at 0 0 270)
			(size 1.5 1.5)
			(layers "F.Cu" "F.Mask")
			(net 9 "+5V")
			(pinfunction "1")
			(pintype "passive")
		)
	)
	(footprint "antmicro-footprints:R_0402_1005Metric"
		(layer "F.Cu")
		(at 151.7 115.355 -90)
		(descr "Resistor SMD 0402")
		(tags "resistor SMD 0402")
		(property "Reference" "R34"
			(at -1.122484 -1.35 90)
			(layer "F.SilkS")
			(effects
				(font
					(size 0.7 0.7)
					(thickness 0.15)
				)
				(justify right bottom)
			)
		)
		(property "Value" "R_100k_0402"
			(at -1.011843 1.772047 90)
			(layer "F.Fab")
			(effects
				(font
					(size 0.7 0.7)
					(thickness 0.15)
				)
				(justify right bottom)
			)
		)
		(property "Footprint" "antmicro-footprints:R_0402_1005Metric"
			(at 0 0 -90)
			(layer "F.Fab")
			(hide yes)
			(effects
				(font
					(size 1.27 1.27)
					(thickness 0.15)
				)
			)
		)
		(property "Datasheet" "https://www.bourns.com/docs/product-datasheets/cr.pdf"
			(at 0 0 -90)
			(layer "F.Fab")
			(hide yes)
			(effects
				(font
					(size 1.27 1.27)
					(thickness 0.15)
				)
			)
		)
		(property "Author" "Antmicro"
			(at 36.345 267.055 0)
			(layer "F.Fab")
			(hide yes)
			(effects
				(font
					(size 1 1)
					(thickness 0.15)
				)
			)
		)
		(property "License" "Apache-2.0"
			(at 36.345 267.055 0)
			(layer "F.Fab")
			(hide yes)
			(effects
				(font
					(size 1 1)
					(thickness 0.15)
				)
			)
		)
		(property "MPN" "CR0402-FX-1003GLF"
			(at 36.345 267.055 0)
			(layer "F.Fab")
			(hide yes)
			(effects
				(font
					(size 1 1)
					(thickness 0.15)
				)
			)
		)
		(property "Manufacturer" "Bourns"
			(at 36.345 267.055 0)
			(layer "F.Fab")
			(hide yes)
			(effects
				(font
					(size 1 1)
					(thickness 0.15)
				)
			)
		)
		(property "Tolerance" "1%"
			(at 36.345 267.055 0)
			(layer "F.Fab")
			(hide yes)
			(effects
				(font
					(size 1 1)
					(thickness 0.15)
				)
			)
		)
		(property "Val" "100k"
			(at 36.345 267.055 0)
			(layer "F.Fab")
			(hide yes)
			(effects
				(font
					(size 1 1)
					(thickness 0.15)
				)
			)
		)
		(sheetname "Supply")
		(sheetfile "supply.kicad_sch")
		(attr smd)
		(fp_rect
			(start -0.925 -0.47)
			(end 0.925 0.47)
			(stroke
				(width 0.05)
				(type default)
			)
			(fill none)
			(layer "F.CrtYd")
		)
		(fp_rect
			(start -0.5 -0.25)
			(end 0.5 0.25)
			(stroke
				(width 0.15)
				(type solid)
			)
			(fill none)
			(layer "F.Fab")
		)
		(fp_text user "License: Apache-2.0"
			(at -0.95 5.169 90)
			(layer "F.Fab")
			(hide yes)
			(effects
				(font
					(size 0.7 0.7)
					(thickness 0.15)
				)
				(justify right bottom)
			)
		)
		(fp_text user "Author: Antmicro"
			(at -0.95 4.169 90)
			(layer "F.Fab")
			(hide yes)
			(effects
				(font
					(size 0.7 0.7)
					(thickness 0.15)
				)
				(justify right bottom)
			)
		)
		(fp_text user "${REFERENCE}"
			(at -0.95 3.168 90)
			(layer "F.Fab")
			(hide yes)
			(effects
				(font
					(size 0.7 0.7)
					(thickness 0.15)
				)
				(justify right bottom)
			)
		)
		(pad "1" smd roundrect
			(at -0.48 0 270)
			(size 0.59 0.64)
			(layers "F.Cu" "F.Paste" "F.Mask")
			(roundrect_rratio 0.25)
			(net 1 "GND")
			(pintype "passive")
		)
		(pad "2" smd roundrect
			(at 0.48 0 270)
			(size 0.59 0.64)
			(layers "F.Cu" "F.Paste" "F.Mask")
			(roundrect_rratio 0.25)
			(net 12 "+1V2")
			(pintype "passive")
		)
	)
	(footprint "antmicro-footprints:DFN-10_2.5x1mm"
		(layer "F.Cu")
		(at 130.5 109.349)
		(property "Reference" "D1"
			(at -0.7 2.351 0)
			(layer "F.SilkS")
			(effects
				(font
					(size 0.7 0.7)
					(thickness 0.15)
				)
				(justify left bottom)
			)
		)
		(property "Value" "PESD4USB5U-TTS"
			(at 2.032 1.524 0)
			(layer "F.Fab")
			(effects
				(font
					(size 0.7 0.7)
					(thickness 0.15)
				)
				(justify left bottom)
			)
		)
		(property "Footprint" "antmicro-footprints:DFN-10_2.5x1mm"
			(at 0 0 0)
			(layer "F.Fab")
			(hide yes)
			(effects
				(font
					(size 1.27 1.27)
					(thickness 0.15)
				)
			)
		)
		(property "Datasheet" "https://assets.nexperia.com/documents/data-sheet/PESD4USB5U-TTS.pdf"
			(at 0 0 0)
			(layer "F.Fab")
			(hide yes)
			(effects
				(font
					(size 1.27 1.27)
					(thickness 0.15)
				)
			)
		)
		(property "Author" "Antmicro"
			(at 0 0 0)
			(layer "F.Fab")
			(hide yes)
			(effects
				(font
					(size 1 1)
					(thickness 0.15)
				)
			)
		)
		(property "License" "Apache-2.0"
			(at 0 0 0)
			(layer "F.Fab")
			(hide yes)
			(effects
				(font
					(size 1 1)
					(thickness 0.15)
				)
			)
		)
		(property "MPN" "PESD4USB5U-TTS"
			(at 0 0 0)
			(layer "F.Fab")
			(hide yes)
			(effects
				(font
					(size 1 1)
					(thickness 0.15)
				)
			)
		)
		(property "Manufacturer" "Nexperia"
			(at 0 0 0)
			(layer "F.Fab")
			(hide yes)
			(effects
				(font
					(size 1 1)
					(thickness 0.15)
				)
			)
		)
		(sheetname "CSI Connector")
		(sheetfile "CSI.kicad_sch")
		(attr smd)
		(fp_line
			(start -0.4 1.4)
			(end 0.4 1.4)
			(stroke
				(width 0.15)
				(type solid)
			)
			(layer "F.SilkS")
		)
		(fp_line
			(start 0.4 -1.4)
			(end -0.4 -1.4)
			(stroke
				(width 0.15)
				(type solid)
			)
			(layer "F.SilkS")
		)
		(fp_circle
			(center -0.762 -1.27)
			(end -0.712 -1.27)
			(stroke
				(width 0.15)
				(type solid)
			)
			(fill solid)
			(layer "F.SilkS")
		)
		(fp_rect
			(start -0.85 -1.6)
			(end 0.85 1.6)
			(stroke
				(width 0.05)
				(type solid)
			)
			(fill none)
			(layer "F.CrtYd")
		)
		(fp_line
			(start -0.5 -0.9)
			(end -0.5 1.25)
			(stroke
				(width 0.15)
				(type solid)
			)
			(layer "F.Fab")
		)
		(fp_line
			(start -0.5 1.25)
			(end 0.5 1.25)
			(stroke
				(width 0.15)
				(type solid)
			)
			(layer "F.Fab")
		)
		(fp_line
			(start -0.15 -1.25)
			(end -0.5 -0.9)
			(stroke
				(width 0.15)
				(type solid)
			)
			(layer "F.Fab")
		)
		(fp_line
			(start 0.5 -1.25)
			(end -0.15 -1.25)
			(stroke
				(width 0.15)
				(type solid)
			)
			(layer "F.Fab")
		)
		(fp_line
			(start 0.5 1.25)
			(end 0.5 -1.25)
			(stroke
				(width 0.15)
				(type solid)
			)
			(layer "F.Fab")
		)
		(fp_text user "License: Apache-2.0"
			(at -0.95 5.924 0)
			(layer "F.Fab")
			(hide yes)
			(effects
				(font
					(size 0.7 0.7)
					(thickness 0.15)
				)
				(justify left bottom)
			)
		)
		(fp_text user "Author: Antmicro"
			(at -0.95 4.724 0)
			(layer "F.Fab")
			(hide yes)
			(effects
				(font
					(size 0.7 0.7)
					(thickness 0.15)
				)
				(justify left bottom)
			)
		)
		(fp_text user "${REFERENCE}"
			(at -0.95 3.524 0)
			(layer "F.Fab")
			(hide yes)
			(effects
				(font
					(size 0.7 0.7)
					(thickness 0.15)
				)
				(justify left bottom)
			)
		)
		(pad "1" smd roundrect
			(at -0.425 -1 270)
			(size 0.2 0.6)
			(layers "F.Cu" "F.Paste" "F.Mask")
			(roundrect_rratio 0.25)
			(net 34 "/CSI Connector/SDA_CAM0")
			(pinfunction "1")
			(pintype "passive")
			(solder_mask_margin 0.05)
		)
		(pad "2" smd roundrect
			(at -0.425 -0.5 270)
			(size 0.2 0.6)
			(layers "F.Cu" "F.Paste" "F.Mask")
			(roundrect_rratio 0.25)
			(net 35 "/CSI Connector/SCL_CAM0")
			(pinfunction "2")
			(pintype "passive")
			(solder_mask_margin 0.05)
		)
		(pad "3" smd roundrect
			(at -0.425 0 270)
			(size 0.4 0.6)
			(layers "F.Cu" "F.Paste" "F.Mask")
			(roundrect_rratio 0.25)
			(net 1 "GND")
			(pinfunction "3")
			(pintype "passive")
			(solder_mask_margin 0.05)
		)
		(pad "4" smd roundrect
			(at -0.425 0.5 270)
			(size 0.2 0.6)
			(layers "F.Cu" "F.Paste" "F.Mask")
			(roundrect_rratio 0.25)
			(net 36 "/CSI Connector/SDA_CAM1")
			(pinfunction "4")
			(pintype "passive")
			(solder_mask_margin 0.05)
		)
		(pad "5" smd roundrect
			(at -0.425 1 270)
			(size 0.2 0.6)
			(layers "F.Cu" "F.Paste" "F.Mask")
			(roundrect_rratio 0.25)
			(net 37 "/CSI Connector/SCL_CAM1")
			(pinfunction "5")
			(pintype "passive")
			(solder_mask_margin 0.05)
		)
		(pad "6" smd roundrect
			(at 0.425 1 270)
			(size 0.2 0.6)
			(layers "F.Cu" "F.Paste" "F.Mask")
			(roundrect_rratio 0.25)
			(net 37 "/CSI Connector/SCL_CAM1")
			(pinfunction "6")
			(pintype "passive")
			(solder_mask_margin 0.05)
		)
		(pad "7" smd roundrect
			(at 0.425 0.5 270)
			(size 0.2 0.6)
			(layers "F.Cu" "F.Paste" "F.Mask")
			(roundrect_rratio 0.25)
			(net 36 "/CSI Connector/SDA_CAM1")
			(pinfunction "7")
			(pintype "passive")
			(solder_mask_margin 0.05)
		)
		(pad "8" smd roundrect
			(at 0.425 0 270)
			(size 0.4 0.6)
			(layers "F.Cu" "F.Paste" "F.Mask")
			(roundrect_rratio 0.25)
			(net 1 "GND")
			(pinfunction "8")
			(pintype "passive")
			(solder_mask_margin 0.05)
		)
		(pad "9" smd roundrect
			(at 0.425 -0.5 270)
			(size 0.2 0.6)
			(layers "F.Cu" "F.Paste" "F.Mask")
			(roundrect_rratio 0.25)
			(net 35 "/CSI Connector/SCL_CAM0")
			(pinfunction "9")
			(pintype "passive")
			(solder_mask_margin 0.05)
		)
		(pad "10" smd roundrect
			(at 0.425 -1 270)
			(size 0.2 0.6)
			(layers "F.Cu" "F.Paste" "F.Mask")
			(roundrect_rratio 0.25)
			(net 34 "/CSI Connector/SDA_CAM0")
			(pinfunction "10")
			(pintype "passive")
			(solder_mask_margin 0.05)
		)
	)
	(footprint "antmicro-footprints:R_0402_1005Metric"
		(layer "F.Cu")
		(at 163.95 98.125)
		(descr "Resistor SMD 0402")
		(tags "resistor SMD 0402")
		(property "Reference" "R8"
			(at -0.65 1.275 0)
			(layer "F.SilkS")
			(effects
				(font
					(size 0.7 0.7)
					(thickness 0.15)
				)
				(justify left bottom)
			)
		)
		(property "Value" "R_10k_0402"
			(at -1.011843 1.772047 0)
			(layer "F.Fab")
			(effects
				(font
					(size 0.7 0.7)
					(thickness 0.15)
				)
				(justify left bottom)
			)
		)
		(property "Footprint" "antmicro-footprints:R_0402_1005Metric"
			(at 0 0 0)
			(layer "F.Fab")
			(hide yes)
			(effects
				(font
					(size 1.27 1.27)
					(thickness 0.15)
				)
			)
		)
		(property "Datasheet" "https://www.bourns.com/docs/product-datasheets/cr.pdf"
			(at 0 0 0)
			(layer "F.Fab")
			(hide yes)
			(effects
				(font
					(size 1.27 1.27)
					(thickness 0.15)
				)
			)
		)
		(property "Author" "Antmicro"
			(at 0 0 0)
			(layer "F.Fab")
			(hide yes)
			(effects
				(font
					(size 1 1)
					(thickness 0.15)
				)
			)
		)
		(property "License" "Apache-2.0"
			(at 0 0 0)
			(layer "F.Fab")
			(hide yes)
			(effects
				(font
					(size 1 1)
					(thickness 0.15)
				)
			)
		)
		(property "MPN" "CR0402-FX-1002GLF"
			(at 0 0 0)
			(layer "F.Fab")
			(hide yes)
			(effects
				(font
					(size 1 1)
					(thickness 0.15)
				)
			)
		)
		(property "Manufacturer" "Bourns"
			(at 0 0 0)
			(layer "F.Fab")
			(hide yes)
			(effects
				(font
					(size 1 1)
					(thickness 0.15)
				)
			)
		)
		(property "Tolerance" "1%"
			(at 0 0 0)
			(layer "F.Fab")
			(hide yes)
			(effects
				(font
					(size 1 1)
					(thickness 0.15)
				)
			)
		)
		(property "Val" "10k"
			(at 0 0 0)
			(layer "F.Fab")
			(hide yes)
			(effects
				(font
					(size 1 1)
					(thickness 0.15)
				)
			)
		)
		(sheetname "Supply")
		(sheetfile "supply.kicad_sch")
		(attr smd)
		(fp_rect
			(start -0.925 -0.47)
			(end 0.925 0.47)
			(stroke
				(width 0.05)
				(type default)
			)
			(fill none)
			(layer "F.CrtYd")
		)
		(fp_rect
			(start -0.5 -0.25)
			(end 0.5 0.25)
			(stroke
				(width 0.15)
				(type solid)
			)
			(fill none)
			(layer "F.Fab")
		)
		(fp_text user "${REFERENCE}"
			(at -0.95 3.168 0)
			(layer "F.Fab")
			(hide yes)
			(effects
				(font
					(size 0.7 0.7)
					(thickness 0.15)
				)
				(justify left bottom)
			)
		)
		(fp_text user "License: Apache-2.0"
			(at -0.95 5.169 0)
			(layer "F.Fab")
			(hide yes)
			(effects
				(font
					(size 0.7 0.7)
					(thickness 0.15)
				)
				(justify left bottom)
			)
		)
		(fp_text user "Author: Antmicro"
			(at -0.95 4.169 0)
			(layer "F.Fab")
			(hide yes)
			(effects
				(font
					(size 0.7 0.7)
					(thickness 0.15)
				)
				(justify left bottom)
			)
		)
		(pad "1" smd roundrect
			(at -0.48 0)
			(size 0.59 0.64)
			(layers "F.Cu" "F.Paste" "F.Mask")
			(roundrect_rratio 0.25)
			(net 63 "/Supply/EN_1V8")
			(pintype "passive")
		)
		(pad "2" smd roundrect
			(at 0.48 0)
			(size 0.59 0.64)
			(layers "F.Cu" "F.Paste" "F.Mask")
			(roundrect_rratio 0.25)
			(net 2 "+12V")
			(pintype "passive")
		)
	)
	(footprint "antmicro-footprints:R_0402_1005Metric"
		(layer "F.Cu")
		(at 135.4 107.7)
		(descr "Resistor SMD 0402")
		(tags "resistor SMD 0402")
		(property "Reference" "R32"
			(at 0.9 0.4 0)
			(layer "F.SilkS")
			(effects
				(font
					(size 0.7 0.7)
					(thickness 0.15)
				)
				(justify left bottom)
			)
		)
		(property "Value" "R_0R_0402"
			(at -1.011843 1.772047 0)
			(layer "F.Fab")
			(effects
				(font
					(size 0.7 0.7)
					(thickness 0.15)
				)
				(justify left bottom)
			)
		)
		(property "Footprint" "antmicro-footprints:R_0402_1005Metric"
			(at 0 0 0)
			(layer "F.Fab")
			(hide yes)
			(effects
				(font
					(size 1.27 1.27)
					(thickness 0.15)
				)
			)
		)
		(property "Datasheet" "https://industrial.panasonic.com/cdbs/www-data/pdf/RDA0000/AOA0000C301.pdf"
			(at 0 0 0)
			(layer "F.Fab")
			(hide yes)
			(effects
				(font
					(size 1.27 1.27)
					(thickness 0.15)
				)
			)
		)
		(property "Author" "Antmicro"
			(at 0 0 0)
			(layer "F.Fab")
			(hide yes)
			(effects
				(font
					(size 1 1)
					(thickness 0.15)
				)
			)
		)
		(property "Current" "1A"
			(at 0 0 0)
			(layer "F.Fab")
			(hide yes)
			(effects
				(font
					(size 1 1)
					(thickness 0.15)
				)
			)
		)
		(property "License" "Apache-2.0"
			(at 0 0 0)
			(layer "F.Fab")
			(hide yes)
			(effects
				(font
					(size 1 1)
					(thickness 0.15)
				)
			)
		)
		(property "MPN" "ERJ2GE0R00X"
			(at 0 0 0)
			(layer "F.Fab")
			(hide yes)
			(effects
				(font
					(size 1 1)
					(thickness 0.15)
				)
			)
		)
		(property "Manufacturer" "Panasonic"
			(at 0 0 0)
			(layer "F.Fab")
			(hide yes)
			(effects
				(font
					(size 1 1)
					(thickness 0.15)
				)
			)
		)
		(property "Tolerance" ""
			(at 0 0 0)
			(layer "F.Fab")
			(hide yes)
			(effects
				(font
					(size 1 1)
					(thickness 0.15)
				)
			)
		)
		(property "Val" "0R"
			(at 0 0 0)
			(layer "F.Fab")
			(hide yes)
			(effects
				(font
					(size 1 1)
					(thickness 0.15)
				)
			)
		)
		(sheetname "Serializer")
		(sheetfile "serializer.kicad_sch")
		(attr smd)
		(fp_rect
			(start -0.925 -0.47)
			(end 0.925 0.47)
			(stroke
				(width 0.05)
				(type default)
			)
			(fill none)
			(layer "F.CrtYd")
		)
		(fp_rect
			(start -0.5 -0.25)
			(end 0.5 0.25)
			(stroke
				(width 0.15)
				(type solid)
			)
			(fill none)
			(layer "F.Fab")
		)
		(fp_text user "${REFERENCE}"
			(at -0.95 3.168 0)
			(layer "F.Fab")
			(hide yes)
			(effects
				(font
					(size 0.7 0.7)
					(thickness 0.15)
				)
				(justify left bottom)
			)
		)
		(fp_text user "Author: Antmicro"
			(at -0.95 4.169 0)
			(layer "F.Fab")
			(hide yes)
			(effects
				(font
					(size 0.7 0.7)
					(thickness 0.15)
				)
				(justify left bottom)
			)
		)
		(fp_text user "License: Apache-2.0"
			(at -0.95 5.169 0)
			(layer "F.Fab")
			(hide yes)
			(effects
				(font
					(size 0.7 0.7)
					(thickness 0.15)
				)
				(justify left bottom)
			)
		)
		(pad "1" smd roundrect
			(at -0.48 0)
			(size 0.59 0.64)
			(layers "F.Cu" "F.Paste" "F.Mask")
			(roundrect_rratio 0.25)
			(net 88 "/CSI Connector/I2C.SDA")
			(pintype "passive")
		)
		(pad "2" smd roundrect
			(at 0.48 0)
			(size 0.59 0.64)
			(layers "F.Cu" "F.Paste" "F.Mask")
			(roundrect_rratio 0.25)
			(net 81 "Net-(U6-MFP9)")
			(pintype "passive")
		)
	)
	(footprint "antmicro-footprints:C_0402_1005Metric"
		(layer "F.Cu")
		(at 137.78 85.647 -90)
		(descr "Capacitor SMD 0402")
		(tags "capacitor SMD 0402")
		(property "Reference" "C5"
			(at 0.773 -1.469 90)
			(layer "F.SilkS")
			(effects
				(font
					(size 0.7 0.7)
					(thickness 0.15)
				)
				(justify right bottom)
			)
		)
		(property "Value" "C_22u_0402"
			(at -1.022927 2.155213 90)
			(layer "F.Fab")
			(effects
				(font
					(size 0.7 0.7)
					(thickness 0.15)
				)
				(justify right bottom)
			)
		)
		(property "Footprint" "antmicro-footprints:C_0402_1005Metric"
			(at 0 0 -90)
			(layer "F.Fab")
			(hide yes)
			(effects
				(font
					(size 1.27 1.27)
					(thickness 0.15)
				)
			)
		)
		(property "Datasheet" "https://www.murata.com/products/productdetail?partno=GRM158R60J226ME01%23"
			(at 0 0 -90)
			(layer "F.Fab")
			(hide yes)
			(effects
				(font
					(size 1.27 1.27)
					(thickness 0.15)
				)
			)
		)
		(property "Author" "Antmicro"
			(at 54.053 225.047 0)
			(layer "F.Fab")
			(hide yes)
			(effects
				(font
					(size 1 1)
					(thickness 0.15)
				)
			)
		)
		(property "Dielectric" ""
			(at 54.053 225.047 0)
			(layer "F.Fab")
			(hide yes)
			(effects
				(font
					(size 1 1)
					(thickness 0.15)
				)
			)
		)
		(property "License" "Apache-2.0"
			(at 54.053 225.047 0)
			(layer "F.Fab")
			(hide yes)
			(effects
				(font
					(size 1 1)
					(thickness 0.15)
				)
			)
		)
		(property "MPN" "GRM158R60J226ME01D"
			(at 54.053 225.047 0)
			(layer "F.Fab")
			(hide yes)
			(effects
				(font
					(size 1 1)
					(thickness 0.15)
				)
			)
		)
		(property "Manufacturer" "Murata"
			(at 54.053 225.047 0)
			(layer "F.Fab")
			(hide yes)
			(effects
				(font
					(size 1 1)
					(thickness 0.15)
				)
			)
		)
		(property "Val" "22u"
			(at 54.053 225.047 0)
			(layer "F.Fab")
			(hide yes)
			(effects
				(font
					(size 1 1)
					(thickness 0.15)
				)
			)
		)
		(property "Voltage" ""
			(at 54.053 225.047 0)
			(layer "F.Fab")
			(hide yes)
			(effects
				(font
					(size 1 1)
					(thickness 0.15)
				)
			)
		)
		(sheetname "Supply")
		(sheetfile "supply.kicad_sch")
		(attr smd)
		(fp_rect
			(start -0.925 -0.47)
			(end 0.925 0.47)
			(stroke
				(width 0.05)
				(type default)
			)
			(fill none)
			(layer "F.CrtYd")
		)
		(fp_line
			(start -0.494 0.248)
			(end -0.494 -0.25)
			(stroke
				(width 0.15)
				(type solid)
			)
			(layer "F.Fab")
		)
		(fp_line
			(start 0.504 0.248)
			(end -0.494 0.248)
			(stroke
				(width 0.15)
				(type solid)
			)
			(layer "F.Fab")
		)
		(fp_line
			(start -0.494 -0.25)
			(end 0.504 -0.25)
			(stroke
				(width 0.15)
				(type solid)
			)
			(layer "F.Fab")
		)
		(fp_line
			(start 0.504 -0.25)
			(end 0.504 0.248)
			(stroke
				(width 0.15)
				(type solid)
			)
			(layer "F.Fab")
		)
		(fp_text user "License: Apache-2.0"
			(at -0.939 5.799 90)
			(layer "F.Fab")
			(hide yes)
			(effects
				(font
					(size 0.7 0.7)
					(thickness 0.15)
				)
				(justify right bottom)
			)
		)
		(fp_text user "Author: Antmicro"
			(at -0.939 3.399 90)
			(layer "F.Fab")
			(hide yes)
			(effects
				(font
					(size 0.7 0.7)
					(thickness 0.15)
				)
				(justify right bottom)
			)
		)
		(fp_text user "${REFERENCE}"
			(at -0.939 4.599 90)
			(layer "F.Fab")
			(hide yes)
			(effects
				(font
					(size 0.7 0.7)
					(thickness 0.15)
				)
				(justify right bottom)
			)
		)
		(pad "1" smd roundrect
			(at -0.48 0 270)
			(size 0.59 0.64)
			(layers "F.Cu" "F.Paste" "F.Mask")
			(roundrect_rratio 0.25)
			(net 1 "GND")
			(pintype "passive")
		)
		(pad "2" smd roundrect
			(at 0.48 0 270)
			(size 0.59 0.64)
			(layers "F.Cu" "F.Paste" "F.Mask")
			(roundrect_rratio 0.25)
			(net 7 "/Supply/OUT_5V")
			(pintype "passive")
		)
	)
	(footprint "antmicro-footprints:R_0402_1005Metric"
		(layer "F.Cu")
		(at 160.986 97.8 180)
		(descr "Resistor SMD 0402")
		(tags "resistor SMD 0402")
		(property "Reference" "R12"
			(at 0.886 -1.3 0)
			(layer "F.SilkS")
			(effects
				(font
					(size 0.7 0.7)
					(thickness 0.15)
				)
				(justify right bottom)
			)
		)
		(property "Value" "R_10k_0402"
			(at -1.011843 1.772047 0)
			(layer "F.Fab")
			(effects
				(font
					(size 0.7 0.7)
					(thickness 0.15)
				)
				(justify right bottom)
			)
		)
		(property "Footprint" "antmicro-footprints:R_0402_1005Metric"
			(at 0 0 180)
			(layer "F.Fab")
			(hide yes)
			(effects
				(font
					(size 1.27 1.27)
					(thickness 0.15)
				)
			)
		)
		(property "Datasheet" "https://www.bourns.com/docs/product-datasheets/cr.pdf"
			(at 0 0 180)
			(layer "F.Fab")
			(hide yes)
			(effects
				(font
					(size 1.27 1.27)
					(thickness 0.15)
				)
			)
		)
		(property "Author" "Antmicro"
			(at 321.972 195.6 0)
			(layer "F.Fab")
			(hide yes)
			(effects
				(font
					(size 1 1)
					(thickness 0.15)
				)
			)
		)
		(property "License" "Apache-2.0"
			(at 321.972 195.6 0)
			(layer "F.Fab")
			(hide yes)
			(effects
				(font
					(size 1 1)
					(thickness 0.15)
				)
			)
		)
		(property "MPN" "CR0402-FX-1002GLF"
			(at 321.972 195.6 0)
			(layer "F.Fab")
			(hide yes)
			(effects
				(font
					(size 1 1)
					(thickness 0.15)
				)
			)
		)
		(property "Manufacturer" "Bourns"
			(at 321.972 195.6 0)
			(layer "F.Fab")
			(hide yes)
			(effects
				(font
					(size 1 1)
					(thickness 0.15)
				)
			)
		)
		(property "Tolerance" "1%"
			(at 321.972 195.6 0)
			(layer "F.Fab")
			(hide yes)
			(effects
				(font
					(size 1 1)
					(thickness 0.15)
				)
			)
		)
		(property "Val" "10k"
			(at 321.972 195.6 0)
			(layer "F.Fab")
			(hide yes)
			(effects
				(font
					(size 1 1)
					(thickness 0.15)
				)
			)
		)
		(sheetname "Supply")
		(sheetfile "supply.kicad_sch")
		(attr smd)
		(fp_rect
			(start -0.925 -0.47)
			(end 0.925 0.47)
			(stroke
				(width 0.05)
				(type default)
			)
			(fill none)
			(layer "F.CrtYd")
		)
		(fp_rect
			(start -0.5 -0.25)
			(end 0.5 0.25)
			(stroke
				(width 0.15)
				(type solid)
			)
			(fill none)
			(layer "F.Fab")
		)
		(fp_text user "License: Apache-2.0"
			(at -0.95 5.169 0)
			(layer "F.Fab")
			(hide yes)
			(effects
				(font
					(size 0.7 0.7)
					(thickness 0.15)
				)
				(justify right bottom)
			)
		)
		(fp_text user "${REFERENCE}"
			(at -0.95 3.168 0)
			(layer "F.Fab")
			(hide yes)
			(effects
				(font
					(size 0.7 0.7)
					(thickness 0.15)
				)
				(justify right bottom)
			)
		)
		(fp_text user "Author: Antmicro"
			(at -0.95 4.169 0)
			(layer "F.Fab")
			(hide yes)
			(effects
				(font
					(size 0.7 0.7)
					(thickness 0.15)
				)
				(justify right bottom)
			)
		)
		(pad "1" smd roundrect
			(at -0.48 0 180)
			(size 0.59 0.64)
			(layers "F.Cu" "F.Paste" "F.Mask")
			(roundrect_rratio 0.25)
			(net 1 "GND")
			(pintype "passive")
		)
		(pad "2" smd roundrect
			(at 0.48 0 180)
			(size 0.59 0.64)
			(layers "F.Cu" "F.Paste" "F.Mask")
			(roundrect_rratio 0.25)
			(net 65 "/Supply/FB_1V8")
			(pintype "passive")
		)
	)
	(footprint "antmicro-footprints:C_0402_1005Metric"
		(layer "F.Cu")
		(at 150.45 98.025 45)
		(descr "Capacitor SMD 0402")
		(tags "capacitor SMD 0402")
		(property "Reference" "C31"
			(at 2.697612 0.420729 45)
			(layer "F.SilkS")
			(effects
				(font
					(size 0.7 0.7)
					(thickness 0.15)
				)
				(justify left bottom)
			)
		)
		(property "Value" "C_100n_0402"
			(at -1.022927 2.155213 45)
			(layer "F.Fab")
			(effects
				(font
					(size 0.7 0.7)
					(thickness 0.15)
				)
				(justify left bottom)
			)
		)
		(property "Footprint" "antmicro-footprints:C_0402_1005Metric"
			(at 0 0 45)
			(layer "F.Fab")
			(hide yes)
			(effects
				(font
					(size 1.27 1.27)
					(thickness 0.15)
				)
			)
		)
		(property "Datasheet" "https://www.murata.com/products/productdetail?partno=GRM155R61H104KE14%23"
			(at 0 0 45)
			(layer "F.Fab")
			(hide yes)
			(effects
				(font
					(size 1.27 1.27)
					(thickness 0.15)
				)
			)
		)
		(property "Author" "Antmicro"
			(at 113.379927 -77.673358 0)
			(layer "F.Fab")
			(hide yes)
			(effects
				(font
					(size 1 1)
					(thickness 0.15)
				)
			)
		)
		(property "Dielectric" "X5R"
			(at 113.379927 -77.673358 0)
			(layer "F.Fab")
			(hide yes)
			(effects
				(font
					(size 1 1)
					(thickness 0.15)
				)
			)
		)
		(property "License" "Apache-2.0"
			(at 113.379927 -77.673358 0)
			(layer "F.Fab")
			(hide yes)
			(effects
				(font
					(size 1 1)
					(thickness 0.15)
				)
			)
		)
		(property "MPN" "GRM155R61H104KE14D"
			(at 113.379927 -77.673358 0)
			(layer "F.Fab")
			(hide yes)
			(effects
				(font
					(size 1 1)
					(thickness 0.15)
				)
			)
		)
		(property "Manufacturer" "Murata"
			(at 113.379927 -77.673358 0)
			(layer "F.Fab")
			(hide yes)
			(effects
				(font
					(size 1 1)
					(thickness 0.15)
				)
			)
		)
		(property "Val" "100n"
			(at 113.379927 -77.673358 0)
			(layer "F.Fab")
			(hide yes)
			(effects
				(font
					(size 1 1)
					(thickness 0.15)
				)
			)
		)
		(property "Voltage" "50V"
			(at 113.379927 -77.673358 0)
			(layer "F.Fab")
			(hide yes)
			(effects
				(font
					(size 1 1)
					(thickness 0.15)
				)
			)
		)
		(sheetname "Serializer")
		(sheetfile "serializer.kicad_sch")
		(attr smd)
		(fp_poly
			(pts
				(xy -0.925 -0.47) (xy 0.925 -0.47) (xy 0.925 0.47) (xy -0.925 0.47)
			)
			(stroke
				(width 0.05)
				(type default)
			)
			(fill none)
			(layer "F.CrtYd")
		)
		(fp_line
			(start -0.494 -0.25)
			(end 0.504 -0.25)
			(stroke
				(width 0.15)
				(type solid)
			)
			(layer "F.Fab")
		)
		(fp_line
			(start -0.494 0.248)
			(end -0.494 -0.25)
			(stroke
				(width 0.15)
				(type solid)
			)
			(layer "F.Fab")
		)
		(fp_line
			(start 0.504 -0.25)
			(end 0.504 0.248)
			(stroke
				(width 0.15)
				(type solid)
			)
			(layer "F.Fab")
		)
		(fp_line
			(start 0.504 0.248)
			(end -0.494 0.248)
			(stroke
				(width 0.15)
				(type solid)
			)
			(layer "F.Fab")
		)
		(fp_text user "${REFERENCE}"
			(at -0.939 4.599 45)
			(layer "F.Fab")
			(hide yes)
			(effects
				(font
					(size 0.7 0.7)
					(thickness 0.15)
				)
				(justify left bottom)
			)
		)
		(fp_text user "Author: Antmicro"
			(at -0.939 3.399 45)
			(layer "F.Fab")
			(hide yes)
			(effects
				(font
					(size 0.7 0.7)
					(thickness 0.15)
				)
				(justify left bottom)
			)
		)
		(fp_text user "License: Apache-2.0"
			(at -0.939 5.799 45)
			(layer "F.Fab")
			(hide yes)
			(effects
				(font
					(size 0.7 0.7)
					(thickness 0.15)
				)
				(justify left bottom)
			)
		)
		(pad "1" smd roundrect
			(at -0.48 0 45)
			(size 0.59 0.64)
			(layers "F.Cu" "F.Paste" "F.Mask")
			(roundrect_rratio 0.25)
			(net 33 "Net-(U6-SION)")
			(pintype "passive")
		)
		(pad "2" smd roundrect
			(at 0.48 0 45)
			(size 0.59 0.64)
			(layers "F.Cu" "F.Paste" "F.Mask")
			(roundrect_rratio 0.25)
			(net 16 "Net-(C31-Pad2)")
			(pintype "passive")
		)
	)
	(footprint "antmicro-footprints:TSOT23-6"
		(layer "F.Cu")
		(at 133.779 83.45 180)
		(property "Reference" "U1"
			(at -0.722 1.766 0)
			(layer "F.SilkS")
			(effects
				(font
					(size 0.7 0.7)
					(thickness 0.15)
				)
				(justify right bottom)
			)
		)
		(property "Value" "AP62301_TSOT"
			(at -1.44 3.9 0)
			(layer "F.Fab")
			(effects
				(font
					(size 0.7 0.7)
					(thickness 0.15)
				)
				(justify right bottom)
			)
		)
		(property "Footprint" "antmicro-footprints:TSOT23-6"
			(at 0 0 180)
			(layer "F.Fab")
			(hide yes)
			(effects
				(font
					(size 1.27 1.27)
					(thickness 0.15)
				)
			)
		)
		(property "Datasheet" "https://www.diodes.com/assets/Datasheets/AP62300_AP62301_AP62300T.pdf"
			(at 0 0 180)
			(layer "F.Fab")
			(hide yes)
			(effects
				(font
					(size 1.27 1.27)
					(thickness 0.15)
				)
			)
		)
		(property "Author" "Antmicro"
			(at 271.098 166.6 0)
			(layer "F.Fab")
			(hide yes)
			(effects
				(font
					(size 1 1)
					(thickness 0.15)
				)
			)
		)
		(property "License" "Apache-2.0"
			(at 271.098 166.6 0)
			(layer "F.Fab")
			(hide yes)
			(effects
				(font
					(size 1 1)
					(thickness 0.15)
				)
			)
		)
		(property "MPN" "AP62301WU-7"
			(at 271.098 166.6 0)
			(layer "F.Fab")
			(hide yes)
			(effects
				(font
					(size 1 1)
					(thickness 0.15)
				)
			)
		)
		(property "Manufacturer" "Diodes Incorporated"
			(at 271.098 166.6 0)
			(layer "F.Fab")
			(hide yes)
			(effects
				(font
					(size 1 1)
					(thickness 0.15)
				)
			)
		)
		(sheetname "Supply")
		(sheetfile "supply.kicad_sch")
		(attr smd)
		(fp_line
			(start 1 1.55)
			(end 1 1.4)
			(stroke
				(width 0.15)
				(type solid)
			)
			(layer "F.SilkS")
		)
		(fp_line
			(start 1 1.55)
			(end -1 1.55)
			(stroke
				(width 0.15)
				(type solid)
			)
			(layer "F.SilkS")
		)
		(fp_line
			(start 1 -1.497)
			(end 1 -1.375)
			(stroke
				(width 0.15)
				(type solid)
			)
			(layer "F.SilkS")
		)
		(fp_line
			(start 1 -1.497)
			(end -1 -1.5)
			(stroke
				(width 0.15)
				(type solid)
			)
			(layer "F.SilkS")
		)
		(fp_line
			(start -1 1.55)
			(end -1 1.4)
			(stroke
				(width 0.15)
				(type solid)
			)
			(layer "F.SilkS")
		)
		(fp_line
			(start -1 -1.5)
			(end -1 -1.375)
			(stroke
				(width 0.15)
				(type solid)
			)
			(layer "F.SilkS")
		)
		(fp_circle
			(center -1.44 -1.5)
			(end -1.39 -1.5)
			(stroke
				(width 0.15)
				(type solid)
			)
			(fill solid)
			(layer "F.SilkS")
		)
		(fp_rect
			(start 1.93 -1.7)
			(end -1.93 1.7)
			(stroke
				(width 0.05)
				(type solid)
			)
			(fill none)
			(layer "F.CrtYd")
		)
		(fp_line
			(start -0.45 -1.521)
			(end -0.876 -1.096)
			(stroke
				(width 0.15)
				(type solid)
			)
			(layer "F.Fab")
		)
		(fp_rect
			(start 0.875 1.528)
			(end -0.875 -1.525)
			(stroke
				(width 0.15)
				(type solid)
			)
			(fill none)
			(layer "F.Fab")
		)
		(fp_text user "License: Apache-2.0"
			(at -1.93 6.199 0)
			(layer "F.Fab")
			(hide yes)
			(effects
				(font
					(size 0.7 0.7)
					(thickness 0.15)
				)
				(justify right bottom)
			)
		)
		(fp_text user "Author: Antmicro"
			(at -1.93 5 0)
			(layer "F.Fab")
			(hide yes)
			(effects
				(font
					(size 0.7 0.7)
					(thickness 0.15)
				)
				(justify right bottom)
			)
		)
		(fp_text user "${REFERENCE}"
			(at -1.93 3.8 0)
			(layer "F.Fab")
			(hide yes)
			(effects
				(font
					(size 0.7 0.7)
					(thickness 0.15)
				)
				(justify right bottom)
			)
		)
		(pad "1" smd rect
			(at -1.301 -0.947 90)
			(size 0.7 1.2)
			(layers "F.Cu" "F.Paste" "F.Mask")
			(net 1 "GND")
			(pinfunction "GND")
			(pintype "power_in")
		)
		(pad "2" smd rect
			(at -1.301 0.004 90)
			(size 0.7 1.2)
			(layers "F.Cu" "F.Paste" "F.Mask")
			(net 4 "/Supply/SW_5V")
			(pinfunction "SW")
			(pintype "power_out")
		)
		(pad "3" smd rect
			(at -1.301 0.954 90)
			(size 0.7 1.2)
			(layers "F.Cu" "F.Paste" "F.Mask")
			(net 2 "+12V")
			(pinfunction "VIN")
			(pintype "power_in")
		)
		(pad "4" smd rect
			(at 1.299 0.954 90)
			(size 0.7 1.2)
			(layers "F.Cu" "F.Paste" "F.Mask")
			(net 64 "/Supply/FB_5V")
			(pinfunction "FB")
			(pintype "input")
		)
		(pad "5" smd rect
			(at 1.299 0.004 90)
			(size 0.7 1.2)
			(layers "F.Cu" "F.Paste" "F.Mask")
			(net 62 "/Supply/EN_5V")
			(pinfunction "EN")
			(pintype "input")
		)
		(pad "6" smd rect
			(at 1.299 -0.947 90)
			(size 0.7 1.2)
			(layers "F.Cu" "F.Paste" "F.Mask")
			(net 3 "Net-(U1-BST)")
			(pinfunction "BST")
			(pintype "output")
		)
	)
	(footprint "antmicro-footprints:R_0402_1005Metric"
		(layer "F.Cu")
		(at 138.35 115.525 90)
		(descr "Resistor SMD 0402")
		(tags "resistor SMD 0402")
		(property "Reference" "R40"
			(at 0.875 0.45 90)
			(layer "F.SilkS")
			(effects
				(font
					(size 0.7 0.7)
					(thickness 0.15)
				)
				(justify left bottom)
			)
		)
		(property "Value" "R_1k65_0402"
			(at -1.011843 1.772047 90)
			(layer "F.Fab")
			(effects
				(font
					(size 0.7 0.7)
					(thickness 0.15)
				)
				(justify left bottom)
			)
		)
		(property "Footprint" "antmicro-footprints:R_0402_1005Metric"
			(at 0 0 90)
			(layer "F.Fab")
			(hide yes)
			(effects
				(font
					(size 1.27 1.27)
					(thickness 0.15)
				)
			)
		)
		(property "Datasheet" "https://www.farnell.com/datasheets/3795017.pdf"
			(at 0 0 90)
			(layer "F.Fab")
			(hide yes)
			(effects
				(font
					(size 1.27 1.27)
					(thickness 0.15)
				)
			)
		)
		(property "Author" "Antmicro"
			(at 253.875 -22.825 0)
			(layer "F.Fab")
			(hide yes)
			(effects
				(font
					(size 1 1)
					(thickness 0.15)
				)
			)
		)
		(property "License" "Apache-2.0"
			(at 253.875 -22.825 0)
			(layer "F.Fab")
			(hide yes)
			(effects
				(font
					(size 1 1)
					(thickness 0.15)
				)
			)
		)
		(property "MPN" "RC0402FR-071K65L"
			(at 253.875 -22.825 0)
			(layer "F.Fab")
			(hide yes)
			(effects
				(font
					(size 1 1)
					(thickness 0.15)
				)
			)
		)
		(property "Manufacturer" "YAGEO"
			(at 253.875 -22.825 0)
			(layer "F.Fab")
			(hide yes)
			(effects
				(font
					(size 1 1)
					(thickness 0.15)
				)
			)
		)
		(property "Public" ""
			(at 253.875 -22.825 0)
			(layer "F.Fab")
			(hide yes)
			(effects
				(font
					(size 1 1)
					(thickness 0.15)
				)
			)
		)
		(property "Tolerance" "1%"
			(at 253.875 -22.825 0)
			(layer "F.Fab")
			(hide yes)
			(effects
				(font
					(size 1 1)
					(thickness 0.15)
				)
			)
		)
		(property "Val" "1k65"
			(at 253.875 -22.825 0)
			(layer "F.Fab")
			(hide yes)
			(effects
				(font
					(size 1 1)
					(thickness 0.15)
				)
			)
		)
		(sheetname "Supply")
		(sheetfile "supply.kicad_sch")
		(attr smd)
		(fp_rect
			(start -0.925 -0.47)
			(end 0.925 0.47)
			(stroke
				(width 0.05)
				(type default)
			)
			(fill none)
			(layer "F.CrtYd")
		)
		(fp_rect
			(start -0.5 -0.25)
			(end 0.5 0.25)
			(stroke
				(width 0.15)
				(type solid)
			)
			(fill none)
			(layer "F.Fab")
		)
		(fp_text user "License: Apache-2.0"
			(at -0.95 5.169 90)
			(layer "F.Fab")
			(hide yes)
			(effects
				(font
					(size 0.7 0.7)
					(thickness 0.15)
				)
				(justify left bottom)
			)
		)
		(fp_text user "${REFERENCE}"
			(at -0.95 3.168 90)
			(layer "F.Fab")
			(hide yes)
			(effects
				(font
					(size 0.7 0.7)
					(thickness 0.15)
				)
				(justify left bottom)
			)
		)
		(fp_text user "Author: Antmicro"
			(at -0.95 4.169 90)
			(layer "F.Fab")
			(hide yes)
			(effects
				(font
					(size 0.7 0.7)
					(thickness 0.15)
				)
				(justify left bottom)
			)
		)
		(pad "1" smd roundrect
			(at -0.48 0 90)
			(size 0.59 0.64)
			(layers "F.Cu" "F.Paste" "F.Mask")
			(roundrect_rratio 0.25)
			(net 1 "GND")
			(pintype "passive")
		)
		(pad "2" smd roundrect
			(at 0.48 0 90)
			(size 0.59 0.64)
			(layers "F.Cu" "F.Paste" "F.Mask")
			(roundrect_rratio 0.25)
			(net 75 "Net-(D9-C)")
			(pintype "passive")
		)
	)
	(footprint "antmicro-footprints:L_0806_2016Metric"
		(layer "F.Cu")
		(at 161.6 103.8)
		(property "Reference" "L2"
			(at -0.75 1.9 0)
			(layer "F.SilkS")
			(effects
				(font
					(size 0.7 0.7)
					(thickness 0.15)
				)
				(justify left bottom)
			)
		)
		(property "Value" "L_1u_2.6A_0806"
			(at 0 2 0)
			(layer "F.Fab")
			(effects
				(font
					(size 0.7 0.7)
					(thickness 0.15)
				)
				(justify left bottom)
			)
		)
		(property "Footprint" "antmicro-footprints:L_0806_2016Metric"
			(at 0 0 0)
			(layer "F.Fab")
			(hide yes)
			(effects
				(font
					(size 1.27 1.27)
					(thickness 0.15)
				)
			)
		)
		(property "Datasheet" "https://www.bourns.com/docs/Product-Datasheets/SRP2010.pdf"
			(at 0 0 0)
			(layer "F.Fab")
			(hide yes)
			(effects
				(font
					(size 1.27 1.27)
					(thickness 0.15)
				)
			)
		)
		(property "Author" "Antmicro"
			(at 0 0 0)
			(layer "F.Fab")
			(hide yes)
			(effects
				(font
					(size 1 1)
					(thickness 0.15)
				)
			)
		)
		(property "IMax" "2.6 A"
			(at 0 0 0)
			(layer "F.Fab")
			(hide yes)
			(effects
				(font
					(size 1 1)
					(thickness 0.15)
				)
			)
		)
		(property "ISat" "2.9 A"
			(at 0 0 0)
			(layer "F.Fab")
			(hide yes)
			(effects
				(font
					(size 1 1)
					(thickness 0.15)
				)
			)
		)
		(property "License" "Apache-2.0"
			(at 0 0 0)
			(layer "F.Fab")
			(hide yes)
			(effects
				(font
					(size 1 1)
					(thickness 0.15)
				)
			)
		)
		(property "MPN" "SRP2010-1R0M"
			(at 0 0 0)
			(layer "F.Fab")
			(hide yes)
			(effects
				(font
					(size 1 1)
					(thickness 0.15)
				)
			)
		)
		(property "Manufacturer" "Bourns"
			(at 0 0 0)
			(layer "F.Fab")
			(hide yes)
			(effects
				(font
					(size 1 1)
					(thickness 0.15)
				)
			)
		)
		(property "Size" "2.0x1.6"
			(at 0 0 0)
			(layer "F.Fab")
			(hide yes)
			(effects
				(font
					(size 1 1)
					(thickness 0.15)
				)
			)
		)
		(property "Val" "1u/2.6A"
			(at 0 0 0)
			(layer "F.Fab")
			(hide yes)
			(effects
				(font
					(size 1 1)
					(thickness 0.15)
				)
			)
		)
		(sheetname "Supply")
		(sheetfile "supply.kicad_sch")
		(attr smd)
		(fp_line
			(start -0.301 0.9)
			(end 0.299 0.9)
			(stroke
				(width 0.15)
				(type solid)
			)
			(layer "F.SilkS")
		)
		(fp_line
			(start -0.3 -0.9)
			(end 0.298 -0.9)
			(stroke
				(width 0.15)
				(type solid)
			)
			(layer "F.SilkS")
		)
		(fp_rect
			(start -1.75 -1.05)
			(end 1.75 1.05)
			(stroke
				(width 0.05)
				(type solid)
			)
			(fill none)
			(layer "F.CrtYd")
		)
		(fp_rect
			(start -0.951 -0.882)
			(end 0.949 0.875)
			(stroke
				(width 0.15)
				(type solid)
			)
			(fill none)
			(layer "F.Fab")
		)
		(fp_text user "Author: Antmicro"
			(at -1.9 4.4 0)
			(layer "F.Fab")
			(hide yes)
			(effects
				(font
					(size 0.7 0.7)
					(thickness 0.15)
				)
				(justify left bottom)
			)
		)
		(fp_text user "${REFERENCE}"
			(at -1.9 3.1 0)
			(layer "F.Fab")
			(hide yes)
			(effects
				(font
					(size 0.7 0.7)
					(thickness 0.15)
				)
				(justify left bottom)
			)
		)
		(fp_text user "License: Apache-2.0"
			(at -1.9 5.75 0)
			(layer "F.Fab")
			(hide yes)
			(effects
				(font
					(size 0.7 0.7)
					(thickness 0.15)
				)
				(justify left bottom)
			)
		)
		(pad "1" smd roundrect
			(at -1.1 -0.001)
			(size 1 1.8)
			(layers "F.Cu" "F.Paste" "F.Mask")
			(roundrect_rratio 0.15)
			(net 6 "/Supply/SW_1V8")
			(pintype "passive")
		)
		(pad "2" smd roundrect
			(at 1.1 -0.001)
			(size 1 1.8)
			(layers "F.Cu" "F.Paste" "F.Mask")
			(roundrect_rratio 0.15)
			(net 8 "/Supply/OUT_1V8")
			(pintype "passive")
		)
	)
	(footprint "antmicro-footprints:TSOT23-6"
		(layer "F.Cu")
		(at 161.8 101 180)
		(property "Reference" "U2"
			(at 2.1 1.7 90)
			(layer "F.SilkS")
			(effects
				(font
					(size 0.7 0.7)
					(thickness 0.15)
				)
				(justify right bottom)
			)
		)
		(property "Value" "AP62301_TSOT"
			(at 0 2.6 0)
			(layer "F.Fab")
			(effects
				(font
					(size 0.7 0.7)
					(thickness 0.15)
				)
				(justify right bottom)
			)
		)
		(property "Footprint" "antmicro-footprints:TSOT23-6"
			(at 0 0 180)
			(layer "F.Fab")
			(hide yes)
			(effects
				(font
					(size 1.27 1.27)
					(thickness 0.15)
				)
			)
		)
		(property "Datasheet" "https://www.diodes.com/assets/Datasheets/AP62300_AP62301_AP62300T.pdf"
			(at 0 0 180)
			(layer "F.Fab")
			(hide yes)
			(effects
				(font
					(size 1.27 1.27)
					(thickness 0.15)
				)
			)
		)
		(property "Author" "Antmicro"
			(at 323.6 202 0)
			(layer "F.Fab")
			(hide yes)
			(effects
				(font
					(size 1 1)
					(thickness 0.15)
				)
			)
		)
		(property "License" "Apache-2.0"
			(at 323.6 202 0)
			(layer "F.Fab")
			(hide yes)
			(effects
				(font
					(size 1 1)
					(thickness 0.15)
				)
			)
		)
		(property "MPN" "AP62301WU-7"
			(at 323.6 202 0)
			(layer "F.Fab")
			(hide yes)
			(effects
				(font
					(size 1 1)
					(thickness 0.15)
				)
			)
		)
		(property "Manufacturer" "Diodes Incorporated"
			(at 323.6 202 0)
			(layer "F.Fab")
			(hide yes)
			(effects
				(font
					(size 1 1)
					(thickness 0.15)
				)
			)
		)
		(sheetname "Supply")
		(sheetfile "supply.kicad_sch")
		(attr smd)
		(fp_line
			(start 1 1.55)
			(end 1 1.4)
			(stroke
				(width 0.15)
				(type solid)
			)
			(layer "F.SilkS")
		)
		(fp_line
			(start 1 1.55)
			(end -1 1.55)
			(stroke
				(width 0.15)
				(type solid)
			)
			(layer "F.SilkS")
		)
		(fp_line
			(start 1 -1.497)
			(end 1 -1.375)
			(stroke
				(width 0.15)
				(type solid)
			)
			(layer "F.SilkS")
		)
		(fp_line
			(start 1 -1.497)
			(end -1 -1.5)
			(stroke
				(width 0.15)
				(type solid)
			)
			(layer "F.SilkS")
		)
		(fp_line
			(start -1 1.55)
			(end -1 1.4)
			(stroke
				(width 0.15)
				(type solid)
			)
			(layer "F.SilkS")
		)
		(fp_line
			(start -1 -1.5)
			(end -1 -1.375)
			(stroke
				(width 0.15)
				(type solid)
			)
			(layer "F.SilkS")
		)
		(fp_circle
			(center -1.44 -1.5)
			(end -1.39 -1.5)
			(stroke
				(width 0.15)
				(type solid)
			)
			(fill solid)
			(layer "F.SilkS")
		)
		(fp_rect
			(start 1.93 -1.7)
			(end -1.93 1.7)
			(stroke
				(width 0.05)
				(type solid)
			)
			(fill none)
			(layer "F.CrtYd")
		)
		(fp_line
			(start -0.45 -1.521)
			(end -0.876 -1.096)
			(stroke
				(width 0.15)
				(type solid)
			)
			(layer "F.Fab")
		)
		(fp_rect
			(start 0.875 1.528)
			(end -0.875 -1.525)
			(stroke
				(width 0.15)
				(type solid)
			)
			(fill none)
			(layer "F.Fab")
		)
		(fp_text user "${REFERENCE}"
			(at -1.93 3.8 0)
			(layer "F.Fab")
			(hide yes)
			(effects
				(font
					(size 0.7 0.7)
					(thickness 0.15)
				)
				(justify right bottom)
			)
		)
		(fp_text user "License: Apache-2.0"
			(at -1.93 6.199 0)
			(layer "F.Fab")
			(hide yes)
			(effects
				(font
					(size 0.7 0.7)
					(thickness 0.15)
				)
				(justify right bottom)
			)
		)
		(fp_text user "Author: Antmicro"
			(at -1.93 5 0)
			(layer "F.Fab")
			(hide yes)
			(effects
				(font
					(size 0.7 0.7)
					(thickness 0.15)
				)
				(justify right bottom)
			)
		)
		(pad "1" smd rect
			(at -1.301 -0.947 90)
			(size 0.7 1.2)
			(layers "F.Cu" "F.Paste" "F.Mask")
			(net 1 "GND")
			(pinfunction "GND")
			(pintype "power_in")
		)
		(pad "2" smd rect
			(at -1.301 0.004 90)
			(size 0.7 1.2)
			(layers "F.Cu" "F.Paste" "F.Mask")
			(net 6 "/Supply/SW_1V8")
			(pinfunction "SW")
			(pintype "power_out")
		)
		(pad "3" smd rect
			(at -1.301 0.954 90)
			(size 0.7 1.2)
			(layers "F.Cu" "F.Paste" "F.Mask")
			(net 2 "+12V")
			(pinfunction "VIN")
			(pintype "power_in")
		)
		(pad "4" smd rect
			(at 1.299 0.954 90)
			(size 0.7 1.2)
			(layers "F.Cu" "F.Paste" "F.Mask")
			(net 65 "/Supply/FB_1V8")
			(pinfunction "FB")
			(pintype "input")
		)
		(pad "5" smd rect
			(at 1.299 0.004 90)
			(size 0.7 1.2)
			(layers "F.Cu" "F.Paste" "F.Mask")
			(net 63 "/Supply/EN_1V8")
			(pinfunction "EN")
			(pintype "input")
		)
		(pad "6" smd rect
			(at 1.299 -0.947 90)
			(size 0.7 1.2)
			(layers "F.Cu" "F.Paste" "F.Mask")
			(net 5 "Net-(U2-BST)")
			(pinfunction "BST")
			(pintype "output")
		)
	)
	(footprint "antmicro-footprints:MP_Pad6mm_Drill3mm"
		(layer "F.Cu")
		(at 163.15 117.35)
		(property "Reference" "MP1"
			(at 0 -3.2 0)
			(layer "F.SilkS")
			(hide yes)
			(effects
				(font
					(size 0.7 0.7)
					(thickness 0.15)
				)
				(justify left bottom)
			)
		)
		(property "Value" "MP_Pad6mm_Drill3mm"
			(at 0 3.9 0)
			(layer "F.Fab")
			(effects
				(font
					(size 0.7 0.7)
					(thickness 0.15)
				)
				(justify left bottom)
			)
		)
		(property "Footprint" "antmicro-footprints:MP_Pad6mm_Drill3mm"
			(at 0 0 0)
			(layer "F.Fab")
			(hide yes)
			(effects
				(font
					(size 1.27 1.27)
					(thickness 0.15)
				)
			)
		)
		(property "Author" "Antmicro"
			(at 0 0 0)
			(layer "F.Fab")
			(hide yes)
			(effects
				(font
					(size 1 1)
					(thickness 0.15)
				)
			)
		)
		(property "License" "Apache-2.0"
			(at 0 0 0)
			(layer "F.Fab")
			(hide yes)
			(effects
				(font
					(size 1 1)
					(thickness 0.15)
				)
			)
		)
		(sheetname "Root")
		(sheetfile "gmsl-serializer.kicad_sch")
		(attr exclude_from_pos_files exclude_from_bom)
		(fp_circle
			(center 0 0)
			(end 3.25 0)
			(stroke
				(width 0.05)
				(type default)
			)
			(fill none)
			(layer "F.CrtYd")
		)
		(fp_text user "${REFERENCE}"
			(at -0.178 6.025 0)
			(layer "F.Fab")
			(hide yes)
			(effects
				(font
					(size 0.7 0.7)
					(thickness 0.15)
				)
				(justify left bottom)
			)
		)
		(fp_text user "License: Apache-2.0"
			(at -0.178 8.425 0)
			(layer "F.Fab")
			(hide yes)
			(effects
				(font
					(size 0.7 0.7)
					(thickness 0.15)
				)
				(justify left bottom)
			)
		)
		(fp_text user "Author: Antmicro"
			(at -0.178 7.225 0)
			(layer "F.Fab")
			(hide yes)
			(effects
				(font
					(size 0.7 0.7)
					(thickness 0.15)
				)
				(justify left bottom)
			)
		)
		(pad "1" thru_hole circle
			(at 0 0)
			(size 6 6)
			(drill 3)
			(layers "*.Cu" "*.Mask")
			(remove_unused_layers no)
			(net 1 "GND")
			(pintype "passive")
			(solder_paste_margin_ratio -1)
		)
	)
	(footprint "antmicro-footprints:C_0402_1005Metric"
		(layer "F.Cu")
		(at 147.91 95.77 -45)
		(descr "Capacitor SMD 0402")
		(tags "capacitor SMD 0402")
		(property "Reference" "C33"
			(at 0.947523 -2.375879 -45)
			(unlocked yes)
			(layer "F.SilkS")
			(effects
				(font
					(size 0.7 0.7)
					(thickness 0.15)
				)
				(justify right bottom)
			)
		)
		(property "Value" "C_10u_0402"
			(at -1.022927 2.155213 135)
			(layer "F.Fab")
			(effects
				(font
					(size 0.7 0.7)
					(thickness 0.15)
				)
				(justify right bottom)
			)
		)
		(property "Footprint" "antmicro-footprints:C_0402_1005Metric"
			(at 0 0 -45)
			(layer "F.Fab")
			(hide yes)
			(effects
				(font
					(size 1.27 1.27)
					(thickness 0.15)
				)
			)
		)
		(property "Datasheet" "https://www.yageo.com/en/Chart/Download/pdf/CC0402MRX5R5BB106"
			(at 0 0 -45)
			(layer "F.Fab")
			(hide yes)
			(effects
				(font
					(size 1.27 1.27)
					(thickness 0.15)
				)
			)
		)
		(property "Author" "Antmicro"
			(at -24.39778 132.638547 0)
			(layer "F.Fab")
			(hide yes)
			(effects
				(font
					(size 1 1)
					(thickness 0.15)
				)
			)
		)
		(property "Dielectric" ""
			(at -24.39778 132.638547 0)
			(layer "F.Fab")
			(hide yes)
			(effects
				(font
					(size 1 1)
					(thickness 0.15)
				)
			)
		)
		(property "License" "Apache-2.0"
			(at -24.39778 132.638547 0)
			(layer "F.Fab")
			(hide yes)
			(effects
				(font
					(size 1 1)
					(thickness 0.15)
				)
			)
		)
		(property "MPN" "CC0402MRX5R5BB106"
			(at -24.39778 132.638547 0)
			(layer "F.Fab")
			(hide yes)
			(effects
				(font
					(size 1 1)
					(thickness 0.15)
				)
			)
		)
		(property "Manufacturer" "YAGEO"
			(at -24.39778 132.638547 0)
			(layer "F.Fab")
			(hide yes)
			(effects
				(font
					(size 1 1)
					(thickness 0.15)
				)
			)
		)
		(property "Val" "10u"
			(at -24.39778 132.638547 0)
			(layer "F.Fab")
			(hide yes)
			(effects
				(font
					(size 1 1)
					(thickness 0.15)
				)
			)
		)
		(property "Voltage" ""
			(at -24.39778 132.638547 0)
			(layer "F.Fab")
			(hide yes)
			(effects
				(font
					(size 1 1)
					(thickness 0.15)
				)
			)
		)
		(sheetname "Serializer")
		(sheetfile "serializer.kicad_sch")
		(attr smd)
		(fp_poly
			(pts
				(xy -0.925 -0.47) (xy 0.925 -0.47) (xy 0.925 0.47) (xy -0.925 0.47)
			)
			(stroke
				(width 0.05)
				(type default)
			)
			(fill none)
			(layer "F.CrtYd")
		)
		(fp_line
			(start -0.494 0.248)
			(end -0.494 -0.25)
			(stroke
				(width 0.15)
				(type solid)
			)
			(layer "F.Fab")
		)
		(fp_line
			(start -0.494 -0.25)
			(end 0.504 -0.25)
			(stroke
				(width 0.15)
				(type solid)
			)
			(layer "F.Fab")
		)
		(fp_line
			(start 0.504 0.248)
			(end -0.494 0.248)
			(stroke
				(width 0.15)
				(type solid)
			)
			(layer "F.Fab")
		)
		(fp_line
			(start 0.504 -0.25)
			(end 0.504 0.248)
			(stroke
				(width 0.15)
				(type solid)
			)
			(layer "F.Fab")
		)
		(fp_text user "${REFERENCE}"
			(at -0.939 4.599 135)
			(layer "F.Fab")
			(hide yes)
			(effects
				(font
					(size 0.7 0.7)
					(thickness 0.15)
				)
				(justify right bottom)
			)
		)
		(fp_text user "License: Apache-2.0"
			(at -0.939 5.799 135)
			(layer "F.Fab")
			(hide yes)
			(effects
				(font
					(size 0.7 0.7)
					(thickness 0.15)
				)
				(justify right bottom)
			)
		)
		(fp_text user "Author: Antmicro"
			(at -0.939 3.399 135)
			(layer "F.Fab")
			(hide yes)
			(effects
				(font
					(size 0.7 0.7)
					(thickness 0.15)
				)
				(justify right bottom)
			)
		)
		(pad "1" smd roundrect
			(at -0.48 0 315)
			(size 0.59 0.64)
			(layers "F.Cu" "F.Paste" "F.Mask")
			(roundrect_rratio 0.25)
			(net 1 "GND")
			(pintype "passive")
		)
		(pad "2" smd roundrect
			(at 0.48 0 315)
			(size 0.59 0.64)
			(layers "F.Cu" "F.Paste" "F.Mask")
			(roundrect_rratio 0.25)
			(net 10 "+3V3")
			(pintype "passive")
		)
	)
	(footprint "antmicro-footprints:L_Bourns-SRP3212A"
		(layer "F.Cu")
		(at 142.25 86.910142)
		(property "Reference" "L7"
			(at -2.95 2.469858 0)
			(layer "F.SilkS")
			(effects
				(font
					(size 0.7 0.7)
					(thickness 0.15)
				)
				(justify left bottom)
			)
		)
		(property "Value" "L_3u3_3.1A_Bourns-SRP3212A"
			(at 1.49 1.5 0)
			(layer "F.Fab")
			(effects
				(font
					(size 0.7 0.7)
					(thickness 0.15)
				)
				(justify left bottom)
			)
		)
		(property "Footprint" "antmicro-footprints:L_Bourns-SRP3212A"
			(at 0 0 0)
			(layer "F.Fab")
			(hide yes)
			(effects
				(font
					(size 1.27 1.27)
					(thickness 0.15)
				)
			)
		)
		(property "Datasheet" "https://www.mouser.com/datasheet/2/54/SRP3212A-3011944.pdf"
			(at 0 0 0)
			(layer "F.Fab")
			(hide yes)
			(effects
				(font
					(size 1.27 1.27)
					(thickness 0.15)
				)
			)
		)
		(property "Val" "3u3/3.1A"
			(at 0 0 0)
			(unlocked yes)
			(layer "F.Fab")
			(hide yes)
			(effects
				(font
					(size 1 1)
					(thickness 0.15)
				)
			)
		)
		(property "Manufacturer" "Bourns"
			(at 0 0 0)
			(unlocked yes)
			(layer "F.Fab")
			(hide yes)
			(effects
				(font
					(size 1 1)
					(thickness 0.15)
				)
			)
		)
		(property "MPN" "SRP3212-3R3M"
			(at 0 0 0)
			(unlocked yes)
			(layer "F.Fab")
			(hide yes)
			(effects
				(font
					(size 1 1)
					(thickness 0.15)
				)
			)
		)
		(property "ISat" "3.4 A"
			(at 0 0 0)
			(unlocked yes)
			(layer "F.Fab")
			(hide yes)
			(effects
				(font
					(size 1 1)
					(thickness 0.15)
				)
			)
		)
		(property "IMax" "3.1 A"
			(at 0 0 0)
			(unlocked yes)
			(layer "F.Fab")
			(hide yes)
			(effects
				(font
					(size 1 1)
					(thickness 0.15)
				)
			)
		)
		(property "Size" "3.2x2.5"
			(at 0 0 0)
			(unlocked yes)
			(layer "F.Fab")
			(hide yes)
			(effects
				(font
					(size 1 1)
					(thickness 0.15)
				)
			)
		)
		(property "Author" "Antmicro"
			(at 0 0 0)
			(unlocked yes)
			(layer "F.Fab")
			(hide yes)
			(effects
				(font
					(size 1 1)
					(thickness 0.15)
				)
			)
		)
		(property "License" "Apache-2.0"
			(at 0 0 0)
			(unlocked yes)
			(layer "F.Fab")
			(hide yes)
			(effects
				(font
					(size 1 1)
					(thickness 0.15)
				)
			)
		)
		(sheetname "Supply")
		(sheetfile "supply.kicad_sch")
		(attr smd)
		(fp_line
			(start -0.4 -1.25)
			(end 0.399 -1.25)
			(stroke
				(width 0.15)
				(type solid)
			)
			(layer "F.SilkS")
		)
		(fp_line
			(start -0.4 1.249)
			(end 0.399 1.249)
			(stroke
				(width 0.15)
				(type solid)
			)
			(layer "F.SilkS")
		)
		(fp_rect
			(start -2.1 -1.65)
			(end 2.1 1.65)
			(stroke
				(width 0.05)
				(type solid)
			)
			(fill none)
			(layer "F.CrtYd")
		)
		(fp_rect
			(start -1.609 -1.26)
			(end 1.609 1.26)
			(stroke
				(width 0.15)
				(type solid)
			)
			(fill none)
			(layer "F.Fab")
		)
		(fp_text user "${REFERENCE}"
			(at -2.1 4.8 0)
			(layer "F.Fab")
			(hide yes)
			(effects
				(font
					(size 0.7 0.7)
					(thickness 0.15)
				)
				(justify left bottom)
			)
		)
		(fp_text user "Author: Antmicro"
			(at -2.1 6 0)
			(layer "F.Fab")
			(hide yes)
			(effects
				(font
					(size 0.7 0.7)
					(thickness 0.15)
				)
				(justify left bottom)
			)
		)
		(fp_text user "License: Apache-2.0"
			(at -2.1 7.2 0)
			(layer "F.Fab")
			(hide yes)
			(effects
				(font
					(size 0.7 0.7)
					(thickness 0.15)
				)
				(justify left bottom)
			)
		)
		(pad "1" smd roundrect
			(at -1.175 0)
			(size 1.35 2.8)
			(layers "F.Cu" "F.Paste" "F.Mask")
			(roundrect_rratio 0.1)
			(net 72 "/Supply/SW_3V3")
			(pintype "passive")
		)
		(pad "2" smd roundrect
			(at 1.175 0)
			(size 1.35 2.8)
			(layers "F.Cu" "F.Paste" "F.Mask")
			(roundrect_rratio 0.1)
			(net 94 "/Supply/OUT_3V3")
			(pintype "passive")
		)
	)
	(footprint "antmicro-footprints:R_0402_1005Metric"
		(layer "F.Cu")
		(at 149.05 113.2 -90)
		(descr "Resistor SMD 0402")
		(tags "resistor SMD 0402")
		(property "Reference" "R38"
			(at -1.1 -1.2 90)
			(layer "F.SilkS")
			(effects
				(font
					(size 0.7 0.7)
					(thickness 0.15)
				)
				(justify right bottom)
			)
		)
		(property "Value" "R_100k_0402"
			(at -1.011843 1.772047 90)
			(layer "F.Fab")
			(effects
				(font
					(size 0.7 0.7)
					(thickness 0.15)
				)
				(justify right bottom)
			)
		)
		(property "Footprint" "antmicro-footprints:R_0402_1005Metric"
			(at 0 0 -90)
			(layer "F.Fab")
			(hide yes)
			(effects
				(font
					(size 1.27 1.27)
					(thickness 0.15)
				)
			)
		)
		(property "Datasheet" "https://www.bourns.com/docs/product-datasheets/cr.pdf"
			(at 0 0 -90)
			(layer "F.Fab")
			(hide yes)
			(effects
				(font
					(size 1.27 1.27)
					(thickness 0.15)
				)
			)
		)
		(property "Author" "Antmicro"
			(at 35.85 262.25 0)
			(layer "F.Fab")
			(hide yes)
			(effects
				(font
					(size 1 1)
					(thickness 0.15)
				)
			)
		)
		(property "License" "Apache-2.0"
			(at 35.85 262.25 0)
			(layer "F.Fab")
			(hide yes)
			(effects
				(font
					(size 1 1)
					(thickness 0.15)
				)
			)
		)
		(property "MPN" "CR0402-FX-1003GLF"
			(at 35.85 262.25 0)
			(layer "F.Fab")
			(hide yes)
			(effects
				(font
					(size 1 1)
					(thickness 0.15)
				)
			)
		)
		(property "Manufacturer" "Bourns"
			(at 35.85 262.25 0)
			(layer "F.Fab")
			(hide yes)
			(effects
				(font
					(size 1 1)
					(thickness 0.15)
				)
			)
		)
		(property "Tolerance" "1%"
			(at 35.85 262.25 0)
			(layer "F.Fab")
			(hide yes)
			(effects
				(font
					(size 1 1)
					(thickness 0.15)
				)
			)
		)
		(property "Val" "100k"
			(at 35.85 262.25 0)
			(layer "F.Fab")
			(hide yes)
			(effects
				(font
					(size 1 1)
					(thickness 0.15)
				)
			)
		)
		(sheetname "Supply")
		(sheetfile "supply.kicad_sch")
		(attr smd)
		(fp_rect
			(start -0.925 -0.47)
			(end 0.925 0.47)
			(stroke
				(width 0.05)
				(type default)
			)
			(fill none)
			(layer "F.CrtYd")
		)
		(fp_rect
			(start -0.5 -0.25)
			(end 0.5 0.25)
			(stroke
				(width 0.15)
				(type solid)
			)
			(fill none)
			(layer "F.Fab")
		)
		(fp_text user "Author: Antmicro"
			(at -0.95 4.169 90)
			(layer "F.Fab")
			(hide yes)
			(effects
				(font
					(size 0.7 0.7)
					(thickness 0.15)
				)
				(justify right bottom)
			)
		)
		(fp_text user "${REFERENCE}"
			(at -0.95 3.168 90)
			(layer "F.Fab")
			(hide yes)
			(effects
				(font
					(size 0.7 0.7)
					(thickness 0.15)
				)
				(justify right bottom)
			)
		)
		(fp_text user "License: Apache-2.0"
			(at -0.95 5.169 90)
			(layer "F.Fab")
			(hide yes)
			(effects
				(font
					(size 0.7 0.7)
					(thickness 0.15)
				)
				(justify right bottom)
			)
		)
		(pad "1" smd roundrect
			(at -0.48 0 270)
			(size 0.59 0.64)
			(layers "F.Cu" "F.Paste" "F.Mask")
			(roundrect_rratio 0.25)
			(net 1 "GND")
			(pintype "passive")
		)
		(pad "2" smd roundrect
			(at 0.48 0 270)
			(size 0.59 0.64)
			(layers "F.Cu" "F.Paste" "F.Mask")
			(roundrect_rratio 0.25)
			(net 11 "+1V8")
			(pintype "passive")
		)
	)
	(footprint "antmicro-footprints:Conn_FAKRA_59S2AQ-40MT5-Z_1"
		(layer "F.Cu")
		(at 153 79.998)
		(descr "Connector FAKRA, 5 pins")
		(property "Reference" "J2"
			(at 4.75 -0.998 0)
			(layer "F.SilkS")
			(effects
				(font
					(size 0.7 0.7)
					(thickness 0.15)
				)
				(justify left bottom)
			)
		)
		(property "Value" "Conn_FAKRA_59S2AQ-40MT5-Z_1"
			(at 10.668 5.588 0)
			(layer "F.Fab")
			(effects
				(font
					(size 0.7 0.7)
					(thickness 0.15)
				)
				(justify left bottom)
			)
		)
		(property "Footprint" "antmicro-footprints:Conn_FAKRA_59S2AQ-40MT5-Z_1"
			(at 0 0 0)
			(layer "F.Fab")
			(hide yes)
			(effects
				(font
					(size 1.27 1.27)
					(thickness 0.15)
				)
			)
		)
		(property "Datasheet" "https://products.rosenberger.com/radio-frequency/connectors/288881/59s2aq-40mt5-z-1-right-angle-plug-pcb-w.-housing"
			(at 0 0 0)
			(layer "F.Fab")
			(hide yes)
			(effects
				(font
					(size 1.27 1.27)
					(thickness 0.15)
				)
			)
		)
		(property "Author" "Antmicro"
			(at 0 0 0)
			(layer "F.Fab")
			(hide yes)
			(effects
				(font
					(size 1 1)
					(thickness 0.15)
				)
			)
		)
		(property "License" "Apache-2.0"
			(at 0 0 0)
			(layer "F.Fab")
			(hide yes)
			(effects
				(font
					(size 1 1)
					(thickness 0.15)
				)
			)
		)
		(property "MPN" "59S2AQ-40MT5-Z_1"
			(at 0 0 0)
			(layer "F.Fab")
			(hide yes)
			(effects
				(font
					(size 1 1)
					(thickness 0.15)
				)
			)
		)
		(property "Manufacturer" "Rosenberger"
			(at 0 0 0)
			(layer "F.Fab")
			(hide yes)
			(effects
				(font
					(size 1 1)
					(thickness 0.15)
				)
			)
		)
		(property ki_fp_filters "*BNC* *SMA* *SMB* *SMC* *Cinch*")
		(sheetname "GMSL Connector")
		(sheetfile "GMSL.kicad_sch")
		(attr smd)
		(fp_line
			(start -4.572 -2.004)
			(end -4.572 11.204)
			(stroke
				(width 0.15)
				(type solid)
			)
			(layer "F.SilkS")
		)
		(fp_line
			(start -4.572 11.204)
			(end 4.572 11.204)
			(stroke
				(width 0.15)
				(type solid)
			)
			(layer "F.SilkS")
		)
		(fp_line
			(start 4.572 -2.004)
			(end -4.572 -2.004)
			(stroke
				(width 0.15)
				(type solid)
			)
			(layer "F.SilkS")
		)
		(fp_line
			(start 4.572 11.204)
			(end 4.572 -2.004)
			(stroke
				(width 0.15)
				(type solid)
			)
			(layer "F.SilkS")
		)
		(fp_rect
			(start -5 -14)
			(end 5 10.86)
			(stroke
				(width 0.05)
				(type solid)
			)
			(fill none)
			(layer "F.CrtYd")
		)
		(fp_text user "Author: Antmicro"
			(at -5.35 14.404 0)
			(layer "F.Fab")
			(hide yes)
			(effects
				(font
					(size 0.7 0.7)
					(thickness 0.15)
				)
				(justify left bottom)
			)
		)
		(fp_text user "License: Apache-2.0"
			(at -5.35 13.204 0)
			(layer "F.Fab")
			(hide yes)
			(effects
				(font
					(size 0.7 0.7)
					(thickness 0.15)
				)
				(justify left bottom)
			)
		)
		(fp_text user "${REFERENCE}"
			(at -5.35 15.604 0)
			(layer "F.Fab")
			(hide yes)
			(effects
				(font
					(size 0.7 0.7)
					(thickness 0.15)
				)
				(justify left bottom)
			)
		)
		(pad "1" smd roundrect
			(at 0 0 270)
			(size 3.4 1.9)
			(layers "F.Cu" "F.Paste" "F.Mask")
			(roundrect_rratio 0.25)
			(net 18 "/GMSL Connector/SIO_P")
			(pinfunction "1")
			(pintype "passive")
		)
		(pad "2" thru_hole circle
			(at -3 0.6 270)
			(size 1.8 1.8)
			(drill 1.45)
			(layers "*.Cu" "*.Mask")
			(remove_unused_layers no)
			(net 1 "GND")
			(pinfunction "2")
			(pintype "passive")
		)
		(pad "2" smd roundrect
			(at -3 0.9 270)
			(size 5.2 1.8)
			(layers "F.Cu" "F.Paste" "F.Mask")
			(roundrect_rratio 0.25)
			(net 1 "GND")
			(pinfunction "2")
			(pintype "passive")
		)
		(pad "3" thru_hole circle
			(at -3 7.6 270)
			(size 1.8 1.8)
			(drill 1.45)
			(layers "*.Cu" "*.Mask")
			(remove_unused_layers no)
			(net 1 "GND")
			(pinfunction "3")
			(pintype "passive")
		)
		(pad "3" smd roundrect
			(at -3 8.1 270)
			(size 5.6 1.8)
			(layers "F.Cu" "F.Paste" "F.Mask")
			(roundrect_rratio 0.25)
			(net 1 "GND")
			(pinfunction "3")
			(pintype "passive")
		)
		(pad "4" thru_hole circle
			(at 3 7.6 270)
			(size 1.8 1.8)
			(drill 1.45)
			(layers "*.Cu" "*.Mask")
			(remove_unused_layers no)
			(net 1 "GND")
			(pinfunction "4")
			(pintype "passive")
		)
		(pad "4" smd roundrect
			(at 3 8.1 270)
			(size 5.6 1.8)
			(layers "F.Cu" "F.Paste" "F.Mask")
			(roundrect_rratio 0.25)
			(net 1 "GND")
			(pinfunction "4")
			(pintype "passive")
		)
		(pad "5" thru_hole circle
			(at 3 0.6 270)
			(size 1.8 1.8)
			(drill 1.45)
			(layers "*.Cu" "*.Mask")
			(remove_unused_layers no)
			(net 1 "GND")
			(pinfunction "5")
			(pintype "passive")
		)
		(pad "5" smd roundrect
			(at 3 0.9 270)
			(size 5.2 1.8)
			(layers "F.Cu" "F.Paste" "F.Mask")
			(roundrect_rratio 0.25)
			(net 1 "GND")
			(pinfunction "5")
			(pintype "passive")
		)
	)
	(footprint "antmicro-footprints:R_0402_1005Metric"
		(layer "F.Cu")
		(at 133.1 108.75)
		(descr "Resistor SMD 0402")
		(tags "resistor SMD 0402")
		(property "Reference" "R4"
			(at 1.05 -5.241666 0)
			(layer "F.SilkS")
			(effects
				(font
					(size 0.7 0.7)
					(thickness 0.15)
				)
				(justify left bottom)
			)
		)
		(property "Value" "R_100R_0402"
			(at -1.011843 1.772047 0)
			(layer "F.Fab")
			(effects
				(font
					(size 0.7 0.7)
					(thickness 0.15)
				)
				(justify left bottom)
			)
		)
		(property "Footprint" "antmicro-footprints:R_0402_1005Metric"
			(at 0 0 0)
			(layer "F.Fab")
			(hide yes)
			(effects
				(font
					(size 1.27 1.27)
					(thickness 0.15)
				)
			)
		)
		(property "Datasheet" "https://www.bourns.com/docs/product-datasheets/cr.pdf"
			(at 0 0 0)
			(layer "F.Fab")
			(hide yes)
			(effects
				(font
					(size 1.27 1.27)
					(thickness 0.15)
				)
			)
		)
		(property "Author" "Antmicro"
			(at 0 0 0)
			(layer "F.Fab")
			(hide yes)
			(effects
				(font
					(size 1 1)
					(thickness 0.15)
				)
			)
		)
		(property "License" "Apache-2.0"
			(at 0 0 0)
			(layer "F.Fab")
			(hide yes)
			(effects
				(font
					(size 1 1)
					(thickness 0.15)
				)
			)
		)
		(property "MPN" "CR0402-FX-1000GLF"
			(at 0 0 0)
			(layer "F.Fab")
			(hide yes)
			(effects
				(font
					(size 1 1)
					(thickness 0.15)
				)
			)
		)
		(property "Manufacturer" "Bourns"
			(at 0 0 0)
			(layer "F.Fab")
			(hide yes)
			(effects
				(font
					(size 1 1)
					(thickness 0.15)
				)
			)
		)
		(property "Tolerance" "1%"
			(at 0 0 0)
			(layer "F.Fab")
			(hide yes)
			(effects
				(font
					(size 1 1)
					(thickness 0.15)
				)
			)
		)
		(property "Val" "100R"
			(at 0 0 0)
			(layer "F.Fab")
			(hide yes)
			(effects
				(font
					(size 1 1)
					(thickness 0.15)
				)
			)
		)
		(sheetname "CSI Connector")
		(sheetfile "CSI.kicad_sch")
		(attr smd)
		(fp_rect
			(start -0.925 -0.47)
			(end 0.925 0.47)
			(stroke
				(width 0.05)
				(type default)
			)
			(fill none)
			(layer "F.CrtYd")
		)
		(fp_rect
			(start -0.5 -0.25)
			(end 0.5 0.25)
			(stroke
				(width 0.15)
				(type solid)
			)
			(fill none)
			(layer "F.Fab")
		)
		(fp_text user "${REFERENCE}"
			(at -0.95 3.168 0)
			(layer "F.Fab")
			(hide yes)
			(effects
				(font
					(size 0.7 0.7)
					(thickness 0.15)
				)
				(justify left bottom)
			)
		)
		(fp_text user "License: Apache-2.0"
			(at -0.95 5.169 0)
			(layer "F.Fab")
			(hide yes)
			(effects
				(font
					(size 0.7 0.7)
					(thickness 0.15)
				)
				(justify left bottom)
			)
		)
		(fp_text user "Author: Antmicro"
			(at -0.95 4.169 0)
			(layer "F.Fab")
			(hide yes)
			(effects
				(font
					(size 0.7 0.7)
					(thickness 0.15)
				)
				(justify left bottom)
			)
		)
		(pad "1" smd roundrect
			(at -0.48 0)
			(size 0.59 0.64)
			(layers "F.Cu" "F.Paste" "F.Mask")
			(roundrect_rratio 0.25)
			(net 35 "/CSI Connector/SCL_CAM0")
			(pintype "passive")
		)
		(pad "2" smd roundrect
			(at 0.48 0)
			(size 0.59 0.64)
			(layers "F.Cu" "F.Paste" "F.Mask")
			(roundrect_rratio 0.25)
			(net 89 "/CSI Connector/I2C.SCL")
			(pintype "passive")
		)
	)
	(footprint "antmicro-footprints:C_0402_1005Metric"
		(layer "F.Cu")
		(at 156.23 99.79 135)
		(descr "Capacitor SMD 0402")
		(tags "capacitor SMD 0402")
		(property "Reference" "C17"
			(at -1.086116 0.681651 -45)
			(unlocked yes)
			(layer "F.SilkS")
			(effects
				(font
					(size 0.7 0.7)
					(thickness 0.15)
				)
				(justify right bottom)
			)
		)
		(property "Value" "C_33p_0402"
			(at -1.022927 2.155213 135)
			(layer "F.Fab")
			(effects
				(font
					(size 0.7 0.7)
					(thickness 0.15)
				)
				(justify left bottom)
			)
		)
		(property "Footprint" "antmicro-footprints:C_0402_1005Metric"
			(at 0 0 135)
			(layer "F.Fab")
			(hide yes)
			(effects
				(font
					(size 1.27 1.27)
					(thickness 0.15)
				)
			)
		)
		(property "Datasheet" "https://spicat.kyocera-avx.com/product/mlcc/chartview/04025A330FAT2A/"
			(at 0 0 135)
			(layer "F.Fab")
			(hide yes)
			(effects
				(font
					(size 1.27 1.27)
					(thickness 0.15)
				)
			)
		)
		(property "Author" "Antmicro"
			(at 337.263478 59.880893 0)
			(layer "F.Fab")
			(hide yes)
			(effects
				(font
					(size 1 1)
					(thickness 0.15)
				)
			)
		)
		(property "Dielectric" ""
			(at 337.263478 59.880893 0)
			(layer "F.Fab")
			(hide yes)
			(effects
				(font
					(size 1 1)
					(thickness 0.15)
				)
			)
		)
		(property "License" "Apache-2.0"
			(at 337.263478 59.880893 0)
			(layer "F.Fab")
			(hide yes)
			(effects
				(font
					(size 1 1)
					(thickness 0.15)
				)
			)
		)
		(property "MPN" "04025A330FAT2A"
			(at 337.263478 59.880893 0)
			(layer "F.Fab")
			(hide yes)
			(effects
				(font
					(size 1 1)
					(thickness 0.15)
				)
			)
		)
		(property "Manufacturer" "KYOCERA AVX"
			(at 337.263478 59.880893 0)
			(layer "F.Fab")
			(hide yes)
			(effects
				(font
					(size 1 1)
					(thickness 0.15)
				)
			)
		)
		(property "Val" "33p"
			(at 337.263478 59.880893 0)
			(layer "F.Fab")
			(hide yes)
			(effects
				(font
					(size 1 1)
					(thickness 0.15)
				)
			)
		)
		(property "Voltage" ""
			(at 337.263478 59.880893 0)
			(layer "F.Fab")
			(hide yes)
			(effects
				(font
					(size 1 1)
					(thickness 0.15)
				)
			)
		)
		(sheetname "Serializer")
		(sheetfile "serializer.kicad_sch")
		(attr smd)
		(fp_poly
			(pts
				(xy -0.925 -0.47) (xy 0.925 -0.47) (xy 0.925 0.47) (xy -0.925 0.47)
			)
			(stroke
				(width 0.05)
				(type default)
			)
			(fill none)
			(layer "F.CrtYd")
		)
		(fp_line
			(start 0.504 -0.25)
			(end 0.504 0.248)
			(stroke
				(width 0.15)
				(type solid)
			)
			(layer "F.Fab")
		)
		(fp_line
			(start 0.504 0.248)
			(end -0.494 0.248)
			(stroke
				(width 0.15)
				(type solid)
			)
			(layer "F.Fab")
		)
		(fp_line
			(start -0.494 -0.25)
			(end 0.504 -0.25)
			(stroke
				(width 0.15)
				(type solid)
			)
			(layer "F.Fab")
		)
		(fp_line
			(start -0.494 0.248)
			(end -0.494 -0.25)
			(stroke
				(width 0.15)
				(type solid)
			)
			(layer "F.Fab")
		)
		(fp_text user "Author: Antmicro"
			(at -0.939 3.399 135)
			(layer "F.Fab")
			(hide yes)
			(effects
				(font
					(size 0.7 0.7)
					(thickness 0.15)
				)
				(justify left bottom)
			)
		)
		(fp_text user "License: Apache-2.0"
			(at -0.939 5.799 135)
			(layer "F.Fab")
			(hide yes)
			(effects
				(font
					(size 0.7 0.7)
					(thickness 0.15)
				)
				(justify left bottom)
			)
		)
		(fp_text user "${REFERENCE}"
			(at -0.939 4.599 135)
			(layer "F.Fab")
			(hide yes)
			(effects
				(font
					(size 0.7 0.7)
					(thickness 0.15)
				)
				(justify left bottom)
			)
		)
		(pad "1" smd roundrect
			(at -0.48 0 135)
			(size 0.59 0.64)
			(layers "F.Cu" "F.Paste" "F.Mask")
			(roundrect_rratio 0.25)
			(net 1 "GND")
			(pintype "passive")
		)
		(pad "2" smd roundrect
			(at 0.48 0 135)
			(size 0.59 0.64)
			(layers "F.Cu" "F.Paste" "F.Mask")
			(roundrect_rratio 0.25)
			(net 14 "/Serializer/X2_R")
			(pintype "passive")
		)
	)
	(footprint "antmicro-footprints:R_0402_1005Metric"
		(layer "F.Cu")
		(at 148.15 111.355 180)
		(descr "Resistor SMD 0402")
		(tags "resistor SMD 0402")
		(property "Reference" "R21"
			(at 0.81 -0.41 0)
			(layer "F.SilkS")
			(effects
				(font
					(size 0.7 0.7)
					(thickness 0.15)
				)
				(justify right bottom)
			)
		)
		(property "Value" "R_10k_0402"
			(at -1.011843 1.772047 0)
			(layer "F.Fab")
			(effects
				(font
					(size 0.7 0.7)
					(thickness 0.15)
				)
				(justify right bottom)
			)
		)
		(property "Footprint" "antmicro-footprints:R_0402_1005Metric"
			(at 0 0 180)
			(layer "F.Fab")
			(hide yes)
			(effects
				(font
					(size 1.27 1.27)
					(thickness 0.15)
				)
			)
		)
		(property "Datasheet" "https://www.bourns.com/docs/product-datasheets/cr.pdf"
			(at 0 0 180)
			(layer "F.Fab")
			(hide yes)
			(effects
				(font
					(size 1.27 1.27)
					(thickness 0.15)
				)
			)
		)
		(property "Author" "Antmicro"
			(at 296.3 222.71 0)
			(layer "F.Fab")
			(hide yes)
			(effects
				(font
					(size 1 1)
					(thickness 0.15)
				)
			)
		)
		(property "License" "Apache-2.0"
			(at 296.3 222.71 0)
			(layer "F.Fab")
			(hide yes)
			(effects
				(font
					(size 1 1)
					(thickness 0.15)
				)
			)
		)
		(property "MPN" "CR0402-FX-1002GLF"
			(at 296.3 222.71 0)
			(layer "F.Fab")
			(hide yes)
			(effects
				(font
					(size 1 1)
					(thickness 0.15)
				)
			)
		)
		(property "Manufacturer" "Bourns"
			(at 296.3 222.71 0)
			(layer "F.Fab")
			(hide yes)
			(effects
				(font
					(size 1 1)
					(thickness 0.15)
				)
			)
		)
		(property "Tolerance" "1%"
			(at 296.3 222.71 0)
			(layer "F.Fab")
			(hide yes)
			(effects
				(font
					(size 1 1)
					(thickness 0.15)
				)
			)
		)
		(property "Val" "10k"
			(at 296.3 222.71 0)
			(layer "F.Fab")
			(hide yes)
			(effects
				(font
					(size 1 1)
					(thickness 0.15)
				)
			)
		)
		(sheetname "Serializer")
		(sheetfile "serializer.kicad_sch")
		(attr smd)
		(fp_rect
			(start -0.925 -0.47)
			(end 0.925 0.47)
			(stroke
				(width 0.05)
				(type default)
			)
			(fill none)
			(layer "F.CrtYd")
		)
		(fp_rect
			(start -0.5 -0.25)
			(end 0.5 0.25)
			(stroke
				(width 0.15)
				(type solid)
			)
			(fill none)
			(layer "F.Fab")
		)
		(fp_text user "Author: Antmicro"
			(at -0.95 4.169 0)
			(layer "F.Fab")
			(hide yes)
			(effects
				(font
					(size 0.7 0.7)
					(thickness 0.15)
				)
				(justify right bottom)
			)
		)
		(fp_text user "${REFERENCE}"
			(at -0.95 3.168 0)
			(layer "F.Fab")
			(hide yes)
			(effects
				(font
					(size 0.7 0.7)
					(thickness 0.15)
				)
				(justify right bottom)
			)
		)
		(fp_text user "License: Apache-2.0"
			(at -0.95 5.169 0)
			(layer "F.Fab")
			(hide yes)
			(effects
				(font
					(size 0.7 0.7)
					(thickness 0.15)
				)
				(justify right bottom)
			)
		)
		(pad "1" smd roundrect
			(at -0.48 0 180)
			(size 0.59 0.64)
			(layers "F.Cu" "F.Paste" "F.Mask")
			(roundrect_rratio 0.25)
			(net 68 "/Serializer/CFG1")
			(pintype "passive")
		)
		(pad "2" smd roundrect
			(at 0.48 0 180)
			(size 0.59 0.64)
			(layers "F.Cu" "F.Paste" "F.Mask")
			(roundrect_rratio 0.25)
			(net 10 "+3V3")
			(pintype "passive")
		)
	)
	(footprint "antmicro-footprints:TP_SMD_1.5mm"
		(layer "F.Cu")
		(at 145 118)
		(property "Reference" "TP4"
			(at -0.4 -1 0)
			(layer "F.SilkS")
			(hide yes)
			(effects
				(font
					(size 0.7 0.7)
					(thickness 0.15)
				)
				(justify left bottom)
			)
		)
		(property "Value" "TP_1.5mm_SMD"
			(at 0 1.7 0)
			(layer "F.Fab")
			(effects
				(font
					(size 0.7 0.7)
					(thickness 0.15)
				)
				(justify left bottom)
			)
		)
		(property "Footprint" "antmicro-footprints:TP_SMD_1.5mm"
			(at 0 0 0)
			(layer "F.Fab")
			(hide yes)
			(effects
				(font
					(size 1.27 1.27)
					(thickness 0.15)
				)
			)
		)
		(property "Author" "Antmicro"
			(at 0 0 0)
			(layer "F.Fab")
			(hide yes)
			(effects
				(font
					(size 1 1)
					(thickness 0.15)
				)
			)
		)
		(property "License" "Apache-2.0"
			(at 0 0 0)
			(layer "F.Fab")
			(hide yes)
			(effects
				(font
					(size 1 1)
					(thickness 0.15)
				)
			)
		)
		(property "MPN" ""
			(at 0 0 0)
			(layer "F.Fab")
			(hide yes)
			(effects
				(font
					(size 1 1)
					(thickness 0.15)
				)
			)
		)
		(property "Manufacturer" ""
			(at 0 0 0)
			(layer "F.Fab")
			(hide yes)
			(effects
				(font
					(size 1 1)
					(thickness 0.15)
				)
			)
		)
		(sheetname "Supply")
		(sheetfile "supply.kicad_sch")
		(attr exclude_from_pos_files exclude_from_bom)
		(fp_circle
			(center 0 0)
			(end 0.85 0)
			(stroke
				(width 0.05)
				(type default)
			)
			(fill none)
			(layer "F.CrtYd")
		)
		(fp_text user "${REFERENCE}"
			(at -0.7 2.9 0)
			(layer "F.Fab")
			(hide yes)
			(effects
				(font
					(size 0.7 0.7)
					(thickness 0.15)
				)
				(justify left bottom)
			)
		)
		(fp_text user "License: Apache-2.0"
			(at -0.7 5.301 0)
			(layer "F.Fab")
			(hide yes)
			(effects
				(font
					(size 0.7 0.7)
					(thickness 0.15)
				)
				(justify left bottom)
			)
		)
		(fp_text user "Author: Antmicro"
			(at -0.7 4.101 0)
			(layer "F.Fab")
			(hide yes)
			(effects
				(font
					(size 0.7 0.7)
					(thickness 0.15)
				)
				(justify left bottom)
			)
		)
		(pad "1" smd circle
			(at 0 0 270)
			(size 1.5 1.5)
			(layers "F.Cu" "F.Mask")
			(net 10 "+3V3")
			(pinfunction "1")
			(pintype "passive")
		)
	)
	(footprint "antmicro-footprints:L_Coilcraft-PFL1609"
		(layer "F.Cu")
		(at 153.635 92.2 180)
		(property "Reference" "L6"
			(at 1.115 -0.37 0)
			(layer "F.SilkS")
			(effects
				(font
					(size 0.7 0.7)
					(thickness 0.15)
				)
				(justify right bottom)
			)
		)
		(property "Value" "L_470n_1A_Coilcraft-PFL1609"
			(at 0 2 0)
			(layer "F.Fab")
			(effects
				(font
					(size 0.7 0.7)
					(thickness 0.15)
				)
				(justify right bottom)
			)
		)
		(property "Footprint" "antmicro-footprints:L_Coilcraft-PFL1609"
			(at 0 0 180)
			(layer "F.Fab")
			(hide yes)
			(effects
				(font
					(size 1.27 1.27)
					(thickness 0.15)
				)
			)
		)
		(property "Datasheet" "https://www.coilcraft.com/getmedia/2f4cd442-d64d-4413-a518-12fcfd03318d/pfl1609.pdf"
			(at 0 0 180)
			(layer "F.Fab")
			(hide yes)
			(effects
				(font
					(size 1.27 1.27)
					(thickness 0.15)
				)
			)
		)
		(property "Author" "Antmicro"
			(at 307.27 184.4 0)
			(layer "F.Fab")
			(hide yes)
			(effects
				(font
					(size 1 1)
					(thickness 0.15)
				)
			)
		)
		(property "IMax" "1 A"
			(at 307.27 184.4 0)
			(layer "F.Fab")
			(hide yes)
			(effects
				(font
					(size 1 1)
					(thickness 0.15)
				)
			)
		)
		(property "ISat" "0.99 A"
			(at 307.27 184.4 0)
			(layer "F.Fab")
			(hide yes)
			(effects
				(font
					(size 1 1)
					(thickness 0.15)
				)
			)
		)
		(property "License" "Apache-2.0"
			(at 307.27 184.4 0)
			(layer "F.Fab")
			(hide yes)
			(effects
				(font
					(size 1 1)
					(thickness 0.15)
				)
			)
		)
		(property "MPN" "PFL1609-471"
			(at 307.27 184.4 0)
			(layer "F.Fab")
			(hide yes)
			(effects
				(font
					(size 1 1)
					(thickness 0.15)
				)
			)
		)
		(property "Manufacturer" "Coilcraft"
			(at 307.27 184.4 0)
			(layer "F.Fab")
			(hide yes)
			(effects
				(font
					(size 1 1)
					(thickness 0.15)
				)
			)
		)
		(property "Size" "1.07x1.8"
			(at 307.27 184.4 0)
			(layer "F.Fab")
			(hide yes)
			(effects
				(font
					(size 1 1)
					(thickness 0.15)
				)
			)
		)
		(property "Val" "470n/0.99A"
			(at 307.27 184.4 0)
			(layer "F.Fab")
			(hide yes)
			(effects
				(font
					(size 1 1)
					(thickness 0.15)
				)
			)
		)
		(sheetname "GMSL Connector")
		(sheetfile "GMSL.kicad_sch")
		(attr smd)
		(fp_line
			(start -0.23 0.45)
			(end 0.23 0.45)
			(stroke
				(width 0.15)
				(type solid)
			)
			(layer "F.SilkS")
		)
		(fp_line
			(start -0.23 -0.45)
			(end 0.23 -0.45)
			(stroke
				(width 0.15)
				(type solid)
			)
			(layer "F.SilkS")
		)
		(fp_rect
			(start -1.2 -0.84)
			(end 1.2 0.84)
			(stroke
				(width 0.05)
				(type solid)
			)
			(fill none)
			(layer "F.CrtYd")
		)
		(fp_rect
			(start -0.9 -0.535)
			(end 0.9 0.535)
			(stroke
				(width 0.15)
				(type solid)
			)
			(fill none)
			(layer "F.Fab")
		)
		(fp_text user "${REFERENCE}"
			(at -1.35 4 0)
			(layer "F.Fab")
			(hide yes)
			(effects
				(font
					(size 0.7 0.7)
					(thickness 0.15)
				)
				(justify right bottom)
			)
		)
		(fp_text user "Author: Antmicro"
			(at -1.35 5.2 0)
			(layer "F.Fab")
			(hide yes)
			(effects
				(font
					(size 0.7 0.7)
					(thickness 0.15)
				)
				(justify right bottom)
			)
		)
		(fp_text user "License: Apache-2.0"
			(at -1.35 6.4 0)
			(layer "F.Fab")
			(hide yes)
			(effects
				(font
					(size 0.7 0.7)
					(thickness 0.15)
				)
				(justify right bottom)
			)
		)
		(pad "1" smd roundrect
			(at -0.635 0 180)
			(size 0.64 1.02)
			(layers "F.Cu" "F.Paste" "F.Mask")
			(roundrect_rratio 0.15)
			(net 60 "Net-(L5-Pad2)")
			(pintype "passive")
		)
		(pad "2" smd roundrect
			(at 0.635 0 180)
			(size 0.64 1.02)
			(layers "F.Cu" "F.Paste" "F.Mask")
			(roundrect_rratio 0.15)
			(net 18 "/GMSL Connector/SIO_P")
			(pintype "passive")
		)
	)
	(footprint "antmicro-footprints:TP_SMD_1.5mm"
		(layer "F.Cu")
		(at 147.75 118)
		(property "Reference" "TP2"
			(at -1 -0.964 0)
			(layer "F.SilkS")
			(hide yes)
			(effects
				(font
					(size 0.7 0.7)
					(thickness 0.15)
				)
				(justify left bottom)
			)
		)
		(property "Value" "TP_1.5mm_SMD"
			(at 0 1.7 0)
			(layer "F.Fab")
			(effects
				(font
					(size 0.7 0.7)
					(thickness 0.15)
				)
				(justify left bottom)
			)
		)
		(property "Footprint" "antmicro-footprints:TP_SMD_1.5mm"
			(at 0 0 0)
			(layer "F.Fab")
			(hide yes)
			(effects
				(font
					(size 1.27 1.27)
					(thickness 0.15)
				)
			)
		)
		(property "Author" "Antmicro"
			(at 0 0 0)
			(layer "F.Fab")
			(hide yes)
			(effects
				(font
					(size 1 1)
					(thickness 0.15)
				)
			)
		)
		(property "License" "Apache-2.0"
			(at 0 0 0)
			(layer "F.Fab")
			(hide yes)
			(effects
				(font
					(size 1 1)
					(thickness 0.15)
				)
			)
		)
		(property "MPN" ""
			(at 0 0 0)
			(layer "F.Fab")
			(hide yes)
			(effects
				(font
					(size 1 1)
					(thickness 0.15)
				)
			)
		)
		(property "Manufacturer" ""
			(at 0 0 0)
			(layer "F.Fab")
			(hide yes)
			(effects
				(font
					(size 1 1)
					(thickness 0.15)
				)
			)
		)
		(sheetname "Supply")
		(sheetfile "supply.kicad_sch")
		(attr exclude_from_pos_files exclude_from_bom)
		(fp_circle
			(center 0 0)
			(end 0.85 0)
			(stroke
				(width 0.05)
				(type default)
			)
			(fill none)
			(layer "F.CrtYd")
		)
		(fp_text user "Author: Antmicro"
			(at -0.7 4.101 0)
			(layer "F.Fab")
			(hide yes)
			(effects
				(font
					(size 0.7 0.7)
					(thickness 0.15)
				)
				(justify left bottom)
			)
		)
		(fp_text user "${REFERENCE}"
			(at -0.7 2.9 0)
			(layer "F.Fab")
			(hide yes)
			(effects
				(font
					(size 0.7 0.7)
					(thickness 0.15)
				)
				(justify left bottom)
			)
		)
		(fp_text user "License: Apache-2.0"
			(at -0.7 5.301 0)
			(layer "F.Fab")
			(hide yes)
			(effects
				(font
					(size 0.7 0.7)
					(thickness 0.15)
				)
				(justify left bottom)
			)
		)
		(pad "1" smd circle
			(at 0 0 270)
			(size 1.5 1.5)
			(layers "F.Cu" "F.Mask")
			(net 11 "+1V8")
			(pinfunction "1")
			(pintype "passive")
		)
	)
	(footprint "antmicro-footprints:R_0402_1005Metric"
		(layer "F.Cu")
		(at 135.83 79.675 90)
		(descr "Resistor SMD 0402")
		(tags "resistor SMD 0402")
		(property "Reference" "R27"
			(at -0.925 -0.43 90)
			(layer "F.SilkS")
			(effects
				(font
					(size 0.7 0.7)
					(thickness 0.15)
				)
				(justify left bottom)
			)
		)
		(property "Value" "R_10k_0402"
			(at -1.011843 1.772047 90)
			(layer "F.Fab")
			(effects
				(font
					(size 0.7 0.7)
					(thickness 0.15)
				)
				(justify left bottom)
			)
		)
		(property "Footprint" "antmicro-footprints:R_0402_1005Metric"
			(at 0 0 90)
			(layer "F.Fab")
			(hide yes)
			(effects
				(font
					(size 1.27 1.27)
					(thickness 0.15)
				)
			)
		)
		(property "Datasheet" "https://www.bourns.com/docs/product-datasheets/cr.pdf"
			(at 0 0 90)
			(layer "F.Fab")
			(hide yes)
			(effects
				(font
					(size 1.27 1.27)
					(thickness 0.15)
				)
			)
		)
		(property "Author" "Antmicro"
			(at 217.125 -58.075 0)
			(layer "F.Fab")
			(hide yes)
			(effects
				(font
					(size 1 1)
					(thickness 0.15)
				)
			)
		)
		(property "License" "Apache-2.0"
			(at 217.125 -58.075 0)
			(layer "F.Fab")
			(hide yes)
			(effects
				(font
					(size 1 1)
					(thickness 0.15)
				)
			)
		)
		(property "MPN" "CR0402-FX-1002GLF"
			(at 217.125 -58.075 0)
			(layer "F.Fab")
			(hide yes)
			(effects
				(font
					(size 1 1)
					(thickness 0.15)
				)
			)
		)
		(property "Manufacturer" "Bourns"
			(at 217.125 -58.075 0)
			(layer "F.Fab")
			(hide yes)
			(effects
				(font
					(size 1 1)
					(thickness 0.15)
				)
			)
		)
		(property "Tolerance" "1%"
			(at 217.125 -58.075 0)
			(layer "F.Fab")
			(hide yes)
			(effects
				(font
					(size 1 1)
					(thickness 0.15)
				)
			)
		)
		(property "Val" "10k"
			(at 217.125 -58.075 0)
			(layer "F.Fab")
			(hide yes)
			(effects
				(font
					(size 1 1)
					(thickness 0.15)
				)
			)
		)
		(sheetname "Supply")
		(sheetfile "supply.kicad_sch")
		(attr smd)
		(fp_rect
			(start -0.925 -0.47)
			(end 0.925 0.47)
			(stroke
				(width 0.05)
				(type default)
			)
			(fill none)
			(layer "F.CrtYd")
		)
		(fp_rect
			(start -0.5 -0.25)
			(end 0.5 0.25)
			(stroke
				(width 0.15)
				(type solid)
			)
			(fill none)
			(layer "F.Fab")
		)
		(fp_text user "License: Apache-2.0"
			(at -0.95 5.169 90)
			(layer "F.Fab")
			(hide yes)
			(effects
				(font
					(size 0.7 0.7)
					(thickness 0.15)
				)
				(justify left bottom)
			)
		)
		(fp_text user "${REFERENCE}"
			(at -0.95 3.168 90)
			(layer "F.Fab")
			(hide yes)
			(effects
				(font
					(size 0.7 0.7)
					(thickness 0.15)
				)
				(justify left bottom)
			)
		)
		(fp_text user "Author: Antmicro"
			(at -0.95 4.169 90)
			(layer "F.Fab")
			(hide yes)
			(effects
				(font
					(size 0.7 0.7)
					(thickness 0.15)
				)
				(justify left bottom)
			)
		)
		(pad "1" smd roundrect
			(at -0.48 0 90)
			(size 0.59 0.64)
			(layers "F.Cu" "F.Paste" "F.Mask")
			(roundrect_rratio 0.25)
			(net 1 "GND")
			(pintype "passive")
		)
		(pad "2" smd roundrect
			(at 0.48 0 90)
			(size 0.59 0.64)
			(layers "F.Cu" "F.Paste" "F.Mask")
			(roundrect_rratio 0.25)
			(net 62 "/Supply/EN_5V")
			(pintype "passive")
		)
	)
	(footprint "antmicro-footprints:R_0402_1005Metric"
		(layer "F.Cu")
		(at 133.1 106.65 180)
		(descr "Resistor SMD 0402")
		(tags "resistor SMD 0402")
		(property "Reference" "R2"
			(at -2.566667 5.024998 0)
			(layer "F.SilkS")
			(effects
				(font
					(size 0.7 0.7)
					(thickness 0.15)
				)
				(justify right bottom)
			)
		)
		(property "Value" "R_12k_0402"
			(at -1.011843 1.772047 0)
			(layer "F.Fab")
			(effects
				(font
					(size 0.7 0.7)
					(thickness 0.15)
				)
				(justify right bottom)
			)
		)
		(property "Footprint" "antmicro-footprints:R_0402_1005Metric"
			(at 0 0 180)
			(layer "F.Fab")
			(hide yes)
			(effects
				(font
					(size 1.27 1.27)
					(thickness 0.15)
				)
			)
		)
		(property "Datasheet" "https://www.bourns.com/docs/product-datasheets/cr.pdf"
			(at 0 0 180)
			(layer "F.Fab")
			(hide yes)
			(effects
				(font
					(size 1.27 1.27)
					(thickness 0.15)
				)
			)
		)
		(property "Author" "Antmicro"
			(at 266.2 213.3 0)
			(layer "F.Fab")
			(hide yes)
			(effects
				(font
					(size 1 1)
					(thickness 0.15)
				)
			)
		)
		(property "License" "Apache-2.0"
			(at 266.2 213.3 0)
			(layer "F.Fab")
			(hide yes)
			(effects
				(font
					(size 1 1)
					(thickness 0.15)
				)
			)
		)
		(property "MPN" "CR0402-FX-1202GLF"
			(at 266.2 213.3 0)
			(layer "F.Fab")
			(hide yes)
			(effects
				(font
					(size 1 1)
					(thickness 0.15)
				)
			)
		)
		(property "Manufacturer" "Bourns"
			(at 266.2 213.3 0)
			(layer "F.Fab")
			(hide yes)
			(effects
				(font
					(size 1 1)
					(thickness 0.15)
				)
			)
		)
		(property "Tolerance" "1%"
			(at 266.2 213.3 0)
			(layer "F.Fab")
			(hide yes)
			(effects
				(font
					(size 1 1)
					(thickness 0.15)
				)
			)
		)
		(property "Val" "12k"
			(at 266.2 213.3 0)
			(layer "F.Fab")
			(hide yes)
			(effects
				(font
					(size 1 1)
					(thickness 0.15)
				)
			)
		)
		(sheetname "CSI Connector")
		(sheetfile "CSI.kicad_sch")
		(attr smd)
		(fp_rect
			(start -0.925 -0.47)
			(end 0.925 0.47)
			(stroke
				(width 0.05)
				(type default)
			)
			(fill none)
			(layer "F.CrtYd")
		)
		(fp_rect
			(start -0.5 -0.25)
			(end 0.5 0.25)
			(stroke
				(width 0.15)
				(type solid)
			)
			(fill none)
			(layer "F.Fab")
		)
		(fp_text user "Author: Antmicro"
			(at -0.95 4.169 0)
			(layer "F.Fab")
			(hide yes)
			(effects
				(font
					(size 0.7 0.7)
					(thickness 0.15)
				)
				(justify right bottom)
			)
		)
		(fp_text user "License: Apache-2.0"
			(at -0.95 5.169 0)
			(layer "F.Fab")
			(hide yes)
			(effects
				(font
					(size 0.7 0.7)
					(thickness 0.15)
				)
				(justify right bottom)
			)
		)
		(fp_text user "${REFERENCE}"
			(at -0.95 3.168 0)
			(layer "F.Fab")
			(hide yes)
			(effects
				(font
					(size 0.7 0.7)
					(thickness 0.15)
				)
				(justify right bottom)
			)
		)
		(pad "1" smd roundrect
			(at -0.48 0 180)
			(size 0.59 0.64)
			(layers "F.Cu" "F.Paste" "F.Mask")
			(roundrect_rratio 0.25)
			(net 39 "/CSI Connector/GPIO4_1V8")
			(pintype "passive")
		)
		(pad "2" smd roundrect
			(at 0.48 0 180)
			(size 0.59 0.64)
			(layers "F.Cu" "F.Paste" "F.Mask")
			(roundrect_rratio 0.25)
			(net 1 "GND")
			(pintype "passive")
		)
	)
	(footprint "antmicro-footprints:L_Coilcraft-1210POC"
		(layer "F.Cu")
		(at 158.242 94.742 180)
		(property "Reference" "L4"
			(at -3.238 -0.328 180)
			(layer "F.SilkS")
			(effects
				(font
					(size 0.7 0.7)
					(thickness 0.15)
				)
				(justify right bottom)
			)
		)
		(property "Value" "L_6u8_1A_Coilcraft-1210POC"
			(at 0 2.4 0)
			(layer "F.Fab")
			(effects
				(font
					(size 0.7 0.7)
					(thickness 0.15)
				)
				(justify right bottom)
			)
		)
		(property "Footprint" "antmicro-footprints:L_Coilcraft-1210POC"
			(at 0 0 180)
			(layer "F.Fab")
			(hide yes)
			(effects
				(font
					(size 1.27 1.27)
					(thickness 0.15)
				)
			)
		)
		(property "Datasheet" "https://www.coilcraft.com/getmedia/5e8de018-68c5-4442-84ce-d5212c44660c/1210poc.pdf"
			(at 0 0 180)
			(layer "F.Fab")
			(hide yes)
			(effects
				(font
					(size 1.27 1.27)
					(thickness 0.15)
				)
			)
		)
		(property "Author" "Antmicro"
			(at 316.484 189.484 0)
			(layer "F.Fab")
			(hide yes)
			(effects
				(font
					(size 1 1)
					(thickness 0.15)
				)
			)
		)
		(property "IMax" "1.36 A"
			(at 316.484 189.484 0)
			(layer "F.Fab")
			(hide yes)
			(effects
				(font
					(size 1 1)
					(thickness 0.15)
				)
			)
		)
		(property "ISat" "1 A"
			(at 316.484 189.484 0)
			(layer "F.Fab")
			(hide yes)
			(effects
				(font
					(size 1 1)
					(thickness 0.15)
				)
			)
		)
		(property "License" "Apache-2.0"
			(at 316.484 189.484 0)
			(layer "F.Fab")
			(hide yes)
			(effects
				(font
					(size 1 1)
					(thickness 0.15)
				)
			)
		)
		(property "MPN" "1210POC-682"
			(at 316.484 189.484 0)
			(layer "F.Fab")
			(hide yes)
			(effects
				(font
					(size 1 1)
					(thickness 0.15)
				)
			)
		)
		(property "Manufacturer" "Coilcraft"
			(at 316.484 189.484 0)
			(layer "F.Fab")
			(hide yes)
			(effects
				(font
					(size 1 1)
					(thickness 0.15)
				)
			)
		)
		(property "Size" "2.67x3.3"
			(at 316.484 189.484 0)
			(layer "F.Fab")
			(hide yes)
			(effects
				(font
					(size 1 1)
					(thickness 0.15)
				)
			)
		)
		(property "Val" "6u8/1A"
			(at 316.484 189.484 0)
			(layer "F.Fab")
			(hide yes)
			(effects
				(font
					(size 1 1)
					(thickness 0.15)
				)
			)
		)
		(sheetname "GMSL Connector")
		(sheetfile "GMSL.kicad_sch")
		(attr smd)
		(fp_line
			(start -0.7 1.4)
			(end 0.7 1.4)
			(stroke
				(width 0.15)
				(type solid)
			)
			(layer "F.SilkS")
		)
		(fp_line
			(start -0.7 -1.4)
			(end 0.7 -1.4)
			(stroke
				(width 0.15)
				(type solid)
			)
			(layer "F.SilkS")
		)
		(fp_rect
			(start -1.9 -1.585)
			(end 1.9 1.585)
			(stroke
				(width 0.05)
				(type solid)
			)
			(fill none)
			(layer "F.CrtYd")
		)
		(fp_line
			(start 1.65 1.335)
			(end 1.65 -1.335)
			(stroke
				(width 0.15)
				(type solid)
			)
			(layer "F.Fab")
		)
		(fp_line
			(start 1.65 1.335)
			(end -1.65 1.335)
			(stroke
				(width 0.15)
				(type solid)
			)
			(layer "F.Fab")
		)
		(fp_line
			(start 1.65 -1.335)
			(end -1.65 -1.335)
			(stroke
				(width 0.15)
				(type solid)
			)
			(layer "F.Fab")
		)
		(fp_line
			(start -1.65 1.335)
			(end -1.65 -1.335)
			(stroke
				(width 0.15)
				(type solid)
			)
			(layer "F.Fab")
		)
		(fp_text user "${REFERENCE}"
			(at -2.1 3.95 0)
			(layer "F.Fab")
			(hide yes)
			(effects
				(font
					(size 0.7 0.7)
					(thickness 0.15)
				)
				(justify right bottom)
			)
		)
		(fp_text user "License: Apache-2.0"
			(at -2.1 6.35 0)
			(layer "F.Fab")
			(hide yes)
			(effects
				(font
					(size 0.7 0.7)
					(thickness 0.15)
				)
				(justify right bottom)
			)
		)
		(fp_text user "Author: Antmicro"
			(at -2.1 5.15 0)
			(layer "F.Fab")
			(hide yes)
			(effects
				(font
					(size 0.7 0.7)
					(thickness 0.15)
				)
				(justify right bottom)
			)
		)
		(pad "1" smd rect
			(at -1.27 0 180)
			(size 0.65 2.65)
			(layers "F.Cu" "F.Paste" "F.Mask")
			(net 58 "Net-(L3-Pad2)")
			(pintype "passive")
		)
		(pad "2" smd rect
			(at 1.27 0 180)
			(size 0.65 2.65)
			(layers "F.Cu" "F.Paste" "F.Mask")
			(net 59 "Net-(L4-Pad2)")
			(pintype "passive")
		)
	)
	(footprint "antmicro-footprints:R_0402_1005Metric"
		(layer "F.Cu")
		(at 160.986 98.8)
		(descr "Resistor SMD 0402")
		(tags "resistor SMD 0402")
		(property "Reference" "R11"
			(at -3.069333 -0.6 0)
			(layer "F.SilkS")
			(effects
				(font
					(size 0.7 0.7)
					(thickness 0.15)
				)
				(justify left bottom)
			)
		)
		(property "Value" "R_12k4_0402"
			(at -1.011843 1.772047 0)
			(layer "F.Fab")
			(effects
				(font
					(size 0.7 0.7)
					(thickness 0.15)
				)
				(justify left bottom)
			)
		)
		(property "Footprint" "antmicro-footprints:R_0402_1005Metric"
			(at 0 0 0)
			(layer "F.Fab")
			(hide yes)
			(effects
				(font
					(size 1.27 1.27)
					(thickness 0.15)
				)
			)
		)
		(property "Datasheet" "https://www.bourns.com/docs/product-datasheets/cr.pdf"
			(at 0 0 0)
			(layer "F.Fab")
			(hide yes)
			(effects
				(font
					(size 1.27 1.27)
					(thickness 0.15)
				)
			)
		)
		(property "Author" "Antmicro"
			(at 0 0 0)
			(layer "F.Fab")
			(hide yes)
			(effects
				(font
					(size 1 1)
					(thickness 0.15)
				)
			)
		)
		(property "License" "Apache-2.0"
			(at 0 0 0)
			(layer "F.Fab")
			(hide yes)
			(effects
				(font
					(size 1 1)
					(thickness 0.15)
				)
			)
		)
		(property "MPN" "CR0402-FX-1242GLF"
			(at 0 0 0)
			(layer "F.Fab")
			(hide yes)
			(effects
				(font
					(size 1 1)
					(thickness 0.15)
				)
			)
		)
		(property "Manufacturer" "Bourns"
			(at 0 0 0)
			(layer "F.Fab")
			(hide yes)
			(effects
				(font
					(size 1 1)
					(thickness 0.15)
				)
			)
		)
		(property "Tolerance" "1%"
			(at 0 0 0)
			(layer "F.Fab")
			(hide yes)
			(effects
				(font
					(size 1 1)
					(thickness 0.15)
				)
			)
		)
		(property "Val" "12k4"
			(at 0 0 0)
			(layer "F.Fab")
			(hide yes)
			(effects
				(font
					(size 1 1)
					(thickness 0.15)
				)
			)
		)
		(sheetname "Supply")
		(sheetfile "supply.kicad_sch")
		(attr smd)
		(fp_rect
			(start -0.925 -0.47)
			(end 0.925 0.47)
			(stroke
				(width 0.05)
				(type default)
			)
			(fill none)
			(layer "F.CrtYd")
		)
		(fp_rect
			(start -0.5 -0.25)
			(end 0.5 0.25)
			(stroke
				(width 0.15)
				(type solid)
			)
			(fill none)
			(layer "F.Fab")
		)
		(fp_text user "License: Apache-2.0"
			(at -0.95 5.169 0)
			(layer "F.Fab")
			(hide yes)
			(effects
				(font
					(size 0.7 0.7)
					(thickness 0.15)
				)
				(justify left bottom)
			)
		)
		(fp_text user "Author: Antmicro"
			(at -0.95 4.169 0)
			(layer "F.Fab")
			(hide yes)
			(effects
				(font
					(size 0.7 0.7)
					(thickness 0.15)
				)
				(justify left bottom)
			)
		)
		(fp_text user "${REFERENCE}"
			(at -0.95 3.168 0)
			(layer "F.Fab")
			(hide yes)
			(effects
				(font
					(size 0.7 0.7)
					(thickness 0.15)
				)
				(justify left bottom)
			)
		)
		(pad "1" smd roundrect
			(at -0.48 0)
			(size 0.59 0.64)
			(layers "F.Cu" "F.Paste" "F.Mask")
			(roundrect_rratio 0.25)
			(net 65 "/Supply/FB_1V8")
			(pintype "passive")
		)
		(pad "2" smd roundrect
			(at 0.48 0)
			(size 0.59 0.64)
			(layers "F.Cu" "F.Paste" "F.Mask")
			(roundrect_rratio 0.25)
			(net 8 "/Supply/OUT_1V8")
			(pintype "passive")
		)
	)
	(footprint "antmicro-footprints:TSOT23-6"
		(layer "F.Cu")
		(at 142.195 83.350142 180)
		(property "Reference" "U3"
			(at -0.905 2.500142 0)
			(layer "F.SilkS")
			(effects
				(font
					(size 0.7 0.7)
					(thickness 0.15)
				)
				(justify right top)
			)
		)
		(property "Value" "AP62301_TSOT"
			(at 0.13 1.85 0)
			(layer "F.Fab")
			(effects
				(font
					(size 0.7 0.7)
					(thickness 0.15)
				)
				(justify right top)
			)
		)
		(property "Footprint" "antmicro-footprints:TSOT23-6"
			(at 0 0 0)
			(layer "F.Fab")
			(hide yes)
			(effects
				(font
					(size 1.27 1.27)
					(thickness 0.15)
				)
			)
		)
		(property "Datasheet" "https://www.diodes.com/assets/Datasheets/AP62300_AP62301_AP62300T.pdf"
			(at 0 0 0)
			(layer "F.Fab")
			(hide yes)
			(effects
				(font
					(size 1.27 1.27)
					(thickness 0.15)
				)
			)
		)
		(property "MPN" "AP62301WU-7"
			(at 0 0 180)
			(unlocked yes)
			(layer "F.Fab")
			(hide yes)
			(effects
				(font
					(size 1 1)
					(thickness 0.15)
				)
			)
		)
		(property "Manufacturer" "Diodes Incorporated"
			(at 0 0 180)
			(unlocked yes)
			(layer "F.Fab")
			(hide yes)
			(effects
				(font
					(size 1 1)
					(thickness 0.15)
				)
			)
		)
		(property "Author" "Antmicro"
			(at 0 0 180)
			(unlocked yes)
			(layer "F.Fab")
			(hide yes)
			(effects
				(font
					(size 1 1)
					(thickness 0.15)
				)
			)
		)
		(property "License" "Apache-2.0"
			(at 0 0 180)
			(unlocked yes)
			(layer "F.Fab")
			(hide yes)
			(effects
				(font
					(size 1 1)
					(thickness 0.15)
				)
			)
		)
		(sheetname "Supply")
		(sheetfile "supply.kicad_sch")
		(attr smd)
		(fp_line
			(start 1 1.55)
			(end 1 1.4)
			(stroke
				(width 0.15)
				(type solid)
			)
			(layer "F.SilkS")
		)
		(fp_line
			(start 1 1.55)
			(end -1 1.55)
			(stroke
				(width 0.15)
				(type solid)
			)
			(layer "F.SilkS")
		)
		(fp_line
			(start 1 -1.497)
			(end 1 -1.375)
			(stroke
				(width 0.15)
				(type solid)
			)
			(layer "F.SilkS")
		)
		(fp_line
			(start 1 -1.497)
			(end -1 -1.5)
			(stroke
				(width 0.15)
				(type solid)
			)
			(layer "F.SilkS")
		)
		(fp_line
			(start -1 1.55)
			(end -1 1.4)
			(stroke
				(width 0.15)
				(type solid)
			)
			(layer "F.SilkS")
		)
		(fp_line
			(start -1 -1.5)
			(end -1 -1.375)
			(stroke
				(width 0.15)
				(type solid)
			)
			(layer "F.SilkS")
		)
		(fp_circle
			(center -1.44 -1.5)
			(end -1.39 -1.5)
			(stroke
				(width 0.15)
				(type solid)
			)
			(fill solid)
			(layer "F.SilkS")
		)
		(fp_rect
			(start 1.93 -1.7)
			(end -1.93 1.7)
			(stroke
				(width 0.05)
				(type solid)
			)
			(fill none)
			(layer "F.CrtYd")
		)
		(fp_line
			(start -0.45 -1.521)
			(end -0.876 -1.096)
			(stroke
				(width 0.15)
				(type solid)
			)
			(layer "F.Fab")
		)
		(fp_rect
			(start 0.875 1.528)
			(end -0.875 -1.525)
			(stroke
				(width 0.15)
				(type solid)
			)
			(fill none)
			(layer "F.Fab")
		)
		(fp_text user "License: Apache-2.0"
			(at -1.93 6.199 0)
			(layer "F.Fab")
			(hide yes)
			(effects
				(font
					(size 0.7 0.7)
					(thickness 0.15)
				)
				(justify right top)
			)
		)
		(fp_text user "${REFERENCE}"
			(at -1.93 3.8 0)
			(layer "F.Fab")
			(hide yes)
			(effects
				(font
					(size 0.7 0.7)
					(thickness 0.15)
				)
				(justify right top)
			)
		)
		(fp_text user "Author: Antmicro"
			(at -1.93 5 0)
			(layer "F.Fab")
			(hide yes)
			(effects
				(font
					(size 0.7 0.7)
					(thickness 0.15)
				)
				(justify right top)
			)
		)
		(pad "1" smd rect
			(at -1.301 -0.947 90)
			(size 0.7 1.2)
			(layers "F.Cu" "F.Paste" "F.Mask")
			(net 1 "GND")
			(pinfunction "GND")
			(pintype "power_in")
		)
		(pad "2" smd rect
			(at -1.301 0.004 90)
			(size 0.7 1.2)
			(layers "F.Cu" "F.Paste" "F.Mask")
			(net 72 "/Supply/SW_3V3")
			(pinfunction "SW")
			(pintype "power_out")
		)
		(pad "3" smd rect
			(at -1.301 0.954 90)
			(size 0.7 1.2)
			(layers "F.Cu" "F.Paste" "F.Mask")
			(net 2 "+12V")
			(pinfunction "VIN")
			(pintype "power_in")
		)
		(pad "4" smd rect
			(at 1.299 0.954 90)
			(size 0.7 1.2)
			(layers "F.Cu" "F.Paste" "F.Mask")
			(net 96 "/Supply/FB_3V3")
			(pinfunction "FB")
			(pintype "input")
		)
		(pad "5" smd rect
			(at 1.299 0.004 90)
			(size 0.7 1.2)
			(layers "F.Cu" "F.Paste" "F.Mask")
			(net 97 "/Supply/EN_3V3")
			(pinfunction "EN")
			(pintype "input")
		)
		(pad "6" smd rect
			(at 1.299 -0.947 90)
			(size 0.7 1.2)
			(layers "F.Cu" "F.Paste" "F.Mask")
			(net 93 "Net-(U3-BST)")
			(pinfunction "BST")
			(pintype "output")
		)
	)
	(footprint "antmicro-footprints:L_Coilcraft-PFL1609"
		(layer "F.Cu")
		(at 156.337 92.2 180)
		(property "Reference" "L5"
			(at -2.273 -0.41 180)
			(layer "F.SilkS")
			(effects
				(font
					(size 0.7 0.7)
					(thickness 0.15)
				)
				(justify right bottom)
			)
		)
		(property "Value" "L_470n_1A_Coilcraft-PFL1609"
			(at 0 2 0)
			(layer "F.Fab")
			(effects
				(font
					(size 0.7 0.7)
					(thickness 0.15)
				)
				(justify right bottom)
			)
		)
		(property "Footprint" "antmicro-footprints:L_Coilcraft-PFL1609"
			(at 0 0 180)
			(layer "F.Fab")
			(hide yes)
			(effects
				(font
					(size 1.27 1.27)
					(thickness 0.15)
				)
			)
		)
		(property "Datasheet" "https://www.coilcraft.com/getmedia/2f4cd442-d64d-4413-a518-12fcfd03318d/pfl1609.pdf"
			(at 0 0 180)
			(layer "F.Fab")
			(hide yes)
			(effects
				(font
					(size 1.27 1.27)
					(thickness 0.15)
				)
			)
		)
		(property "Author" "Antmicro"
			(at 312.674 184.4 0)
			(layer "F.Fab")
			(hide yes)
			(effects
				(font
					(size 1 1)
					(thickness 0.15)
				)
			)
		)
		(property "IMax" "1 A"
			(at 312.674 184.4 0)
			(layer "F.Fab")
			(hide yes)
			(effects
				(font
					(size 1 1)
					(thickness 0.15)
				)
			)
		)
		(property "ISat" "0.99 A"
			(at 312.674 184.4 0)
			(layer "F.Fab")
			(hide yes)
			(effects
				(font
					(size 1 1)
					(thickness 0.15)
				)
			)
		)
		(property "License" "Apache-2.0"
			(at 312.674 184.4 0)
			(layer "F.Fab")
			(hide yes)
			(effects
				(font
					(size 1 1)
					(thickness 0.15)
				)
			)
		)
		(property "MPN" "PFL1609-471"
			(at 312.674 184.4 0)
			(layer "F.Fab")
			(hide yes)
			(effects
				(font
					(size 1 1)
					(thickness 0.15)
				)
			)
		)
		(property "Manufacturer" "Coilcraft"
			(at 312.674 184.4 0)
			(layer "F.Fab")
			(hide yes)
			(effects
				(font
					(size 1 1)
					(thickness 0.15)
				)
			)
		)
		(property "Size" "1.07x1.8"
			(at 312.674 184.4 0)
			(layer "F.Fab")
			(hide yes)
			(effects
				(font
					(size 1 1)
					(thickness 0.15)
				)
			)
		)
		(property "Val" "470n/0.99A"
			(at 312.674 184.4 0)
			(layer "F.Fab")
			(hide yes)
			(effects
				(font
					(size 1 1)
					(thickness 0.15)
				)
			)
		)
		(sheetname "GMSL Connector")
		(sheetfile "GMSL.kicad_sch")
		(attr smd)
		(fp_line
			(start -0.23 0.45)
			(end 0.23 0.45)
			(stroke
				(width 0.15)
				(type solid)
			)
			(layer "F.SilkS")
		)
		(fp_line
			(start -0.23 -0.45)
			(end 0.23 -0.45)
			(stroke
				(width 0.15)
				(type solid)
			)
			(layer "F.SilkS")
		)
		(fp_rect
			(start -1.2 -0.84)
			(end 1.2 0.84)
			(stroke
				(width 0.05)
				(type solid)
			)
			(fill none)
			(layer "F.CrtYd")
		)
		(fp_rect
			(start -0.9 -0.535)
			(end 0.9 0.535)
			(stroke
				(width 0.15)
				(type solid)
			)
			(fill none)
			(layer "F.Fab")
		)
		(fp_text user "License: Apache-2.0"
			(at -1.35 6.4 0)
			(layer "F.Fab")
			(hide yes)
			(effects
				(font
					(size 0.7 0.7)
					(thickness 0.15)
				)
				(justify right bottom)
			)
		)
		(fp_text user "${REFERENCE}"
			(at -1.35 4 0)
			(layer "F.Fab")
			(hide yes)
			(effects
				(font
					(size 0.7 0.7)
					(thickness 0.15)
				)
				(justify right bottom)
			)
		)
		(fp_text user "Author: Antmicro"
			(at -1.35 5.2 0)
			(layer "F.Fab")
			(hide yes)
			(effects
				(font
					(size 0.7 0.7)
					(thickness 0.15)
				)
				(justify right bottom)
			)
		)
		(pad "1" smd roundrect
			(at -0.635 0 180)
			(size 0.64 1.02)
			(layers "F.Cu" "F.Paste" "F.Mask")
			(roundrect_rratio 0.15)
			(net 59 "Net-(L4-Pad2)")
			(pintype "passive")
		)
		(pad "2" smd roundrect
			(at 0.635 0 180)
			(size 0.64 1.02)
			(layers "F.Cu" "F.Paste" "F.Mask")
			(roundrect_rratio 0.15)
			(net 60 "Net-(L5-Pad2)")
			(pintype "passive")
		)
	)
	(footprint "antmicro-footprints:R_0402_1005Metric"
		(layer "F.Cu")
		(at 141.1 115.55 90)
		(descr "Resistor SMD 0402")
		(tags "resistor SMD 0402")
		(property "Reference" "R15"
			(at 0.75 0.5 90)
			(layer "F.SilkS")
			(effects
				(font
					(size 0.7 0.7)
					(thickness 0.15)
				)
				(justify left bottom)
			)
		)
		(property "Value" "R_470R_0402"
			(at -1.011843 1.772047 90)
			(layer "F.Fab")
			(effects
				(font
					(size 0.7 0.7)
					(thickness 0.15)
				)
				(justify left bottom)
			)
		)
		(property "Footprint" "antmicro-footprints:R_0402_1005Metric"
			(at 0 0 90)
			(layer "F.Fab")
			(hide yes)
			(effects
				(font
					(size 1.27 1.27)
					(thickness 0.15)
				)
			)
		)
		(property "Datasheet" "https://www.bourns.com/docs/product-datasheets/cr.pdf"
			(at 0 0 90)
			(layer "F.Fab")
			(hide yes)
			(effects
				(font
					(size 1.27 1.27)
					(thickness 0.15)
				)
			)
		)
		(property "Author" "Antmicro"
			(at 256.65 -25.55 0)
			(layer "F.Fab")
			(hide yes)
			(effects
				(font
					(size 1 1)
					(thickness 0.15)
				)
			)
		)
		(property "License" "Apache-2.0"
			(at 256.65 -25.55 0)
			(layer "F.Fab")
			(hide yes)
			(effects
				(font
					(size 1 1)
					(thickness 0.15)
				)
			)
		)
		(property "MPN" "CR0402-FX-4700GLF"
			(at 256.65 -25.55 0)
			(layer "F.Fab")
			(hide yes)
			(effects
				(font
					(size 1 1)
					(thickness 0.15)
				)
			)
		)
		(property "Manufacturer" "Bourns"
			(at 256.65 -25.55 0)
			(layer "F.Fab")
			(hide yes)
			(effects
				(font
					(size 1 1)
					(thickness 0.15)
				)
			)
		)
		(property "Tolerance" "1%"
			(at 256.65 -25.55 0)
			(layer "F.Fab")
			(hide yes)
			(effects
				(font
					(size 1 1)
					(thickness 0.15)
				)
			)
		)
		(property "Val" "470R"
			(at 256.65 -25.55 0)
			(layer "F.Fab")
			(hide yes)
			(effects
				(font
					(size 1 1)
					(thickness 0.15)
				)
			)
		)
		(sheetname "Supply")
		(sheetfile "supply.kicad_sch")
		(attr smd)
		(fp_rect
			(start -0.925 -0.47)
			(end 0.925 0.47)
			(stroke
				(width 0.05)
				(type default)
			)
			(fill none)
			(layer "F.CrtYd")
		)
		(fp_rect
			(start -0.5 -0.25)
			(end 0.5 0.25)
			(stroke
				(width 0.15)
				(type solid)
			)
			(fill none)
			(layer "F.Fab")
		)
		(fp_text user "License: Apache-2.0"
			(at -0.95 5.169 90)
			(layer "F.Fab")
			(hide yes)
			(effects
				(font
					(size 0.7 0.7)
					(thickness 0.15)
				)
				(justify left bottom)
			)
		)
		(fp_text user "Author: Antmicro"
			(at -0.95 4.169 90)
			(layer "F.Fab")
			(hide yes)
			(effects
				(font
					(size 0.7 0.7)
					(thickness 0.15)
				)
				(justify left bottom)
			)
		)
		(fp_text user "${REFERENCE}"
			(at -0.95 3.168 90)
			(layer "F.Fab")
			(hide yes)
			(effects
				(font
					(size 0.7 0.7)
					(thickness 0.15)
				)
				(justify left bottom)
			)
		)
		(pad "1" smd roundrect
			(at -0.48 0 90)
			(size 0.59 0.64)
			(layers "F.Cu" "F.Paste" "F.Mask")
			(roundrect_rratio 0.25)
			(net 1 "GND")
			(pintype "passive")
		)
		(pad "2" smd roundrect
			(at 0.48 0 90)
			(size 0.59 0.64)
			(layers "F.Cu" "F.Paste" "F.Mask")
			(roundrect_rratio 0.25)
			(net 69 "Net-(D5-C)")
			(pintype "passive")
		)
	)
	(footprint "antmicro-footprints:MP_Pad6mm_Drill3mm"
		(layer "F.Cu")
		(at 134.15 117.35)
		(property "Reference" "MP3"
			(at 0 -3.2 0)
			(layer "F.SilkS")
			(hide yes)
			(effects
				(font
					(size 0.7 0.7)
					(thickness 0.15)
				)
				(justify left bottom)
			)
		)
		(property "Value" "MP_Pad6mm_Drill3mm"
			(at 0 3.9 0)
			(layer "F.Fab")
			(effects
				(font
					(size 0.7 0.7)
					(thickness 0.15)
				)
				(justify left bottom)
			)
		)
		(property "Footprint" "antmicro-footprints:MP_Pad6mm_Drill3mm"
			(at 0 0 0)
			(layer "F.Fab")
			(hide yes)
			(effects
				(font
					(size 1.27 1.27)
					(thickness 0.15)
				)
			)
		)
		(property "Author" "Antmicro"
			(at 0 0 0)
			(layer "F.Fab")
			(hide yes)
			(effects
				(font
					(size 1 1)
					(thickness 0.15)
				)
			)
		)
		(property "License" "Apache-2.0"
			(at 0 0 0)
			(layer "F.Fab")
			(hide yes)
			(effects
				(font
					(size 1 1)
					(thickness 0.15)
				)
			)
		)
		(sheetname "Root")
		(sheetfile "gmsl-serializer.kicad_sch")
		(attr exclude_from_pos_files exclude_from_bom)
		(fp_circle
			(center 0 0)
			(end 3.25 0)
			(stroke
				(width 0.05)
				(type default)
			)
			(fill none)
			(layer "F.CrtYd")
		)
		(fp_text user "License: Apache-2.0"
			(at -0.178 8.425 0)
			(layer "F.Fab")
			(hide yes)
			(effects
				(font
					(size 0.7 0.7)
					(thickness 0.15)
				)
				(justify left bottom)
			)
		)
		(fp_text user "Author: Antmicro"
			(at -0.178 7.225 0)
			(layer "F.Fab")
			(hide yes)
			(effects
				(font
					(size 0.7 0.7)
					(thickness 0.15)
				)
				(justify left bottom)
			)
		)
		(fp_text user "${REFERENCE}"
			(at -0.178 6.025 0)
			(layer "F.Fab")
			(hide yes)
			(effects
				(font
					(size 0.7 0.7)
					(thickness 0.15)
				)
				(justify left bottom)
			)
		)
		(pad "1" thru_hole circle
			(at 0 0)
			(size 6 6)
			(drill 3)
			(layers "*.Cu" "*.Mask")
			(remove_unused_layers no)
			(net 1 "GND")
			(pintype "passive")
			(solder_paste_margin_ratio -1)
		)
	)
	(footprint "antmicro-footprints:SOT-523"
		(layer "F.Cu")
		(at 151.17 113.3 90)
		(property "Reference" "Q1"
			(at -0.7 1.825 90)
			(layer "F.SilkS")
			(effects
				(font
					(size 0.7 0.7)
					(thickness 0.15)
				)
				(justify left bottom)
			)
		)
		(property "Value" "DMG1012T-7"
			(at 0.1 1.824 90)
			(layer "F.Fab")
			(effects
				(font
					(size 0.7 0.7)
					(thickness 0.15)
				)
				(justify left bottom)
			)
		)
		(property "Footprint" "antmicro-footprints:SOT-523"
			(at 0 0 90)
			(layer "F.Fab")
			(hide yes)
			(effects
				(font
					(size 1.27 1.27)
					(thickness 0.15)
				)
			)
		)
		(property "Datasheet" "https://www.diodes.com/assets/Datasheets/ds31783.pdf"
			(at 0 0 90)
			(layer "F.Fab")
			(hide yes)
			(effects
				(font
					(size 1.27 1.27)
					(thickness 0.15)
				)
			)
		)
		(property "Author" "Antmicro"
			(at 264.47 -37.87 0)
			(layer "F.Fab")
			(hide yes)
			(effects
				(font
					(size 1 1)
					(thickness 0.15)
				)
			)
		)
		(property "License" "Apache-2.0"
			(at 264.47 -37.87 0)
			(layer "F.Fab")
			(hide yes)
			(effects
				(font
					(size 1 1)
					(thickness 0.15)
				)
			)
		)
		(property "MPN" "DMG1012T-7"
			(at 264.47 -37.87 0)
			(layer "F.Fab")
			(hide yes)
			(effects
				(font
					(size 1 1)
					(thickness 0.15)
				)
			)
		)
		(property "Manufacturer" "Diodes Incorporated"
			(at 264.47 -37.87 0)
			(layer "F.Fab")
			(hide yes)
			(effects
				(font
					(size 1 1)
					(thickness 0.15)
				)
			)
		)
		(property "Public" ""
			(at 264.47 -37.87 0)
			(layer "F.Fab")
			(hide yes)
			(effects
				(font
					(size 1 1)
					(thickness 0.15)
				)
			)
		)
		(sheetname "Supply")
		(sheetfile "supply.kicad_sch")
		(attr smd exclude_from_bom)
		(fp_line
			(start -0.277 -0.551)
			(end -0.277 -0.75)
			(stroke
				(width 0.15)
				(type solid)
			)
			(layer "F.SilkS")
		)
		(fp_line
			(start -0.725 -0.551)
			(end -0.277 -0.551)
			(stroke
				(width 0.15)
				(type solid)
			)
			(layer "F.SilkS")
		)
		(fp_line
			(start -0.927 -0.351)
			(end -0.725 -0.551)
			(stroke
				(width 0.15)
				(type solid)
			)
			(layer "F.SilkS")
		)
		(fp_line
			(start -0.927 -0.051)
			(end -0.927 -0.351)
			(stroke
				(width 0.15)
				(type solid)
			)
			(layer "F.SilkS")
		)
		(fp_circle
			(center -0.9652 0.9652)
			(end -0.9152 0.9652)
			(stroke
				(width 0.15)
				(type solid)
			)
			(fill solid)
			(layer "F.SilkS")
		)
		(fp_line
			(start 1.1 -1.16)
			(end 1.1 1.15)
			(stroke
				(width 0.05)
				(type solid)
			)
			(layer "F.CrtYd")
		)
		(fp_line
			(start -1.12 -1.16)
			(end 1.1 -1.16)
			(stroke
				(width 0.05)
				(type solid)
			)
			(layer "F.CrtYd")
		)
		(fp_line
			(start -1.12 -1.16)
			(end -1.12 1.15)
			(stroke
				(width 0.05)
				(type solid)
			)
			(layer "F.CrtYd")
		)
		(fp_line
			(start -1.12 1.15)
			(end 1.1 1.15)
			(stroke
				(width 0.05)
				(type solid)
			)
			(layer "F.CrtYd")
		)
		(fp_line
			(start 0.8 -0.425)
			(end -0.652 -0.425)
			(stroke
				(width 0.15)
				(type solid)
			)
			(layer "F.Fab")
		)
		(fp_line
			(start 0.8 -0.425)
			(end 0.8 0.424)
			(stroke
				(width 0.15)
				(type solid)
			)
			(layer "F.Fab")
		)
		(fp_line
			(start -0.652 -0.425)
			(end -0.802 -0.276)
			(stroke
				(width 0.15)
				(type solid)
			)
			(layer "F.Fab")
		)
		(fp_line
			(start -0.802 -0.276)
			(end -0.802 0.424)
			(stroke
				(width 0.15)
				(type solid)
			)
			(layer "F.Fab")
		)
		(fp_line
			(start 0.8 0.424)
			(end -0.802 0.424)
			(stroke
				(width 0.15)
				(type solid)
			)
			(layer "F.Fab")
		)
		(fp_circle
			(center -0.9652 0.9652)
			(end -0.9144 0.9652)
			(stroke
				(width 0.15)
				(type solid)
			)
			(fill none)
			(layer "F.Fab")
		)
		(fp_text user "Author: Antmicro"
			(at -1.12 6.224 90)
			(layer "F.Fab")
			(hide yes)
			(effects
				(font
					(size 0.7 0.7)
					(thickness 0.15)
				)
				(justify left bottom)
			)
		)
		(fp_text user "${REFERENCE}"
			(at -1.12 3.824 90)
			(layer "F.Fab")
			(hide yes)
			(effects
				(font
					(size 0.7 0.7)
					(thickness 0.15)
				)
				(justify left bottom)
			)
		)
		(fp_text user "License: Apache-2.0"
			(at -1.12 5.024 90)
			(layer "F.Fab")
			(hide yes)
			(effects
				(font
					(size 0.7 0.7)
					(thickness 0.15)
				)
				(justify left bottom)
			)
		)
		(pad "1" smd rect
			(at -0.5 0.65 90)
			(size 0.4 0.51)
			(layers "F.Cu" "F.Paste" "F.Mask")
			(net 12 "+1V2")
			(pinfunction "G")
			(pintype "passive")
		)
		(pad "2" smd rect
			(at 0.498 0.65 90)
			(size 0.4 0.51)
			(layers "F.Cu" "F.Paste" "F.Mask")
			(net 1 "GND")
			(pinfunction "S")
			(pintype "passive")
		)
		(pad "3" smd rect
			(at 0 -0.652 90)
			(size 0.4 0.51)
			(layers "F.Cu" "F.Paste" "F.Mask")
			(net 70 "Net-(D6-C)")
			(pinfunction "D")
			(pintype "passive")
		)
	)
	(footprint "antmicro-footprints:R_0402_1005Metric"
		(layer "F.Cu")
		(at 150.16 111.355 180)
		(descr "Resistor SMD 0402")
		(tags "resistor SMD 0402")
		(property "Reference" "R22"
			(at -3.05 -0.37 0)
			(layer "F.SilkS")
			(effects
				(font
					(size 0.7 0.7)
					(thickness 0.15)
				)
				(justify right bottom)
			)
		)
		(property "Value" "R_10k_0402"
			(at -1.011843 1.772047 0)
			(layer "F.Fab")
			(effects
				(font
					(size 0.7 0.7)
					(thickness 0.15)
				)
				(justify right bottom)
			)
		)
		(property "Footprint" "antmicro-footprints:R_0402_1005Metric"
			(at 0 0 180)
			(layer "F.Fab")
			(hide yes)
			(effects
				(font
					(size 1.27 1.27)
					(thickness 0.15)
				)
			)
		)
		(property "Datasheet" "https://www.bourns.com/docs/product-datasheets/cr.pdf"
			(at 0 0 180)
			(layer "F.Fab")
			(hide yes)
			(effects
				(font
					(size 1.27 1.27)
					(thickness 0.15)
				)
			)
		)
		(property "Author" "Antmicro"
			(at 300.32 222.71 0)
			(layer "F.Fab")
			(hide yes)
			(effects
				(font
					(size 1 1)
					(thickness 0.15)
				)
			)
		)
		(property "License" "Apache-2.0"
			(at 300.32 222.71 0)
			(layer "F.Fab")
			(hide yes)
			(effects
				(font
					(size 1 1)
					(thickness 0.15)
				)
			)
		)
		(property "MPN" "CR0402-FX-1002GLF"
			(at 300.32 222.71 0)
			(layer "F.Fab")
			(hide yes)
			(effects
				(font
					(size 1 1)
					(thickness 0.15)
				)
			)
		)
		(property "Manufacturer" "Bourns"
			(at 300.32 222.71 0)
			(layer "F.Fab")
			(hide yes)
			(effects
				(font
					(size 1 1)
					(thickness 0.15)
				)
			)
		)
		(property "Tolerance" "1%"
			(at 300.32 222.71 0)
			(layer "F.Fab")
			(hide yes)
			(effects
				(font
					(size 1 1)
					(thickness 0.15)
				)
			)
		)
		(property "Val" "10k"
			(at 300.32 222.71 0)
			(layer "F.Fab")
			(hide yes)
			(effects
				(font
					(size 1 1)
					(thickness 0.15)
				)
			)
		)
		(sheetname "Serializer")
		(sheetfile "serializer.kicad_sch")
		(attr smd exclude_from_bom dnp)
		(fp_rect
			(start -0.925 -0.47)
			(end 0.925 0.47)
			(stroke
				(width 0.05)
				(type default)
			)
			(fill none)
			(layer "F.CrtYd")
		)
		(fp_rect
			(start -0.5 -0.25)
			(end 0.5 0.25)
			(stroke
				(width 0.15)
				(type solid)
			)
			(fill none)
			(layer "F.Fab")
		)
		(fp_text user "Author: Antmicro"
			(at -0.95 4.169 0)
			(layer "F.Fab")
			(hide yes)
			(effects
				(font
					(size 0.7 0.7)
					(thickness 0.15)
				)
				(justify right bottom)
			)
		)
		(fp_text user "License: Apache-2.0"
			(at -0.95 5.169 0)
			(layer "F.Fab")
			(hide yes)
			(effects
				(font
					(size 0.7 0.7)
					(thickness 0.15)
				)
				(justify right bottom)
			)
		)
		(fp_text user "${REFERENCE}"
			(at -0.95 3.168 0)
			(layer "F.Fab")
			(hide yes)
			(effects
				(font
					(size 0.7 0.7)
					(thickness 0.15)
				)
				(justify right bottom)
			)
		)
		(pad "1" smd roundrect
			(at -0.48 0 180)
			(size 0.59 0.64)
			(layers "F.Cu" "F.Paste" "F.Mask")
			(roundrect_rratio 0.25)
			(net 1 "GND")
			(pintype "passive")
		)
		(pad "2" smd roundrect
			(at 0.48 0 180)
			(size 0.59 0.64)
			(layers "F.Cu" "F.Paste" "F.Mask")
			(roundrect_rratio 0.25)
			(net 68 "/Serializer/CFG1")
			(pintype "passive")
		)
	)
	(footprint "antmicro-footprints:R_0402_1005Metric"
		(layer "F.Cu")
		(at 132.17 81.196 180)
		(descr "Resistor SMD 0402")
		(tags "resistor SMD 0402")
		(property "Reference" "R9"
			(at 0.39 -1.454 0)
			(layer "F.SilkS")
			(effects
				(font
					(size 0.7 0.7)
					(thickness 0.15)
				)
				(justify right bottom)
			)
		)
		(property "Value" "R_52k3_0402"
			(at -1.011843 1.772047 0)
			(layer "F.Fab")
			(effects
				(font
					(size 0.7 0.7)
					(thickness 0.15)
				)
				(justify right bottom)
			)
		)
		(property "Footprint" "antmicro-footprints:R_0402_1005Metric"
			(at 0 0 180)
			(layer "F.Fab")
			(hide yes)
			(effects
				(font
					(size 1.27 1.27)
					(thickness 0.15)
				)
			)
		)
		(property "Datasheet" "https://www.bourns.com/docs/product-datasheets/cr.pdf"
			(at 0 0 180)
			(layer "F.Fab")
			(hide yes)
			(effects
				(font
					(size 1.27 1.27)
					(thickness 0.15)
				)
			)
		)
		(property "Author" "Antmicro"
			(at 265 164.692 0)
			(layer "F.Fab")
			(hide yes)
			(effects
				(font
					(size 1 1)
					(thickness 0.15)
				)
			)
		)
		(property "License" "Apache-2.0"
			(at 265 164.692 0)
			(layer "F.Fab")
			(hide yes)
			(effects
				(font
					(size 1 1)
					(thickness 0.15)
				)
			)
		)
		(property "MPN" "CR0402-FX-5232GLF"
			(at 265 164.692 0)
			(layer "F.Fab")
			(hide yes)
			(effects
				(font
					(size 1 1)
					(thickness 0.15)
				)
			)
		)
		(property "Manufacturer" "Bourns"
			(at 265 164.692 0)
			(layer "F.Fab")
			(hide yes)
			(effects
				(font
					(size 1 1)
					(thickness 0.15)
				)
			)
		)
		(property "Tolerance" "1%"
			(at 265 164.692 0)
			(layer "F.Fab")
			(hide yes)
			(effects
				(font
					(size 1 1)
					(thickness 0.15)
				)
			)
		)
		(property "Val" "52k3"
			(at 265 164.692 0)
			(layer "F.Fab")
			(hide yes)
			(effects
				(font
					(size 1 1)
					(thickness 0.15)
				)
			)
		)
		(sheetname "Supply")
		(sheetfile "supply.kicad_sch")
		(attr smd)
		(fp_rect
			(start -0.925 -0.47)
			(end 0.925 0.47)
			(stroke
				(width 0.05)
				(type default)
			)
			(fill none)
			(layer "F.CrtYd")
		)
		(fp_rect
			(start -0.5 -0.25)
			(end 0.5 0.25)
			(stroke
				(width 0.15)
				(type solid)
			)
			(fill none)
			(layer "F.Fab")
		)
		(fp_text user "${REFERENCE}"
			(at -0.95 3.168 0)
			(layer "F.Fab")
			(hide yes)
			(effects
				(font
					(size 0.7 0.7)
					(thickness 0.15)
				)
				(justify right bottom)
			)
		)
		(fp_text user "Author: Antmicro"
			(at -0.95 4.169 0)
			(layer "F.Fab")
			(hide yes)
			(effects
				(font
					(size 0.7 0.7)
					(thickness 0.15)
				)
				(justify right bottom)
			)
		)
		(fp_text user "License: Apache-2.0"
			(at -0.95 5.169 0)
			(layer "F.Fab")
			(hide yes)
			(effects
				(font
					(size 0.7 0.7)
					(thickness 0.15)
				)
				(justify right bottom)
			)
		)
		(pad "1" smd roundrect
			(at -0.48 0 180)
			(size 0.59 0.64)
			(layers "F.Cu" "F.Paste" "F.Mask")
			(roundrect_rratio 0.25)
			(net 64 "/Supply/FB_5V")
			(pintype "passive")
		)
		(pad "2" smd roundrect
			(at 0.48 0 180)
			(size 0.59 0.64)
			(layers "F.Cu" "F.Paste" "F.Mask")
			(roundrect_rratio 0.25)
			(net 7 "/Supply/OUT_5V")
			(pintype "passive")
		)
	)
	(footprint "antmicro-footprints:R_0402_1005Metric"
		(layer "F.Cu")
		(at 148.15 110.28 180)
		(descr "Resistor SMD 0402")
		(tags "resistor SMD 0402")
		(property "Reference" "R18"
			(at 0.93 -0.4 0)
			(layer "F.SilkS")
			(effects
				(font
					(size 0.7 0.7)
					(thickness 0.15)
				)
				(justify right bottom)
			)
		)
		(property "Value" "R_80k6_0402"
			(at -1.011843 1.772047 0)
			(layer "F.Fab")
			(effects
				(font
					(size 0.7 0.7)
					(thickness 0.15)
				)
				(justify right bottom)
			)
		)
		(property "Footprint" "antmicro-footprints:R_0402_1005Metric"
			(at 0 0 180)
			(layer "F.Fab")
			(hide yes)
			(effects
				(font
					(size 1.27 1.27)
					(thickness 0.15)
				)
			)
		)
		(property "Datasheet" "https://www.bourns.com/docs/product-datasheets/cr.pdf"
			(at 0 0 180)
			(layer "F.Fab")
			(hide yes)
			(effects
				(font
					(size 1.27 1.27)
					(thickness 0.15)
				)
			)
		)
		(property "Author" "Antmicro"
			(at 296.3 220.56 0)
			(layer "F.Fab")
			(hide yes)
			(effects
				(font
					(size 1 1)
					(thickness 0.15)
				)
			)
		)
		(property "License" "Apache-2.0"
			(at 296.3 220.56 0)
			(layer "F.Fab")
			(hide yes)
			(effects
				(font
					(size 1 1)
					(thickness 0.15)
				)
			)
		)
		(property "MPN" "CR0402-FX-8062GLF"
			(at 296.3 220.56 0)
			(layer "F.Fab")
			(hide yes)
			(effects
				(font
					(size 1 1)
					(thickness 0.15)
				)
			)
		)
		(property "Manufacturer" "Bourns"
			(at 296.3 220.56 0)
			(layer "F.Fab")
			(hide yes)
			(effects
				(font
					(size 1 1)
					(thickness 0.15)
				)
			)
		)
		(property "Tolerance" "1%"
			(at 296.3 220.56 0)
			(layer "F.Fab")
			(hide yes)
			(effects
				(font
					(size 1 1)
					(thickness 0.15)
				)
			)
		)
		(property "Val" "80k6"
			(at 296.3 220.56 0)
			(layer "F.Fab")
			(hide yes)
			(effects
				(font
					(size 1 1)
					(thickness 0.15)
				)
			)
		)
		(sheetname "Serializer")
		(sheetfile "serializer.kicad_sch")
		(attr smd exclude_from_bom dnp)
		(fp_rect
			(start -0.925 -0.47)
			(end 0.925 0.47)
			(stroke
				(width 0.05)
				(type default)
			)
			(fill none)
			(layer "F.CrtYd")
		)
		(fp_rect
			(start -0.5 -0.25)
			(end 0.5 0.25)
			(stroke
				(width 0.15)
				(type solid)
			)
			(fill none)
			(layer "F.Fab")
		)
		(fp_text user "License: Apache-2.0"
			(at -0.95 5.169 0)
			(layer "F.Fab")
			(hide yes)
			(effects
				(font
					(size 0.7 0.7)
					(thickness 0.15)
				)
				(justify right bottom)
			)
		)
		(fp_text user "${REFERENCE}"
			(at -0.95 3.168 0)
			(layer "F.Fab")
			(hide yes)
			(effects
				(font
					(size 0.7 0.7)
					(thickness 0.15)
				)
				(justify right bottom)
			)
		)
		(fp_text user "Author: Antmicro"
			(at -0.95 4.169 0)
			(layer "F.Fab")
			(hide yes)
			(effects
				(font
					(size 0.7 0.7)
					(thickness 0.15)
				)
				(justify right bottom)
			)
		)
		(pad "1" smd roundrect
			(at -0.48 0 180)
			(size 0.59 0.64)
			(layers "F.Cu" "F.Paste" "F.Mask")
			(roundrect_rratio 0.25)
			(net 66 "/Serializer/CFG0")
			(pintype "passive")
		)
		(pad "2" smd roundrect
			(at 0.48 0 180)
			(size 0.59 0.64)
			(layers "F.Cu" "F.Paste" "F.Mask")
			(roundrect_rratio 0.25)
			(net 10 "+3V3")
			(pintype "passive")
		)
	)
	(footprint "antmicro-footprints:TP_SMD_1.5mm"
		(layer "F.Cu")
		(at 139.5 118 180)
		(property "Reference" "TP3"
			(at -1.6 1 0)
			(layer "F.SilkS")
			(hide yes)
			(effects
				(font
					(size 0.7 0.7)
					(thickness 0.15)
				)
				(justify right bottom)
			)
		)
		(property "Value" "TP_1.5mm_SMD"
			(at 0 1.7 0)
			(layer "F.Fab")
			(effects
				(font
					(size 0.7 0.7)
					(thickness 0.15)
				)
				(justify right bottom)
			)
		)
		(property "Footprint" "antmicro-footprints:TP_SMD_1.5mm"
			(at 0 0 180)
			(layer "F.Fab")
			(hide yes)
			(effects
				(font
					(size 1.27 1.27)
					(thickness 0.15)
				)
			)
		)
		(property "Author" "Antmicro"
			(at 279 236 0)
			(layer "F.Fab")
			(hide yes)
			(effects
				(font
					(size 1 1)
					(thickness 0.15)
				)
			)
		)
		(property "License" "Apache-2.0"
			(at 279 236 0)
			(layer "F.Fab")
			(hide yes)
			(effects
				(font
					(size 1 1)
					(thickness 0.15)
				)
			)
		)
		(property "MPN" ""
			(at 279 236 0)
			(layer "F.Fab")
			(hide yes)
			(effects
				(font
					(size 1 1)
					(thickness 0.15)
				)
			)
		)
		(property "Manufacturer" ""
			(at 279 236 0)
			(layer "F.Fab")
			(hide yes)
			(effects
				(font
					(size 1 1)
					(thickness 0.15)
				)
			)
		)
		(sheetname "GMSL Connector")
		(sheetfile "GMSL.kicad_sch")
		(attr exclude_from_pos_files exclude_from_bom)
		(fp_circle
			(center 0 0)
			(end 0.85 0)
			(stroke
				(width 0.05)
				(type default)
			)
			(fill none)
			(layer "F.CrtYd")
		)
		(fp_text user "License: Apache-2.0"
			(at -0.7 5.301 0)
			(layer "F.Fab")
			(hide yes)
			(effects
				(font
					(size 0.7 0.7)
					(thickness 0.15)
				)
				(justify right bottom)
			)
		)
		(fp_text user "Author: Antmicro"
			(at -0.7 4.101 0)
			(layer "F.Fab")
			(hide yes)
			(effects
				(font
					(size 0.7 0.7)
					(thickness 0.15)
				)
				(justify right bottom)
			)
		)
		(fp_text user "${REFERENCE}"
			(at -0.7 2.9 0)
			(layer "F.Fab")
			(hide yes)
			(effects
				(font
					(size 0.7 0.7)
					(thickness 0.15)
				)
				(justify right bottom)
			)
		)
		(pad "1" smd circle
			(at 0 0 90)
			(size 1.5 1.5)
			(layers "F.Cu" "F.Mask")
			(net 2 "+12V")
			(pinfunction "1")
			(pintype "passive")
		)
	)
	(footprint "antmicro-footprints:C_0402_1005Metric"
		(layer "F.Cu")
		(at 151.032448 98.81 45)
		(descr "Capacitor SMD 0402")
		(tags "capacitor SMD 0402")
		(property "Reference" "C30"
			(at 2.226539 0.456738 45)
			(layer "F.SilkS")
			(effects
				(font
					(size 0.7 0.7)
					(thickness 0.15)
				)
				(justify left bottom)
			)
		)
		(property "Value" "C_100n_0402"
			(at -1.022927 2.155213 45)
			(layer "F.Fab")
			(effects
				(font
					(size 0.7 0.7)
					(thickness 0.15)
				)
				(justify left bottom)
			)
		)
		(property "Footprint" "antmicro-footprints:C_0402_1005Metric"
			(at 0 0 45)
			(layer "F.Fab")
			(hide yes)
			(effects
				(font
					(size 1.27 1.27)
					(thickness 0.15)
				)
			)
		)
		(property "Datasheet" "https://www.murata.com/products/productdetail?partno=GRM155R61H104KE14%23"
			(at 0 0 45)
			(layer "F.Fab")
			(hide yes)
			(effects
				(font
					(size 1.27 1.27)
					(thickness 0.15)
				)
			)
		)
		(property "Author" "Antmicro"
			(at 114.105601 -77.855289 0)
			(layer "F.Fab")
			(hide yes)
			(effects
				(font
					(size 1 1)
					(thickness 0.15)
				)
			)
		)
		(property "Dielectric" "X5R"
			(at 114.105601 -77.855289 0)
			(layer "F.Fab")
			(hide yes)
			(effects
				(font
					(size 1 1)
					(thickness 0.15)
				)
			)
		)
		(property "License" "Apache-2.0"
			(at 114.105601 -77.855289 0)
			(layer "F.Fab")
			(hide yes)
			(effects
				(font
					(size 1 1)
					(thickness 0.15)
				)
			)
		)
		(property "MPN" "GRM155R61H104KE14D"
			(at 114.105601 -77.855289 0)
			(layer "F.Fab")
			(hide yes)
			(effects
				(font
					(size 1 1)
					(thickness 0.15)
				)
			)
		)
		(property "Manufacturer" "Murata"
			(at 114.105601 -77.855289 0)
			(layer "F.Fab")
			(hide yes)
			(effects
				(font
					(size 1 1)
					(thickness 0.15)
				)
			)
		)
		(property "Val" "100n"
			(at 114.105601 -77.855289 0)
			(layer "F.Fab")
			(hide yes)
			(effects
				(font
					(size 1 1)
					(thickness 0.15)
				)
			)
		)
		(property "Voltage" "50V"
			(at 114.105601 -77.855289 0)
			(layer "F.Fab")
			(hide yes)
			(effects
				(font
					(size 1 1)
					(thickness 0.15)
				)
			)
		)
		(sheetname "Serializer")
		(sheetfile "serializer.kicad_sch")
		(attr smd)
		(fp_poly
			(pts
				(xy -0.925 -0.47) (xy 0.925 -0.47) (xy 0.925 0.47) (xy -0.925 0.47)
			)
			(stroke
				(width 0.05)
				(type default)
			)
			(fill none)
			(layer "F.CrtYd")
		)
		(fp_line
			(start -0.494 -0.25)
			(end 0.504 -0.25)
			(stroke
				(width 0.15)
				(type solid)
			)
			(layer "F.Fab")
		)
		(fp_line
			(start -0.494 0.248)
			(end -0.494 -0.25)
			(stroke
				(width 0.15)
				(type solid)
			)
			(layer "F.Fab")
		)
		(fp_line
			(start 0.504 -0.25)
			(end 0.504 0.248)
			(stroke
				(width 0.15)
				(type solid)
			)
			(layer "F.Fab")
		)
		(fp_line
			(start 0.504 0.248)
			(end -0.494 0.248)
			(stroke
				(width 0.15)
				(type solid)
			)
			(layer "F.Fab")
		)
		(fp_text user "${REFERENCE}"
			(at -0.939 4.599 45)
			(layer "F.Fab")
			(hide yes)
			(effects
				(font
					(size 0.7 0.7)
					(thickness 0.15)
				)
				(justify left bottom)
			)
		)
		(fp_text user "Author: Antmicro"
			(at -0.939 3.399 45)
			(layer "F.Fab")
			(hide yes)
			(effects
				(font
					(size 0.7 0.7)
					(thickness 0.15)
				)
				(justify left bottom)
			)
		)
		(fp_text user "License: Apache-2.0"
			(at -0.939 5.799 45)
			(layer "F.Fab")
			(hide yes)
			(effects
				(font
					(size 0.7 0.7)
					(thickness 0.15)
				)
				(justify left bottom)
			)
		)
		(pad "1" smd roundrect
			(at -0.48 0 45)
			(size 0.59 0.64)
			(layers "F.Cu" "F.Paste" "F.Mask")
			(roundrect_rratio 0.25)
			(net 17 "Net-(U6-SIOP)")
			(pintype "passive")
		)
		(pad "2" smd roundrect
			(at 0.48 0 45)
			(size 0.59 0.64)
			(layers "F.Cu" "F.Paste" "F.Mask")
			(roundrect_rratio 0.25)
			(net 18 "/GMSL Connector/SIO_P")
			(pintype "passive")
		)
	)
	(footprint "antmicro-footprints:R_0402_1005Metric"
		(layer "F.Cu")
		(at 132.17 80.15)
		(descr "Resistor SMD 0402")
		(tags "resistor SMD 0402")
		(property "Reference" "R10"
			(at -1.1 -0.6 0)
			(layer "F.SilkS")
			(effects
				(font
					(size 0.7 0.7)
					(thickness 0.15)
				)
				(justify left bottom)
			)
		)
		(property "Value" "R_10k_0402"
			(at -1.011843 1.772047 0)
			(layer "F.Fab")
			(effects
				(font
					(size 0.7 0.7)
					(thickness 0.15)
				)
				(justify left bottom)
			)
		)
		(property "Footprint" "antmicro-footprints:R_0402_1005Metric"
			(at 0 0 0)
			(layer "F.Fab")
			(hide yes)
			(effects
				(font
					(size 1.27 1.27)
					(thickness 0.15)
				)
			)
		)
		(property "Datasheet" "https://www.bourns.com/docs/product-datasheets/cr.pdf"
			(at 0 0 0)
			(layer "F.Fab")
			(hide yes)
			(effects
				(font
					(size 1.27 1.27)
					(thickness 0.15)
				)
			)
		)
		(property "Author" "Antmicro"
			(at 0 0 0)
			(layer "F.Fab")
			(hide yes)
			(effects
				(font
					(size 1 1)
					(thickness 0.15)
				)
			)
		)
		(property "License" "Apache-2.0"
			(at 0 0 0)
			(layer "F.Fab")
			(hide yes)
			(effects
				(font
					(size 1 1)
					(thickness 0.15)
				)
			)
		)
		(property "MPN" "CR0402-FX-1002GLF"
			(at 0 0 0)
			(layer "F.Fab")
			(hide yes)
			(effects
				(font
					(size 1 1)
					(thickness 0.15)
				)
			)
		)
		(property "Manufacturer" "Bourns"
			(at 0 0 0)
			(layer "F.Fab")
			(hide yes)
			(effects
				(font
					(size 1 1)
					(thickness 0.15)
				)
			)
		)
		(property "Tolerance" "1%"
			(at 0 0 0)
			(layer "F.Fab")
			(hide yes)
			(effects
				(font
					(size 1 1)
					(thickness 0.15)
				)
			)
		)
		(property "Val" "10k"
			(at 0 0 0)
			(layer "F.Fab")
			(hide yes)
			(effects
				(font
					(size 1 1)
					(thickness 0.15)
				)
			)
		)
		(sheetname "Supply")
		(sheetfile "supply.kicad_sch")
		(attr smd)
		(fp_rect
			(start -0.925 -0.47)
			(end 0.925 0.47)
			(stroke
				(width 0.05)
				(type default)
			)
			(fill none)
			(layer "F.CrtYd")
		)
		(fp_rect
			(start -0.5 -0.25)
			(end 0.5 0.25)
			(stroke
				(width 0.15)
				(type solid)
			)
			(fill none)
			(layer "F.Fab")
		)
		(fp_text user "License: Apache-2.0"
			(at -0.95 5.169 0)
			(layer "F.Fab")
			(hide yes)
			(effects
				(font
					(size 0.7 0.7)
					(thickness 0.15)
				)
				(justify left bottom)
			)
		)
		(fp_text user "${REFERENCE}"
			(at -0.95 3.168 0)
			(layer "F.Fab")
			(hide yes)
			(effects
				(font
					(size 0.7 0.7)
					(thickness 0.15)
				)
				(justify left bottom)
			)
		)
		(fp_text user "Author: Antmicro"
			(at -0.95 4.169 0)
			(layer "F.Fab")
			(hide yes)
			(effects
				(font
					(size 0.7 0.7)
					(thickness 0.15)
				)
				(justify left bottom)
			)
		)
		(pad "1" smd roundrect
			(at -0.48 0)
			(size 0.59 0.64)
			(layers "F.Cu" "F.Paste" "F.Mask")
			(roundrect_rratio 0.25)
			(net 1 "GND")
			(pintype "passive")
		)
		(pad "2" smd roundrect
			(at 0.48 0)
			(size 0.59 0.64)
			(layers "F.Cu" "F.Paste" "F.Mask")
			(roundrect_rratio 0.25)
			(net 64 "/Supply/FB_5V")
			(pintype "passive")
		)
	)
	(footprint "antmicro-footprints:R_0402_1005Metric"
		(layer "F.Cu")
		(at 133.1 111.98 180)
		(descr "Resistor SMD 0402")
		(tags "resistor SMD 0402")
		(property "Reference" "R5"
			(at -2.566667 5.646668 0)
			(layer "F.SilkS")
			(effects
				(font
					(size 0.7 0.7)
					(thickness 0.15)
				)
				(justify right bottom)
			)
		)
		(property "Value" "R_4k7_0402"
			(at -1.011843 1.772047 0)
			(layer "F.Fab")
			(effects
				(font
					(size 0.7 0.7)
					(thickness 0.15)
				)
				(justify right bottom)
			)
		)
		(property "Footprint" "antmicro-footprints:R_0402_1005Metric"
			(at 0 0 180)
			(layer "F.Fab")
			(hide yes)
			(effects
				(font
					(size 1.27 1.27)
					(thickness 0.15)
				)
			)
		)
		(property "Datasheet" "https://www.bourns.com/docs/product-datasheets/cr.pdf"
			(at 0 0 180)
			(layer "F.Fab")
			(hide yes)
			(effects
				(font
					(size 1.27 1.27)
					(thickness 0.15)
				)
			)
		)
		(property "Author" "Antmicro"
			(at 266.2 223.96 0)
			(layer "F.Fab")
			(hide yes)
			(effects
				(font
					(size 1 1)
					(thickness 0.15)
				)
			)
		)
		(property "License" "Apache-2.0"
			(at 266.2 223.96 0)
			(layer "F.Fab")
			(hide yes)
			(effects
				(font
					(size 1 1)
					(thickness 0.15)
				)
			)
		)
		(property "MPN" "CR0402-FX-4701GLF"
			(at 266.2 223.96 0)
			(layer "F.Fab")
			(hide yes)
			(effects
				(font
					(size 1 1)
					(thickness 0.15)
				)
			)
		)
		(property "Manufacturer" "Bourns"
			(at 266.2 223.96 0)
			(layer "F.Fab")
			(hide yes)
			(effects
				(font
					(size 1 1)
					(thickness 0.15)
				)
			)
		)
		(property "Tolerance" "1%"
			(at 266.2 223.96 0)
			(layer "F.Fab")
			(hide yes)
			(effects
				(font
					(size 1 1)
					(thickness 0.15)
				)
			)
		)
		(property "Val" "4k7"
			(at 266.2 223.96 0)
			(layer "F.Fab")
			(hide yes)
			(effects
				(font
					(size 1 1)
					(thickness 0.15)
				)
			)
		)
		(sheetname "CSI Connector")
		(sheetfile "CSI.kicad_sch")
		(attr smd)
		(fp_rect
			(start -0.925 -0.47)
			(end 0.925 0.47)
			(stroke
				(width 0.05)
				(type default)
			)
			(fill none)
			(layer "F.CrtYd")
		)
		(fp_rect
			(start -0.5 -0.25)
			(end 0.5 0.25)
			(stroke
				(width 0.15)
				(type solid)
			)
			(fill none)
			(layer "F.Fab")
		)
		(fp_text user "Author: Antmicro"
			(at -0.95 4.169 0)
			(layer "F.Fab")
			(hide yes)
			(effects
				(font
					(size 0.7 0.7)
					(thickness 0.15)
				)
				(justify right bottom)
			)
		)
		(fp_text user "License: Apache-2.0"
			(at -0.95 5.169 0)
			(layer "F.Fab")
			(hide yes)
			(effects
				(font
					(size 0.7 0.7)
					(thickness 0.15)
				)
				(justify right bottom)
			)
		)
		(fp_text user "${REFERENCE}"
			(at -0.95 3.168 0)
			(layer "F.Fab")
			(hide yes)
			(effects
				(font
					(size 0.7 0.7)
					(thickness 0.15)
				)
				(justify right bottom)
			)
		)
		(pad "1" smd roundrect
			(at -0.48 0 180)
			(size 0.59 0.64)
			(layers "F.Cu" "F.Paste" "F.Mask")
			(roundrect_rratio 0.25)
			(net 88 "/CSI Connector/I2C.SDA")
			(pintype "passive")
		)
		(pad "2" smd roundrect
			(at 0.48 0 180)
			(size 0.59 0.64)
			(layers "F.Cu" "F.Paste" "F.Mask")
			(roundrect_rratio 0.25)
			(net 10 "+3V3")
			(pintype "passive")
		)
	)
	(footprint "antmicro-footprints:R_0402_1005Metric"
		(layer "F.Cu")
		(at 133.101 109.884)
		(descr "Resistor SMD 0402")
		(tags "resistor SMD 0402")
		(property "Reference" "R24"
			(at 1.049 -5.434 0)
			(layer "F.SilkS")
			(effects
				(font
					(size 0.7 0.7)
					(thickness 0.15)
				)
				(justify left bottom)
			)
		)
		(property "Value" "R_100R_0402"
			(at -1.011843 1.772047 0)
			(layer "F.Fab")
			(effects
				(font
					(size 0.7 0.7)
					(thickness 0.15)
				)
				(justify left bottom)
			)
		)
		(property "Footprint" "antmicro-footprints:R_0402_1005Metric"
			(at 0 0 0)
			(layer "F.Fab")
			(hide yes)
			(effects
				(font
					(size 1.27 1.27)
					(thickness 0.15)
				)
			)
		)
		(property "Datasheet" "https://www.bourns.com/docs/product-datasheets/cr.pdf"
			(at 0 0 0)
			(layer "F.Fab")
			(hide yes)
			(effects
				(font
					(size 1.27 1.27)
					(thickness 0.15)
				)
			)
		)
		(property "Author" "Antmicro"
			(at 0 0 0)
			(layer "F.Fab")
			(hide yes)
			(effects
				(font
					(size 1 1)
					(thickness 0.15)
				)
			)
		)
		(property "License" "Apache-2.0"
			(at 0 0 0)
			(layer "F.Fab")
			(hide yes)
			(effects
				(font
					(size 1 1)
					(thickness 0.15)
				)
			)
		)
		(property "MPN" "CR0402-FX-1000GLF"
			(at 0 0 0)
			(layer "F.Fab")
			(hide yes)
			(effects
				(font
					(size 1 1)
					(thickness 0.15)
				)
			)
		)
		(property "Manufacturer" "Bourns"
			(at 0 0 0)
			(layer "F.Fab")
			(hide yes)
			(effects
				(font
					(size 1 1)
					(thickness 0.15)
				)
			)
		)
		(property "Tolerance" "1%"
			(at 0 0 0)
			(layer "F.Fab")
			(hide yes)
			(effects
				(font
					(size 1 1)
					(thickness 0.15)
				)
			)
		)
		(property "Val" "100R"
			(at 0 0 0)
			(layer "F.Fab")
			(hide yes)
			(effects
				(font
					(size 1 1)
					(thickness 0.15)
				)
			)
		)
		(sheetname "CSI Connector")
		(sheetfile "CSI.kicad_sch")
		(attr smd)
		(fp_rect
			(start -0.925 -0.47)
			(end 0.925 0.47)
			(stroke
				(width 0.05)
				(type default)
			)
			(fill none)
			(layer "F.CrtYd")
		)
		(fp_rect
			(start -0.5 -0.25)
			(end 0.5 0.25)
			(stroke
				(width 0.15)
				(type solid)
			)
			(fill none)
			(layer "F.Fab")
		)
		(fp_text user "Author: Antmicro"
			(at -0.95 4.169 0)
			(layer "F.Fab")
			(hide yes)
			(effects
				(font
					(size 0.7 0.7)
					(thickness 0.15)
				)
				(justify left bottom)
			)
		)
		(fp_text user "${REFERENCE}"
			(at -0.95 3.168 0)
			(layer "F.Fab")
			(hide yes)
			(effects
				(font
					(size 0.7 0.7)
					(thickness 0.15)
				)
				(justify left bottom)
			)
		)
		(fp_text user "License: Apache-2.0"
			(at -0.95 5.169 0)
			(layer "F.Fab")
			(hide yes)
			(effects
				(font
					(size 0.7 0.7)
					(thickness 0.15)
				)
				(justify left bottom)
			)
		)
		(pad "1" smd roundrect
			(at -0.48 0)
			(size 0.59 0.64)
			(layers "F.Cu" "F.Paste" "F.Mask")
			(roundrect_rratio 0.25)
			(net 36 "/CSI Connector/SDA_CAM1")
			(pintype "passive")
		)
		(pad "2" smd roundrect
			(at 0.48 0)
			(size 0.59 0.64)
			(layers "F.Cu" "F.Paste" "F.Mask")
			(roundrect_rratio 0.25)
			(net 88 "/CSI Connector/I2C.SDA")
			(pintype "passive")
		)
	)
	(footprint "antmicro-footprints:R_0402_1005Metric"
		(layer "F.Cu")
		(at 143.69 79.700142 90)
		(descr "Resistor SMD 0402")
		(tags "resistor SMD 0402")
		(property "Reference" "R42"
			(at -0.989858 -0.94 90)
			(layer "F.SilkS")
			(effects
				(font
					(size 0.7 0.7)
					(thickness 0.15)
				)
				(justify left bottom)
			)
		)
		(property "Value" "R_10k_0402"
			(at -1.011843 1.772047 90)
			(layer "F.Fab")
			(effects
				(font
					(size 0.7 0.7)
					(thickness 0.15)
				)
				(justify left bottom)
			)
		)
		(property "Footprint" "antmicro-footprints:R_0402_1005Metric"
			(at 0 0 90)
			(layer "F.Fab")
			(hide yes)
			(effects
				(font
					(size 1.27 1.27)
					(thickness 0.15)
				)
			)
		)
		(property "Datasheet" "https://www.bourns.com/docs/product-datasheets/cr.pdf"
			(at 0 0 90)
			(layer "F.Fab")
			(hide yes)
			(effects
				(font
					(size 1.27 1.27)
					(thickness 0.15)
				)
			)
		)
		(property "MPN" "CR0402-FX-1002GLF"
			(at 0 0 90)
			(unlocked yes)
			(layer "F.Fab")
			(hide yes)
			(effects
				(font
					(size 1 1)
					(thickness 0.15)
				)
			)
		)
		(property "Manufacturer" "Bourns"
			(at 0 0 90)
			(unlocked yes)
			(layer "F.Fab")
			(hide yes)
			(effects
				(font
					(size 1 1)
					(thickness 0.15)
				)
			)
		)
		(property "License" "Apache-2.0"
			(at 0 0 90)
			(unlocked yes)
			(layer "F.Fab")
			(hide yes)
			(effects
				(font
					(size 1 1)
					(thickness 0.15)
				)
			)
		)
		(property "Author" "Antmicro"
			(at 0 0 90)
			(unlocked yes)
			(layer "F.Fab")
			(hide yes)
			(effects
				(font
					(size 1 1)
					(thickness 0.15)
				)
			)
		)
		(property "Val" "10k"
			(at 0 0 90)
			(unlocked yes)
			(layer "F.Fab")
			(hide yes)
			(effects
				(font
					(size 1 1)
					(thickness 0.15)
				)
			)
		)
		(property "Tolerance" "1%"
			(at 0 0 90)
			(unlocked yes)
			(layer "F.Fab")
			(hide yes)
			(effects
				(font
					(size 1 1)
					(thickness 0.15)
				)
			)
		)
		(sheetname "Supply")
		(sheetfile "supply.kicad_sch")
		(attr smd)
		(fp_rect
			(start -0.925 -0.47)
			(end 0.925 0.47)
			(stroke
				(width 0.05)
				(type default)
			)
			(fill none)
			(layer "F.CrtYd")
		)
		(fp_rect
			(start -0.5 -0.25)
			(end 0.5 0.25)
			(stroke
				(width 0.15)
				(type solid)
			)
			(fill none)
			(layer "F.Fab")
		)
		(fp_text user "License: Apache-2.0"
			(at -0.95 5.169 90)
			(layer "F.Fab")
			(hide yes)
			(effects
				(font
					(size 0.7 0.7)
					(thickness 0.15)
				)
				(justify left bottom)
			)
		)
		(fp_text user "${REFERENCE}"
			(at -0.95 3.168 90)
			(layer "F.Fab")
			(hide yes)
			(effects
				(font
					(size 0.7 0.7)
					(thickness 0.15)
				)
				(justify left bottom)
			)
		)
		(fp_text user "Author: Antmicro"
			(at -0.95 4.169 90)
			(layer "F.Fab")
			(hide yes)
			(effects
				(font
					(size 0.7 0.7)
					(thickness 0.15)
				)
				(justify left bottom)
			)
		)
		(pad "1" smd roundrect
			(at -0.48 0 90)
			(size 0.59 0.64)
			(layers "F.Cu" "F.Paste" "F.Mask")
			(roundrect_rratio 0.25)
			(net 1 "GND")
			(pintype "passive")
		)
		(pad "2" smd roundrect
			(at 0.48 0 90)
			(size 0.59 0.64)
			(layers "F.Cu" "F.Paste" "F.Mask")
			(roundrect_rratio 0.25)
			(net 97 "/Supply/EN_3V3")
			(pintype "passive")
		)
	)
	(footprint "antmicro-footprints:R_0603_1608Metric"
		(layer "F.Cu")
		(at 145.295 88.670142 -90)
		(descr "Resistor SMD 0603")
		(tags "resistor SMD 0603")
		(property "Reference" "R45"
			(at 0.279858 -0.755 90)
			(layer "F.SilkS")
			(effects
				(font
					(size 0.7 0.7)
					(thickness 0.15)
				)
				(justify right top)
			)
		)
		(property "Value" "R_0R_22.4A_0603"
			(at 0 1.6 90)
			(layer "F.Fab")
			(effects
				(font
					(size 0.7 0.7)
					(thickness 0.15)
				)
				(justify right top)
			)
		)
		(property "Footprint" "antmicro-footprints:R_0603_1608Metric"
			(at 0 0 90)
			(layer "F.Fab")
			(hide yes)
			(effects
				(font
					(size 1.27 1.27)
					(thickness 0.15)
				)
			)
		)
		(property "Datasheet" "https://fscdn.rohm.com/en/products/databook/datasheet/passive/resistor/chip_resistor/pmr-jpw-e.pdf"
			(at 0 0 90)
			(layer "F.Fab")
			(hide yes)
			(effects
				(font
					(size 1.27 1.27)
					(thickness 0.15)
				)
			)
		)
		(property "MPN" "PMR03EZPJ000"
			(at 0 0 -90)
			(unlocked yes)
			(layer "F.Fab")
			(hide yes)
			(effects
				(font
					(size 1 1)
					(thickness 0.15)
				)
			)
		)
		(property "Manufacturer" "ROHM Semiconductor"
			(at 0 0 -90)
			(unlocked yes)
			(layer "F.Fab")
			(hide yes)
			(effects
				(font
					(size 1 1)
					(thickness 0.15)
				)
			)
		)
		(property "Val" "0R"
			(at 0 0 -90)
			(unlocked yes)
			(layer "F.Fab")
			(hide yes)
			(effects
				(font
					(size 1 1)
					(thickness 0.15)
				)
			)
		)
		(property "Max. Curr." "22.4A"
			(at 0 0 -90)
			(unlocked yes)
			(layer "F.Fab")
			(hide yes)
			(effects
				(font
					(size 1 1)
					(thickness 0.15)
				)
			)
		)
		(property "Author" "Antmicro"
			(at 0 0 -90)
			(unlocked yes)
			(layer "F.Fab")
			(hide yes)
			(effects
				(font
					(size 1 1)
					(thickness 0.15)
				)
			)
		)
		(property "License" "Apache-2.0"
			(at 0 0 -90)
			(unlocked yes)
			(layer "F.Fab")
			(hide yes)
			(effects
				(font
					(size 1 1)
					(thickness 0.15)
				)
			)
		)
		(property "Tolerance" "template_tolerance"
			(at 0 0 -90)
			(unlocked yes)
			(layer "F.Fab")
			(hide yes)
			(effects
				(font
					(size 1 1)
					(thickness 0.15)
				)
			)
		)
		(sheetname "Supply")
		(sheetfile "supply.kicad_sch")
		(attr smd)
		(fp_line
			(start -0.15 0.4)
			(end 0.15 0.4)
			(stroke
				(width 0.15)
				(type solid)
			)
			(layer "F.SilkS")
		)
		(fp_line
			(start -0.15 -0.4)
			(end 0.15 -0.4)
			(stroke
				(width 0.15)
				(type solid)
			)
			(layer "F.SilkS")
		)
		(fp_rect
			(start -1.25 -0.65)
			(end 1.25 0.65)
			(stroke
				(width 0.05)
				(type solid)
			)
			(fill none)
			(layer "F.CrtYd")
		)
		(fp_rect
			(start -0.8 -0.4)
			(end 0.8 0.4)
			(stroke
				(width 0.15)
				(type solid)
			)
			(fill none)
			(layer "F.Fab")
		)
		(fp_text user "Author: Antmicro"
			(at -1.25 4.9 90)
			(layer "F.Fab")
			(hide yes)
			(effects
				(font
					(size 0.7 0.7)
					(thickness 0.15)
				)
				(justify right top)
			)
		)
		(fp_text user "${REFERENCE}"
			(at -1.25 3.898 90)
			(layer "F.Fab")
			(hide yes)
			(effects
				(font
					(size 0.7 0.7)
					(thickness 0.15)
				)
				(justify right top)
			)
		)
		(fp_text user "License: Apache-2.0"
			(at -1.25 5.9 90)
			(layer "F.Fab")
			(hide yes)
			(effects
				(font
					(size 0.7 0.7)
					(thickness 0.15)
				)
				(justify right top)
			)
		)
		(pad "1" smd roundrect
			(at -0.7 0 270)
			(size 0.8 1)
			(layers "F.Cu" "F.Paste" "F.Mask")
			(roundrect_rratio 0.2)
			(net 94 "/Supply/OUT_3V3")
			(pintype "passive")
		)
		(pad "2" smd roundrect
			(at 0.7 0 270)
			(size 0.8 1)
			(layers "F.Cu" "F.Paste" "F.Mask")
			(roundrect_rratio 0.2)
			(net 10 "+3V3")
			(pintype "passive")
		)
	)
	(footprint "antmicro-footprints:C_0603_1608Metric"
		(layer "F.Cu")
		(at 136.755 83.1 90)
		(descr "Capacitor SMD 0603")
		(tags "capacitor 0603")
		(property "Reference" "C1"
			(at 0.28 0.485 180)
			(layer "F.SilkS")
			(effects
				(font
					(size 0.7 0.7)
					(thickness 0.15)
				)
				(justify left bottom)
			)
		)
		(property "Value" "C_10u_25V_0603"
			(at -1.42757 1.770288 90)
			(layer "F.Fab")
			(effects
				(font
					(size 0.7 0.7)
					(thickness 0.15)
				)
				(justify left bottom)
			)
		)
		(property "Footprint" "antmicro-footprints:C_0603_1608Metric"
			(at 0 0 90)
			(layer "F.Fab")
			(hide yes)
			(effects
				(font
					(size 1.27 1.27)
					(thickness 0.15)
				)
			)
		)
		(property "Datasheet" "https://product.tdk.com/en/search/capacitor/ceramic/mlcc/info?part_no=C1608X5R1E106M080AC"
			(at 0 0 90)
			(layer "F.Fab")
			(hide yes)
			(effects
				(font
					(size 1.27 1.27)
					(thickness 0.15)
				)
			)
		)
		(property "Author" "Antmicro"
			(at 221.475 -55.575 0)
			(layer "F.Fab")
			(hide yes)
			(effects
				(font
					(size 1 1)
					(thickness 0.15)
				)
			)
		)
		(property "Dielectric" ""
			(at 221.475 -55.575 0)
			(layer "F.Fab")
			(hide yes)
			(effects
				(font
					(size 1 1)
					(thickness 0.15)
				)
			)
		)
		(property "License" "Apache-2.0"
			(at 221.475 -55.575 0)
			(layer "F.Fab")
			(hide yes)
			(effects
				(font
					(size 1 1)
					(thickness 0.15)
				)
			)
		)
		(property "MPN" "C1608X5R1E106M080AC"
			(at 221.475 -55.575 0)
			(layer "F.Fab")
			(hide yes)
			(effects
				(font
					(size 1 1)
					(thickness 0.15)
				)
			)
		)
		(property "Manufacturer" "TDK"
			(at 221.475 -55.575 0)
			(layer "F.Fab")
			(hide yes)
			(effects
				(font
					(size 1 1)
					(thickness 0.15)
				)
			)
		)
		(property "Val" "10u"
			(at 221.475 -55.575 0)
			(layer "F.Fab")
			(hide yes)
			(effects
				(font
					(size 1 1)
					(thickness 0.15)
				)
			)
		)
		(property "Voltage" "25V"
			(at 221.475 -55.575 0)
			(layer "F.Fab")
			(hide yes)
			(effects
				(font
					(size 1 1)
					(thickness 0.15)
				)
			)
		)
		(sheetname "Supply")
		(sheetfile "supply.kicad_sch")
		(attr smd)
		(fp_line
			(start -0.15 -0.4)
			(end 0.15 -0.4)
			(stroke
				(width 0.15)
				(type solid)
			)
			(layer "F.SilkS")
		)
		(fp_line
			(start -0.15 0.4)
			(end 0.15 0.4)
			(stroke
				(width 0.15)
				(type solid)
			)
			(layer "F.SilkS")
		)
		(fp_rect
			(start -1.25 -0.65)
			(end 1.25 0.65)
			(stroke
				(width 0.05)
				(type solid)
			)
			(fill none)
			(layer "F.CrtYd")
		)
		(fp_rect
			(start -0.8 -0.4)
			(end 0.8 0.4)
			(stroke
				(width 0.15)
				(type solid)
			)
			(fill none)
			(layer "F.Fab")
		)
		(fp_text user "Author: Antmicro"
			(at -1.682 4.894 90)
			(layer "F.Fab")
			(hide yes)
			(effects
				(font
					(size 0.7 0.7)
					(thickness 0.15)
				)
				(justify left bottom)
			)
		)
		(fp_text user "${REFERENCE}"
			(at -1.682 3.895 90)
			(layer "F.Fab")
			(hide yes)
			(effects
				(font
					(size 0.7 0.7)
					(thickness 0.15)
				)
				(justify left bottom)
			)
		)
		(fp_text user "License: Apache-2.0"
			(at -1.682 5.895 90)
			(layer "F.Fab")
			(hide yes)
			(effects
				(font
					(size 0.7 0.7)
					(thickness 0.15)
				)
				(justify left bottom)
			)
		)
		(pad "1" smd roundrect
			(at -0.7 0 90)
			(size 0.8 1)
			(layers "F.Cu" "F.Paste" "F.Mask")
			(roundrect_rratio 0.2)
			(net 1 "GND")
			(pintype "passive")
		)
		(pad "2" smd roundrect
			(at 0.7 0 90)
			(size 0.8 1)
			(layers "F.Cu" "F.Paste" "F.Mask")
			(roundrect_rratio 0.2)
			(net 2 "+12V")
			(pintype "passive")
		)
	)
	(footprint "antmicro-footprints:L_Bourns-SRP3212A"
		(layer "F.Cu")
		(at 133.779 86.95)
		(property "Reference" "L1"
			(at -3.449 0.4 0)
			(layer "F.SilkS")
			(effects
				(font
					(size 0.7 0.7)
					(thickness 0.15)
				)
				(justify left bottom)
			)
		)
		(property "Value" "L_3u3_3.1A_Bourns-SRP3212A"
			(at 0.05 2.8 0)
			(layer "F.Fab")
			(effects
				(font
					(size 0.7 0.7)
					(thickness 0.15)
				)
				(justify left bottom)
			)
		)
		(property "Footprint" "antmicro-footprints:L_Bourns-SRP3212A"
			(at 0 0 0)
			(layer "F.Fab")
			(hide yes)
			(effects
				(font
					(size 1.27 1.27)
					(thickness 0.15)
				)
			)
		)
		(property "Datasheet" "https://www.mouser.com/datasheet/2/54/SRP3212A-3011944.pdf"
			(at 0 0 0)
			(layer "F.Fab")
			(hide yes)
			(effects
				(font
					(size 1.27 1.27)
					(thickness 0.15)
				)
			)
		)
		(property "Author" "Antmicro"
			(at 0 0 0)
			(layer "F.Fab")
			(hide yes)
			(effects
				(font
					(size 1 1)
					(thickness 0.15)
				)
			)
		)
		(property "IMax" "3.1 A"
			(at 0 0 0)
			(layer "F.Fab")
			(hide yes)
			(effects
				(font
					(size 1 1)
					(thickness 0.15)
				)
			)
		)
		(property "ISat" "3.4 A"
			(at 0 0 0)
			(layer "F.Fab")
			(hide yes)
			(effects
				(font
					(size 1 1)
					(thickness 0.15)
				)
			)
		)
		(property "License" "Apache-2.0"
			(at 0 0 0)
			(layer "F.Fab")
			(hide yes)
			(effects
				(font
					(size 1 1)
					(thickness 0.15)
				)
			)
		)
		(property "MPN" "SRP3212-3R3M"
			(at 0 0 0)
			(layer "F.Fab")
			(hide yes)
			(effects
				(font
					(size 1 1)
					(thickness 0.15)
				)
			)
		)
		(property "Manufacturer" "Bourns"
			(at 0 0 0)
			(layer "F.Fab")
			(hide yes)
			(effects
				(font
					(size 1 1)
					(thickness 0.15)
				)
			)
		)
		(property "Size" "3.2x2.5"
			(at 0 0 0)
			(layer "F.Fab")
			(hide yes)
			(effects
				(font
					(size 1 1)
					(thickness 0.15)
				)
			)
		)
		(property "Val" "3u3/3.1A"
			(at 0 0 0)
			(layer "F.Fab")
			(hide yes)
			(effects
				(font
					(size 1 1)
					(thickness 0.15)
				)
			)
		)
		(sheetname "Supply")
		(sheetfile "supply.kicad_sch")
		(attr smd)
		(fp_line
			(start -0.4 -1.25)
			(end 0.399 -1.25)
			(stroke
				(width 0.15)
				(type solid)
			)
			(layer "F.SilkS")
		)
		(fp_line
			(start -0.4 1.249)
			(end 0.399 1.249)
			(stroke
				(width 0.15)
				(type solid)
			)
			(layer "F.SilkS")
		)
		(fp_rect
			(start -2.1 -1.65)
			(end 2.1 1.65)
			(stroke
				(width 0.05)
				(type solid)
			)
			(fill none)
			(layer "F.CrtYd")
		)
		(fp_rect
			(start -1.609 -1.26)
			(end 1.609 1.26)
			(stroke
				(width 0.15)
				(type solid)
			)
			(fill none)
			(layer "F.Fab")
		)
		(fp_text user "${REFERENCE}"
			(at -2.1 4.8 0)
			(layer "F.Fab")
			(hide yes)
			(effects
				(font
					(size 0.7 0.7)
					(thickness 0.15)
				)
				(justify left bottom)
			)
		)
		(fp_text user "Author: Antmicro"
			(at -2.1 6 0)
			(layer "F.Fab")
			(hide yes)
			(effects
				(font
					(size 0.7 0.7)
					(thickness 0.15)
				)
				(justify left bottom)
			)
		)
		(fp_text user "License: Apache-2.0"
			(at -2.1 7.2 0)
			(layer "F.Fab")
			(hide yes)
			(effects
				(font
					(size 0.7 0.7)
					(thickness 0.15)
				)
				(justify left bottom)
			)
		)
		(pad "1" smd roundrect
			(at -1.175 0)
			(size 1.35 2.8)
			(layers "F.Cu" "F.Paste" "F.Mask")
			(roundrect_rratio 0.1)
			(net 4 "/Supply/SW_5V")
			(pintype "passive")
		)
		(pad "2" smd roundrect
			(at 1.175 0)
			(size 1.35 2.8)
			(layers "F.Cu" "F.Paste" "F.Mask")
			(roundrect_rratio 0.1)
			(net 7 "/Supply/OUT_5V")
			(pintype "passive")
		)
	)
	(footprint "antmicro-footprints:SOT-523"
		(layer "F.Cu")
		(at 147.425 113.225 90)
		(property "Reference" "Q3"
			(at -0.225 -1.175 90)
			(layer "F.SilkS")
			(effects
				(font
					(size 0.7 0.7)
					(thickness 0.15)
				)
				(justify left bottom)
			)
		)
		(property "Value" "DMG1012T-7"
			(at 0.1 1.824 90)
			(layer "F.Fab")
			(effects
				(font
					(size 0.7 0.7)
					(thickness 0.15)
				)
				(justify left bottom)
			)
		)
		(property "Footprint" "antmicro-footprints:SOT-523"
			(at 0 0 90)
			(layer "F.Fab")
			(hide yes)
			(effects
				(font
					(size 1.27 1.27)
					(thickness 0.15)
				)
			)
		)
		(property "Datasheet" "https://www.diodes.com/assets/Datasheets/ds31783.pdf"
			(at 0 0 90)
			(layer "F.Fab")
			(hide yes)
			(effects
				(font
					(size 1.27 1.27)
					(thickness 0.15)
				)
			)
		)
		(property "Author" "Antmicro"
			(at 260.65 -34.2 0)
			(layer "F.Fab")
			(hide yes)
			(effects
				(font
					(size 1 1)
					(thickness 0.15)
				)
			)
		)
		(property "License" "Apache-2.0"
			(at 260.65 -34.2 0)
			(layer "F.Fab")
			(hide yes)
			(effects
				(font
					(size 1 1)
					(thickness 0.15)
				)
			)
		)
		(property "MPN" "DMG1012T-7"
			(at 260.65 -34.2 0)
			(layer "F.Fab")
			(hide yes)
			(effects
				(font
					(size 1 1)
					(thickness 0.15)
				)
			)
		)
		(property "Manufacturer" "Diodes Incorporated"
			(at 260.65 -34.2 0)
			(layer "F.Fab")
			(hide yes)
			(effects
				(font
					(size 1 1)
					(thickness 0.15)
				)
			)
		)
		(property "Public" ""
			(at 260.65 -34.2 0)
			(layer "F.Fab")
			(hide yes)
			(effects
				(font
					(size 1 1)
					(thickness 0.15)
				)
			)
		)
		(sheetname "Supply")
		(sheetfile "supply.kicad_sch")
		(attr smd exclude_from_bom)
		(fp_line
			(start -0.277 -0.551)
			(end -0.277 -0.75)
			(stroke
				(width 0.15)
				(type solid)
			)
			(layer "F.SilkS")
		)
		(fp_line
			(start -0.725 -0.551)
			(end -0.277 -0.551)
			(stroke
				(width 0.15)
				(type solid)
			)
			(layer "F.SilkS")
		)
		(fp_line
			(start -0.927 -0.351)
			(end -0.725 -0.551)
			(stroke
				(width 0.15)
				(type solid)
			)
			(layer "F.SilkS")
		)
		(fp_line
			(start -0.927 -0.051)
			(end -0.927 -0.351)
			(stroke
				(width 0.15)
				(type solid)
			)
			(layer "F.SilkS")
		)
		(fp_circle
			(center -0.9652 0.9652)
			(end -0.9152 0.9652)
			(stroke
				(width 0.15)
				(type solid)
			)
			(fill solid)
			(layer "F.SilkS")
		)
		(fp_line
			(start 1.1 -1.16)
			(end 1.1 1.15)
			(stroke
				(width 0.05)
				(type solid)
			)
			(layer "F.CrtYd")
		)
		(fp_line
			(start -1.12 -1.16)
			(end 1.1 -1.16)
			(stroke
				(width 0.05)
				(type solid)
			)
			(layer "F.CrtYd")
		)
		(fp_line
			(start -1.12 -1.16)
			(end -1.12 1.15)
			(stroke
				(width 0.05)
				(type solid)
			)
			(layer "F.CrtYd")
		)
		(fp_line
			(start -1.12 1.15)
			(end 1.1 1.15)
			(stroke
				(width 0.05)
				(type solid)
			)
			(layer "F.CrtYd")
		)
		(fp_line
			(start 0.8 -0.425)
			(end -0.652 -0.425)
			(stroke
				(width 0.15)
				(type solid)
			)
			(layer "F.Fab")
		)
		(fp_line
			(start 0.8 -0.425)
			(end 0.8 0.424)
			(stroke
				(width 0.15)
				(type solid)
			)
			(layer "F.Fab")
		)
		(fp_line
			(start -0.652 -0.425)
			(end -0.802 -0.276)
			(stroke
				(width 0.15)
				(type solid)
			)
			(layer "F.Fab")
		)
		(fp_line
			(start -0.802 -0.276)
			(end -0.802 0.424)
			(stroke
				(width 0.15)
				(type solid)
			)
			(layer "F.Fab")
		)
		(fp_line
			(start 0.8 0.424)
			(end -0.802 0.424)
			(stroke
				(width 0.15)
				(type solid)
			)
			(layer "F.Fab")
		)
		(fp_circle
			(center -0.9652 0.9652)
			(end -0.9144 0.9652)
			(stroke
				(width 0.15)
				(type solid)
			)
			(fill none)
			(layer "F.Fab")
		)
		(fp_text user "Author: Antmicro"
			(at -1.12 6.224 90)
			(layer "F.Fab")
			(hide yes)
			(effects
				(font
					(size 0.7 0.7)
					(thickness 0.15)
				)
				(justify left bottom)
			)
		)
		(fp_text user "${REFERENCE}"
			(at -1.12 3.824 90)
			(layer "F.Fab")
			(hide yes)
			(effects
				(font
					(size 0.7 0.7)
					(thickness 0.15)
				)
				(justify left bottom)
			)
		)
		(fp_text user "License: Apache-2.0"
			(at -1.12 5.024 90)
			(layer "F.Fab")
			(hide yes)
			(effects
				(font
					(size 0.7 0.7)
					(thickness 0.15)
				)
				(justify left bottom)
			)
		)
		(pad "1" smd rect
			(at -0.5 0.65 90)
			(size 0.4 0.51)
			(layers "F.Cu" "F.Paste" "F.Mask")
			(net 11 "+1V8")
			(pinfunction "G")
			(pintype "passive")
		)
		(pad "2" smd rect
			(at 0.498 0.65 90)
			(size 0.4 0.51)
			(layers "F.Cu" "F.Paste" "F.Mask")
			(net 1 "GND")
			(pinfunction "S")
			(pintype "passive")
		)
		(pad "3" smd rect
			(at 0 -0.652 90)
			(size 0.4 0.51)
			(layers "F.Cu" "F.Paste" "F.Mask")
			(net 73 "Net-(D8-C)")
			(pinfunction "D")
			(pintype "passive")
		)
	)
	(footprint "antmicro-footprints:C_0402_1005Metric"
		(layer "F.Cu")
		(at 148.85 97.61 -45)
		(descr "Capacitor SMD 0402")
		(tags "capacitor SMD 0402")
		(property "Reference" "C20"
			(at 0.997021 -2.552655 -45)
			(unlocked yes)
			(layer "F.SilkS")
			(effects
				(font
					(size 0.7 0.7)
					(thickness 0.15)
				)
				(justify right bottom)
			)
		)
		(property "Value" "C_100n_0402"
			(at -1.022927 2.155213 135)
			(layer "F.Fab")
			(effects
				(font
					(size 0.7 0.7)
					(thickness 0.15)
				)
				(justify right bottom)
			)
		)
		(property "Footprint" "antmicro-footprints:C_0402_1005Metric"
			(at 0 0 -45)
			(layer "F.Fab")
			(hide yes)
			(effects
				(font
					(size 1.27 1.27)
					(thickness 0.15)
				)
			)
		)
		(property "Datasheet" "https://www.murata.com/products/productdetail?partno=GRM155R61H104KE14%23"
			(at 0 0 -45)
			(layer "F.Fab")
			(hide yes)
			(effects
				(font
					(size 1.27 1.27)
					(thickness 0.15)
				)
			)
		)
		(property "Author" "Antmicro"
			(at -25.423538 133.842152 0)
			(layer "F.Fab")
			(hide yes)
			(effects
				(font
					(size 1 1)
					(thickness 0.15)
				)
			)
		)
		(property "Dielectric" "X5R"
			(at -25.423538 133.842152 0)
			(layer "F.Fab")
			(hide yes)
			(effects
				(font
					(size 1 1)
					(thickness 0.15)
				)
			)
		)
		(property "License" "Apache-2.0"
			(at -25.423538 133.842152 0)
			(layer "F.Fab")
			(hide yes)
			(effects
				(font
					(size 1 1)
					(thickness 0.15)
				)
			)
		)
		(property "MPN" "GRM155R61H104KE14D"
			(at -25.423538 133.842152 0)
			(layer "F.Fab")
			(hide yes)
			(effects
				(font
					(size 1 1)
					(thickness 0.15)
				)
			)
		)
		(property "Manufacturer" "Murata"
			(at -25.423538 133.842152 0)
			(layer "F.Fab")
			(hide yes)
			(effects
				(font
					(size 1 1)
					(thickness 0.15)
				)
			)
		)
		(property "Val" "100n"
			(at -25.423538 133.842152 0)
			(layer "F.Fab")
			(hide yes)
			(effects
				(font
					(size 1 1)
					(thickness 0.15)
				)
			)
		)
		(property "Voltage" "50V"
			(at -25.423538 133.842152 0)
			(layer "F.Fab")
			(hide yes)
			(effects
				(font
					(size 1 1)
					(thickness 0.15)
				)
			)
		)
		(sheetname "Serializer")
		(sheetfile "serializer.kicad_sch")
		(attr smd)
		(fp_poly
			(pts
				(xy -0.925 -0.47) (xy 0.925 -0.47) (xy 0.925 0.47) (xy -0.925 0.47)
			)
			(stroke
				(width 0.05)
				(type default)
			)
			(fill none)
			(layer "F.CrtYd")
		)
		(fp_line
			(start -0.494 0.248)
			(end -0.494 -0.25)
			(stroke
				(width 0.15)
				(type solid)
			)
			(layer "F.Fab")
		)
		(fp_line
			(start -0.494 -0.25)
			(end 0.504 -0.25)
			(stroke
				(width 0.15)
				(type solid)
			)
			(layer "F.Fab")
		)
		(fp_line
			(start 0.504 0.248)
			(end -0.494 0.248)
			(stroke
				(width 0.15)
				(type solid)
			)
			(layer "F.Fab")
		)
		(fp_line
			(start 0.504 -0.25)
			(end 0.504 0.248)
			(stroke
				(width 0.15)
				(type solid)
			)
			(layer "F.Fab")
		)
		(fp_text user "Author: Antmicro"
			(at -0.939 3.399 135)
			(layer "F.Fab")
			(hide yes)
			(effects
				(font
					(size 0.7 0.7)
					(thickness 0.15)
				)
				(justify right bottom)
			)
		)
		(fp_text user "License: Apache-2.0"
			(at -0.939 5.799 135)
			(layer "F.Fab")
			(hide yes)
			(effects
				(font
					(size 0.7 0.7)
					(thickness 0.15)
				)
				(justify right bottom)
			)
		)
		(fp_text user "${REFERENCE}"
			(at -0.939 4.599 135)
			(layer "F.Fab")
			(hide yes)
			(effects
				(font
					(size 0.7 0.7)
					(thickness 0.15)
				)
				(justify right bottom)
			)
		)
		(pad "1" smd roundrect
			(at -0.48 0 315)
			(size 0.59 0.64)
			(layers "F.Cu" "F.Paste" "F.Mask")
			(roundrect_rratio 0.25)
			(net 1 "GND")
			(pintype "passive")
		)
		(pad "2" smd roundrect
			(at 0.48 0 315)
			(size 0.59 0.64)
			(layers "F.Cu" "F.Paste" "F.Mask")
			(roundrect_rratio 0.25)
			(net 12 "+1V2")
			(pintype "passive")
		)
	)
	(footprint "antmicro-footprints:C_0402_1005Metric"
		(layer "F.Cu")
		(at 139.56 84.850142 -90)
		(descr "Capacitor SMD 0402")
		(tags "capacitor SMD 0402")
		(property "Reference" "C21"
			(at 0.609858 0.11 90)
			(layer "F.SilkS")
			(effects
				(font
					(size 0.7 0.7)
					(thickness 0.15)
				)
				(justify right top)
			)
		)
		(property "Value" "C_220n_0402"
			(at -1.022927 2.155213 90)
			(layer "F.Fab")
			(effects
				(font
					(size 0.7 0.7)
					(thickness 0.15)
				)
				(justify right top)
			)
		)
		(property "Footprint" "antmicro-footprints:C_0402_1005Metric"
			(at 0 0 90)
			(layer "F.Fab")
			(hide yes)
			(effects
				(font
					(size 1.27 1.27)
					(thickness 0.15)
				)
			)
		)
		(property "Datasheet" "https://www.yageo.com/en/Chart/Download/pdf/CC0402KRX5R6BB224"
			(at 0 0 90)
			(layer "F.Fab")
			(hide yes)
			(effects
				(font
					(size 1.27 1.27)
					(thickness 0.15)
				)
			)
		)
		(property "MPN" "CC0402KRX5R6BB224"
			(at 0 0 -90)
			(unlocked yes)
			(layer "F.Fab")
			(hide yes)
			(effects
				(font
					(size 1 1)
					(thickness 0.15)
				)
			)
		)
		(property "Manufacturer" "YAGEO"
			(at 0 0 -90)
			(unlocked yes)
			(layer "F.Fab")
			(hide yes)
			(effects
				(font
					(size 1 1)
					(thickness 0.15)
				)
			)
		)
		(property "License" "Apache-2.0"
			(at 0 0 -90)
			(unlocked yes)
			(layer "F.Fab")
			(hide yes)
			(effects
				(font
					(size 1 1)
					(thickness 0.15)
				)
			)
		)
		(property "Author" "Antmicro"
			(at 0 0 -90)
			(unlocked yes)
			(layer "F.Fab")
			(hide yes)
			(effects
				(font
					(size 1 1)
					(thickness 0.15)
				)
			)
		)
		(property "Val" "220n"
			(at 0 0 -90)
			(unlocked yes)
			(layer "F.Fab")
			(hide yes)
			(effects
				(font
					(size 1 1)
					(thickness 0.15)
				)
			)
		)
		(property "Voltage" ""
			(at 0 0 -90)
			(unlocked yes)
			(layer "F.Fab")
			(hide yes)
			(effects
				(font
					(size 1 1)
					(thickness 0.15)
				)
			)
		)
		(property "Dielectric" ""
			(at 0 0 -90)
			(unlocked yes)
			(layer "F.Fab")
			(hide yes)
			(effects
				(font
					(size 1 1)
					(thickness 0.15)
				)
			)
		)
		(sheetname "Supply")
		(sheetfile "supply.kicad_sch")
		(attr smd)
		(fp_rect
			(start -0.925 -0.47)
			(end 0.925 0.47)
			(stroke
				(width 0.05)
				(type default)
			)
			(fill none)
			(layer "F.CrtYd")
		)
		(fp_line
			(start -0.494 0.248)
			(end -0.494 -0.25)
			(stroke
				(width 0.15)
				(type solid)
			)
			(layer "F.Fab")
		)
		(fp_line
			(start 0.504 0.248)
			(end -0.494 0.248)
			(stroke
				(width 0.15)
				(type solid)
			)
			(layer "F.Fab")
		)
		(fp_line
			(start -0.494 -0.25)
			(end 0.504 -0.25)
			(stroke
				(width 0.15)
				(type solid)
			)
			(layer "F.Fab")
		)
		(fp_line
			(start 0.504 -0.25)
			(end 0.504 0.248)
			(stroke
				(width 0.15)
				(type solid)
			)
			(layer "F.Fab")
		)
		(fp_text user "License: Apache-2.0"
			(at -0.939 5.799 90)
			(layer "F.Fab")
			(hide yes)
			(effects
				(font
					(size 0.7 0.7)
					(thickness 0.15)
				)
				(justify right top)
			)
		)
		(fp_text user "${REFERENCE}"
			(at -0.939 4.599 90)
			(layer "F.Fab")
			(hide yes)
			(effects
				(font
					(size 0.7 0.7)
					(thickness 0.15)
				)
				(justify right top)
			)
		)
		(fp_text user "Author: Antmicro"
			(at -0.939 3.399 90)
			(layer "F.Fab")
			(hide yes)
			(effects
				(font
					(size 0.7 0.7)
					(thickness 0.15)
				)
				(justify right top)
			)
		)
		(pad "1" smd roundrect
			(at -0.48 0 270)
			(size 0.59 0.64)
			(layers "F.Cu" "F.Paste" "F.Mask")
			(roundrect_rratio 0.25)
			(net 93 "Net-(U3-BST)")
			(pintype "passive")
		)
		(pad "2" smd roundrect
			(at 0.48 0 270)
			(size 0.59 0.64)
			(layers "F.Cu" "F.Paste" "F.Mask")
			(roundrect_rratio 0.25)
			(net 72 "/Supply/SW_3V3")
			(pintype "passive")
		)
	)
	(footprint "antmicro-footprints:C_0402_1005Metric"
		(layer "F.Cu")
		(at 147.22 96.46 -45)
		(descr "Capacitor SMD 0402")
		(tags "capacitor SMD 0402")
		(property "Reference" "C29"
			(at 0.947523 -2.446589 -45)
			(unlocked yes)
			(layer "F.SilkS")
			(effects
				(font
					(size 0.7 0.7)
					(thickness 0.15)
				)
				(justify right bottom)
			)
		)
		(property "Value" "C_10n_0402"
			(at -1.022927 2.155213 135)
			(layer "F.Fab")
			(effects
				(font
					(size 0.7 0.7)
					(thickness 0.15)
				)
				(justify right bottom)
			)
		)
		(property "Footprint" "antmicro-footprints:C_0402_1005Metric"
			(at 0 0 -45)
			(layer "F.Fab")
			(hide yes)
			(effects
				(font
					(size 1.27 1.27)
					(thickness 0.15)
				)
			)
		)
		(property "Datasheet" "https://www.murata.com/products/productdetail?partno=GRM155R71H103KA88%23"
			(at 0 0 -45)
			(layer "F.Fab")
			(hide yes)
			(effects
				(font
					(size 1.27 1.27)
					(thickness 0.15)
				)
			)
		)
		(property "Author" "Antmicro"
			(at -25.087781 132.35274 0)
			(layer "F.Fab")
			(hide yes)
			(effects
				(font
					(size 1 1)
					(thickness 0.15)
				)
			)
		)
		(property "Dielectric" "X7R"
			(at -25.087781 132.35274 0)
			(layer "F.Fab")
			(hide yes)
			(effects
				(font
					(size 1 1)
					(thickness 0.15)
				)
			)
		)
		(property "License" "Apache-2.0"
			(at -25.087781 132.35274 0)
			(layer "F.Fab")
			(hide yes)
			(effects
				(font
					(size 1 1)
					(thickness 0.15)
				)
			)
		)
		(property "MPN" "GRM155R71H103KA88D"
			(at -25.087781 132.35274 0)
			(layer "F.Fab")
			(hide yes)
			(effects
				(font
					(size 1 1)
					(thickness 0.15)
				)
			)
		)
		(property "Manufacturer" "Murata"
			(at -25.087781 132.35274 0)
			(layer "F.Fab")
			(hide yes)
			(effects
				(font
					(size 1 1)
					(thickness 0.15)
				)
			)
		)
		(property "Val" "10n"
			(at -25.087781 132.35274 0)
			(layer "F.Fab")
			(hide yes)
			(effects
				(font
					(size 1 1)
					(thickness 0.15)
				)
			)
		)
		(property "Voltage" "50V"
			(at -25.087781 132.35274 0)
			(layer "F.Fab")
			(hide yes)
			(effects
				(font
					(size 1 1)
					(thickness 0.15)
				)
			)
		)
		(sheetname "Serializer")
		(sheetfile "serializer.kicad_sch")
		(attr smd)
		(fp_poly
			(pts
				(xy -0.925 -0.47) (xy 0.925 -0.47) (xy 0.925 0.47) (xy -0.925 0.47)
			)
			(stroke
				(width 0.05)
				(type default)
			)
			(fill none)
			(layer "F.CrtYd")
		)
		(fp_line
			(start -0.494 0.248)
			(end -0.494 -0.25)
			(stroke
				(width 0.15)
				(type solid)
			)
			(layer "F.Fab")
		)
		(fp_line
			(start -0.494 -0.25)
			(end 0.504 -0.25)
			(stroke
				(width 0.15)
				(type solid)
			)
			(layer "F.Fab")
		)
		(fp_line
			(start 0.504 0.248)
			(end -0.494 0.248)
			(stroke
				(width 0.15)
				(type solid)
			)
			(layer "F.Fab")
		)
		(fp_line
			(start 0.504 -0.25)
			(end 0.504 0.248)
			(stroke
				(width 0.15)
				(type solid)
			)
			(layer "F.Fab")
		)
		(fp_text user "License: Apache-2.0"
			(at -0.939 5.799 135)
			(layer "F.Fab")
			(hide yes)
			(effects
				(font
					(size 0.7 0.7)
					(thickness 0.15)
				)
				(justify right bottom)
			)
		)
		(fp_text user "${REFERENCE}"
			(at -0.939 4.599 135)
			(layer "F.Fab")
			(hide yes)
			(effects
				(font
					(size 0.7 0.7)
					(thickness 0.15)
				)
				(justify right bottom)
			)
		)
		(fp_text user "Author: Antmicro"
			(at -0.939 3.399 135)
			(layer "F.Fab")
			(hide yes)
			(effects
				(font
					(size 0.7 0.7)
					(thickness 0.15)
				)
				(justify right bottom)
			)
		)
		(pad "1" smd roundrect
			(at -0.48 0 315)
			(size 0.59 0.64)
			(layers "F.Cu" "F.Paste" "F.Mask")
			(roundrect_rratio 0.25)
			(net 1 "GND")
			(pintype "passive")
		)
		(pad "2" smd roundrect
			(at 0.48 0 315)
			(size 0.59 0.64)
			(layers "F.Cu" "F.Paste" "F.Mask")
			(roundrect_rratio 0.25)
			(net 10 "+3V3")
			(pintype "passive")
		)
	)
	(footprint "antmicro-footprints:R_0402_1005Metric"
		(layer "F.Cu")
		(at 163.95 97.125 180)
		(descr "Resistor SMD 0402")
		(tags "resistor SMD 0402")
		(property "Reference" "R26"
			(at -1.15 0.525 0)
			(layer "F.SilkS")
			(effects
				(font
					(size 0.7 0.7)
					(thickness 0.15)
				)
				(justify right bottom)
			)
		)
		(property "Value" "R_10k_0402"
			(at -1.011843 1.772047 0)
			(layer "F.Fab")
			(effects
				(font
					(size 0.7 0.7)
					(thickness 0.15)
				)
				(justify right bottom)
			)
		)
		(property "Footprint" "antmicro-footprints:R_0402_1005Metric"
			(at 0 0 180)
			(layer "F.Fab")
			(hide yes)
			(effects
				(font
					(size 1.27 1.27)
					(thickness 0.15)
				)
			)
		)
		(property "Datasheet" "https://www.bourns.com/docs/product-datasheets/cr.pdf"
			(at 0 0 180)
			(layer "F.Fab")
			(hide yes)
			(effects
				(font
					(size 1.27 1.27)
					(thickness 0.15)
				)
			)
		)
		(property "Author" "Antmicro"
			(at 327.9 194.25 0)
			(layer "F.Fab")
			(hide yes)
			(effects
				(font
					(size 1 1)
					(thickness 0.15)
				)
			)
		)
		(property "License" "Apache-2.0"
			(at 327.9 194.25 0)
			(layer "F.Fab")
			(hide yes)
			(effects
				(font
					(size 1 1)
					(thickness 0.15)
				)
			)
		)
		(property "MPN" "CR0402-FX-1002GLF"
			(at 327.9 194.25 0)
			(layer "F.Fab")
			(hide yes)
			(effects
				(font
					(size 1 1)
					(thickness 0.15)
				)
			)
		)
		(property "Manufacturer" "Bourns"
			(at 327.9 194.25 0)
			(layer "F.Fab")
			(hide yes)
			(effects
				(font
					(size 1 1)
					(thickness 0.15)
				)
			)
		)
		(property "Tolerance" "1%"
			(at 327.9 194.25 0)
			(layer "F.Fab")
			(hide yes)
			(effects
				(font
					(size 1 1)
					(thickness 0.15)
				)
			)
		)
		(property "Val" "10k"
			(at 327.9 194.25 0)
			(layer "F.Fab")
			(hide yes)
			(effects
				(font
					(size 1 1)
					(thickness 0.15)
				)
			)
		)
		(sheetname "Supply")
		(sheetfile "supply.kicad_sch")
		(attr smd)
		(fp_rect
			(start -0.925 -0.47)
			(end 0.925 0.47)
			(stroke
				(width 0.05)
				(type default)
			)
			(fill none)
			(layer "F.CrtYd")
		)
		(fp_rect
			(start -0.5 -0.25)
			(end 0.5 0.25)
			(stroke
				(width 0.15)
				(type solid)
			)
			(fill none)
			(layer "F.Fab")
		)
		(fp_text user "License: Apache-2.0"
			(at -0.95 5.169 0)
			(layer "F.Fab")
			(hide yes)
			(effects
				(font
					(size 0.7 0.7)
					(thickness 0.15)
				)
				(justify right bottom)
			)
		)
		(fp_text user "${REFERENCE}"
			(at -0.95 3.168 0)
			(layer "F.Fab")
			(hide yes)
			(effects
				(font
					(size 0.7 0.7)
					(thickness 0.15)
				)
				(justify right bottom)
			)
		)
		(fp_text user "Author: Antmicro"
			(at -0.95 4.169 0)
			(layer "F.Fab")
			(hide yes)
			(effects
				(font
					(size 0.7 0.7)
					(thickness 0.15)
				)
				(justify right bottom)
			)
		)
		(pad "1" smd roundrect
			(at -0.48 0 180)
			(size 0.59 0.64)
			(layers "F.Cu" "F.Paste" "F.Mask")
			(roundrect_rratio 0.25)
			(net 1 "GND")
			(pintype "passive")
		)
		(pad "2" smd roundrect
			(at 0.48 0 180)
			(size 0.59 0.64)
			(layers "F.Cu" "F.Paste" "F.Mask")
			(roundrect_rratio 0.25)
			(net 63 "/Supply/EN_1V8")
			(pintype "passive")
		)
	)
	(footprint "antmicro-footprints:DFN-10_2.5x1mm"
		(layer "F.Cu")
		(at 130.5 106.099)
		(property "Reference" "D3"
			(at -0.8 -1.699 0)
			(layer "F.SilkS")
			(effects
				(font
					(size 0.7 0.7)
					(thickness 0.15)
				)
				(justify left bottom)
			)
		)
		(property "Value" "PESD4USB5U-TTS"
			(at 2.032 1.524 0)
			(layer "F.Fab")
			(effects
				(font
					(size 0.7 0.7)
					(thickness 0.15)
				)
				(justify left bottom)
			)
		)
		(property "Footprint" "antmicro-footprints:DFN-10_2.5x1mm"
			(at 0 0 0)
			(layer "F.Fab")
			(hide yes)
			(effects
				(font
					(size 1.27 1.27)
					(thickness 0.15)
				)
			)
		)
		(property "Datasheet" "https://assets.nexperia.com/documents/data-sheet/PESD4USB5U-TTS.pdf"
			(at 0 0 0)
			(layer "F.Fab")
			(hide yes)
			(effects
				(font
					(size 1.27 1.27)
					(thickness 0.15)
				)
			)
		)
		(property "Author" "Antmicro"
			(at 0 0 0)
			(layer "F.Fab")
			(hide yes)
			(effects
				(font
					(size 1 1)
					(thickness 0.15)
				)
			)
		)
		(property "License" "Apache-2.0"
			(at 0 0 0)
			(layer "F.Fab")
			(hide yes)
			(effects
				(font
					(size 1 1)
					(thickness 0.15)
				)
			)
		)
		(property "MPN" "PESD4USB5U-TTS"
			(at 0 0 0)
			(layer "F.Fab")
			(hide yes)
			(effects
				(font
					(size 1 1)
					(thickness 0.15)
				)
			)
		)
		(property "Manufacturer" "Nexperia"
			(at 0 0 0)
			(layer "F.Fab")
			(hide yes)
			(effects
				(font
					(size 1 1)
					(thickness 0.15)
				)
			)
		)
		(sheetname "CSI Connector")
		(sheetfile "CSI.kicad_sch")
		(attr smd)
		(fp_line
			(start -0.4 1.4)
			(end 0.4 1.4)
			(stroke
				(width 0.15)
				(type solid)
			)
			(layer "F.SilkS")
		)
		(fp_line
			(start 0.4 -1.4)
			(end -0.4 -1.4)
			(stroke
				(width 0.15)
				(type solid)
			)
			(layer "F.SilkS")
		)
		(fp_circle
			(center -0.762 -1.27)
			(end -0.712 -1.27)
			(stroke
				(width 0.15)
				(type solid)
			)
			(fill solid)
			(layer "F.SilkS")
		)
		(fp_rect
			(start -0.85 -1.6)
			(end 0.85 1.6)
			(stroke
				(width 0.05)
				(type solid)
			)
			(fill none)
			(layer "F.CrtYd")
		)
		(fp_line
			(start -0.5 -0.9)
			(end -0.5 1.25)
			(stroke
				(width 0.15)
				(type solid)
			)
			(layer "F.Fab")
		)
		(fp_line
			(start -0.5 1.25)
			(end 0.5 1.25)
			(stroke
				(width 0.15)
				(type solid)
			)
			(layer "F.Fab")
		)
		(fp_line
			(start -0.15 -1.25)
			(end -0.5 -0.9)
			(stroke
				(width 0.15)
				(type solid)
			)
			(layer "F.Fab")
		)
		(fp_line
			(start 0.5 -1.25)
			(end -0.15 -1.25)
			(stroke
				(width 0.15)
				(type solid)
			)
			(layer "F.Fab")
		)
		(fp_line
			(start 0.5 1.25)
			(end 0.5 -1.25)
			(stroke
				(width 0.15)
				(type solid)
			)
			(layer "F.Fab")
		)
		(fp_text user "License: Apache-2.0"
			(at -0.95 5.924 0)
			(layer "F.Fab")
			(hide yes)
			(effects
				(font
					(size 0.7 0.7)
					(thickness 0.15)
				)
				(justify left bottom)
			)
		)
		(fp_text user "${REFERENCE}"
			(at -0.95 3.524 0)
			(layer "F.Fab")
			(hide yes)
			(effects
				(font
					(size 0.7 0.7)
					(thickness 0.15)
				)
				(justify left bottom)
			)
		)
		(fp_text user "Author: Antmicro"
			(at -0.95 4.724 0)
			(layer "F.Fab")
			(hide yes)
			(effects
				(font
					(size 0.7 0.7)
					(thickness 0.15)
				)
				(justify left bottom)
			)
		)
		(pad "1" smd roundrect
			(at -0.425 -1 270)
			(size 0.2 0.6)
			(layers "F.Cu" "F.Paste" "F.Mask")
			(roundrect_rratio 0.25)
			(net 38 "/CSI Connector/GPIO3")
			(pinfunction "1")
			(pintype "passive")
			(solder_mask_margin 0.05)
		)
		(pad "2" smd roundrect
			(at -0.425 -0.5 270)
			(size 0.2 0.6)
			(layers "F.Cu" "F.Paste" "F.Mask")
			(roundrect_rratio 0.25)
			(net 39 "/CSI Connector/GPIO4_1V8")
			(pinfunction "2")
			(pintype "passive")
			(solder_mask_margin 0.05)
		)
		(pad "3" smd roundrect
			(at -0.425 0 270)
			(size 0.4 0.6)
			(layers "F.Cu" "F.Paste" "F.Mask")
			(roundrect_rratio 0.25)
			(net 1 "GND")
			(pinfunction "3")
			(pintype "passive")
			(solder_mask_margin 0.05)
		)
		(pad "4" smd roundrect
			(at -0.425 0.5 270)
			(size 0.2 0.6)
			(layers "F.Cu" "F.Paste" "F.Mask")
			(roundrect_rratio 0.25)
			(net 91 "unconnected-(D3-Pad4)")
			(pinfunction "4")
			(pintype "passive")
			(solder_mask_margin 0.05)
		)
		(pad "5" smd roundrect
			(at -0.425 1 270)
			(size 0.2 0.6)
			(layers "F.Cu" "F.Paste" "F.Mask")
			(roundrect_rratio 0.25)
			(net 92 "unconnected-(D3-Pad5)")
			(pinfunction "5")
			(pintype "passive")
			(solder_mask_margin 0.05)
		)
		(pad "6" smd roundrect
			(at 0.425 1 270)
			(size 0.2 0.6)
			(layers "F.Cu" "F.Paste" "F.Mask")
			(roundrect_rratio 0.25)
			(net 92 "unconnected-(D3-Pad5)")
			(pinfunction "6")
			(pintype "passive")
			(solder_mask_margin 0.05)
		)
		(pad "7" smd roundrect
			(at 0.425 0.5 270)
			(size 0.2 0.6)
			(layers "F.Cu" "F.Paste" "F.Mask")
			(roundrect_rratio 0.25)
			(net 91 "unconnected-(D3-Pad4)")
			(pinfunction "7")
			(pintype "passive")
			(solder_mask_margin 0.05)
		)
		(pad "8" smd roundrect
			(at 0.425 0 270)
			(size 0.4 0.6)
			(layers "F.Cu" "F.Paste" "F.Mask")
			(roundrect_rratio 0.25)
			(net 1 "GND")
			(pinfunction "8")
			(pintype "passive")
			(solder_mask_margin 0.05)
		)
		(pad "9" smd roundrect
			(at 0.425 -0.5 270)
			(size 0.2 0.6)
			(layers "F.Cu" "F.Paste" "F.Mask")
			(roundrect_rratio 0.25)
			(net 39 "/CSI Connector/GPIO4_1V8")
			(pinfunction "9")
			(pintype "passive")
			(solder_mask_margin 0.05)
		)
		(pad "10" smd roundrect
			(at 0.425 -1 270)
			(size 0.2 0.6)
			(layers "F.Cu" "F.Paste" "F.Mask")
			(roundrect_rratio 0.25)
			(net 38 "/CSI Connector/GPIO3")
			(pinfunction "10")
			(pintype "passive")
			(solder_mask_margin 0.05)
		)
	)
	(footprint "antmicro-footprints:R_0603_1608Metric"
		(layer "F.Cu")
		(at 136.929 88.647 -90)
		(descr "Resistor SMD 0603")
		(tags "resistor SMD 0603")
		(property "Reference" "R13"
			(at -0.477 -1.481 90)
			(layer "F.SilkS")
			(effects
				(font
					(size 0.7 0.7)
					(thickness 0.15)
				)
				(justify right bottom)
			)
		)
		(property "Value" "R_0R_22.4A_0603"
			(at 0 1.6 90)
			(layer "F.Fab")
			(effects
				(font
					(size 0.7 0.7)
					(thickness 0.15)
				)
				(justify right bottom)
			)
		)
		(property "Footprint" "antmicro-footprints:R_0603_1608Metric"
			(at 0 0 -90)
			(layer "F.Fab")
			(hide yes)
			(effects
				(font
					(size 1.27 1.27)
					(thickness 0.15)
				)
			)
		)
		(property "Datasheet" "https://fscdn.rohm.com/en/products/databook/datasheet/passive/resistor/chip_resistor/pmr-jpw-e.pdf"
			(at 0 0 -90)
			(layer "F.Fab")
			(hide yes)
			(effects
				(font
					(size 1.27 1.27)
					(thickness 0.15)
				)
			)
		)
		(property "Author" "Antmicro"
			(at 50.202 227.196 0)
			(layer "F.Fab")
			(hide yes)
			(effects
				(font
					(size 1 1)
					(thickness 0.15)
				)
			)
		)
		(property "License" "Apache-2.0"
			(at 50.202 227.196 0)
			(layer "F.Fab")
			(hide yes)
			(effects
				(font
					(size 1 1)
					(thickness 0.15)
				)
			)
		)
		(property "MPN" "PMR03EZPJ000"
			(at 50.202 227.196 0)
			(layer "F.Fab")
			(hide yes)
			(effects
				(font
					(size 1 1)
					(thickness 0.15)
				)
			)
		)
		(property "Manufacturer" "ROHM Semiconductor"
			(at 50.202 227.196 0)
			(layer "F.Fab")
			(hide yes)
			(effects
				(font
					(size 1 1)
					(thickness 0.15)
				)
			)
		)
		(property "Max. Curr." "22.4A"
			(at 50.202 227.196 0)
			(layer "F.Fab")
			(hide yes)
			(effects
				(font
					(size 1 1)
					(thickness 0.15)
				)
			)
		)
		(property "Tolerance" "template_tolerance"
			(at 50.202 227.196 0)
			(layer "F.Fab")
			(hide yes)
			(effects
				(font
					(size 1 1)
					(thickness 0.15)
				)
			)
		)
		(property "Val" "0R"
			(at 50.202 227.196 0)
			(layer "F.Fab")
			(hide yes)
			(effects
				(font
					(size 1 1)
					(thickness 0.15)
				)
			)
		)
		(sheetname "Supply")
		(sheetfile "supply.kicad_sch")
		(attr smd)
		(fp_line
			(start -0.15 0.4)
			(end 0.15 0.4)
			(stroke
				(width 0.15)
				(type solid)
			)
			(layer "F.SilkS")
		)
		(fp_line
			(start -0.15 -0.4)
			(end 0.15 -0.4)
			(stroke
				(width 0.15)
				(type solid)
			)
			(layer "F.SilkS")
		)
		(fp_rect
			(start -1.25 -0.65)
			(end 1.25 0.65)
			(stroke
				(width 0.05)
				(type solid)
			)
			(fill none)
			(layer "F.CrtYd")
		)
		(fp_rect
			(start -0.8 -0.4)
			(end 0.8 0.4)
			(stroke
				(width 0.15)
				(type solid)
			)
			(fill none)
			(layer "F.Fab")
		)
		(fp_text user "License: Apache-2.0"
			(at -1.25 5.9 90)
			(layer "F.Fab")
			(hide yes)
			(effects
				(font
					(size 0.7 0.7)
					(thickness 0.15)
				)
				(justify right bottom)
			)
		)
		(fp_text user "Author: Antmicro"
			(at -1.25 4.9 90)
			(layer "F.Fab")
			(hide yes)
			(effects
				(font
					(size 0.7 0.7)
					(thickness 0.15)
				)
				(justify right bottom)
			)
		)
		(fp_text user "${REFERENCE}"
			(at -1.25 3.898 90)
			(layer "F.Fab")
			(hide yes)
			(effects
				(font
					(size 0.7 0.7)
					(thickness 0.15)
				)
				(justify right bottom)
			)
		)
		(pad "1" smd roundrect
			(at -0.7 0 270)
			(size 0.8 1)
			(layers "F.Cu" "F.Paste" "F.Mask")
			(roundrect_rratio 0.2)
			(net 7 "/Supply/OUT_5V")
			(pintype "passive")
		)
		(pad "2" smd roundrect
			(at 0.7 0 270)
			(size 0.8 1)
			(layers "F.Cu" "F.Paste" "F.Mask")
			(roundrect_rratio 0.2)
			(net 9 "+5V")
			(pintype "passive")
		)
	)
	(footprint "antmicro-footprints:LED_0603_1608Metric_G"
		(layer "F.Cu")
		(at 147.75 115.75 -90)
		(descr "LED SMD 0603 Green")
		(tags "LED SMD 0603 Green")
		(property "Reference" "D8"
			(at -2.25 1.125 90)
			(layer "F.SilkS")
			(effects
				(font
					(size 0.7 0.7)
					(thickness 0.15)
				)
				(justify right bottom)
			)
		)
		(property "Value" "LED_G_0603_LTST-C190GKT"
			(at -0.001 1.599 90)
			(layer "F.Fab")
			(effects
				(font
					(size 0.7 0.7)
					(thickness 0.15)
				)
				(justify right bottom)
			)
		)
		(property "Footprint" "antmicro-footprints:LED_0603_1608Metric_G"
			(at 0 0 -90)
			(layer "F.Fab")
			(hide yes)
			(effects
				(font
					(size 1.27 1.27)
					(thickness 0.15)
				)
			)
		)
		(property "Datasheet" "https://media.digikey.com/pdf/Data%20Sheets/Lite-On%20PDFs/LTST-C190GKT.pdf"
			(at 0 0 -90)
			(layer "F.Fab")
			(hide yes)
			(effects
				(font
					(size 1.27 1.27)
					(thickness 0.15)
				)
			)
		)
		(property "Author" "Antmicro"
			(at 32 263.5 0)
			(layer "F.Fab")
			(hide yes)
			(effects
				(font
					(size 1 1)
					(thickness 0.15)
				)
			)
		)
		(property "Color" "Green"
			(at 32 263.5 0)
			(layer "F.Fab")
			(hide yes)
			(effects
				(font
					(size 1 1)
					(thickness 0.15)
				)
			)
		)
		(property "License" "Apache-2.0"
			(at 32 263.5 0)
			(layer "F.Fab")
			(hide yes)
			(effects
				(font
					(size 1 1)
					(thickness 0.15)
				)
			)
		)
		(property "MPN" "LTST-C190GKT"
			(at 32 263.5 0)
			(layer "F.Fab")
			(hide yes)
			(effects
				(font
					(size 1 1)
					(thickness 0.15)
				)
			)
		)
		(property "Manufacturer" "Lite-On"
			(at 32 263.5 0)
			(layer "F.Fab")
			(hide yes)
			(effects
				(font
					(size 1 1)
					(thickness 0.15)
				)
			)
		)
		(property "VSD_class" "LED"
			(at 32 263.5 0)
			(layer "F.Fab")
			(hide yes)
			(effects
				(font
					(size 1 1)
					(thickness 0.15)
				)
			)
		)
		(sheetname "Supply")
		(sheetfile "supply.kicad_sch")
		(attr smd)
		(fp_line
			(start 0.22 0.35)
			(end -0.22 0.35)
			(stroke
				(width 0.15)
				(type solid)
			)
			(layer "F.SilkS")
		)
		(fp_line
			(start -0.094672 0.201008)
			(end -0.094672 -0.198992)
			(stroke
				(width 0.1)
				(type solid)
			)
			(layer "F.SilkS")
		)
		(fp_line
			(start 0.105328 0.201008)
			(end -0.094672 0.001008)
			(stroke
				(width 0.1)
				(type solid)
			)
			(layer "F.SilkS")
		)
		(fp_line
			(start 0.105328 0.201008)
			(end 0.105328 -0.198992)
			(stroke
				(width 0.1)
				(type solid)
			)
			(layer "F.SilkS")
		)
		(fp_line
			(start -0.094672 0.001008)
			(end -0.24 0.001008)
			(stroke
				(width 0.1)
				(type solid)
			)
			(layer "F.SilkS")
		)
		(fp_line
			(start -0.094672 0.001008)
			(end 0.105328 -0.198992)
			(stroke
				(width 0.1)
				(type solid)
			)
			(layer "F.SilkS")
		)
		(fp_line
			(start 0.105328 0.001008)
			(end 0.24 0.001)
			(stroke
				(width 0.1)
				(type solid)
			)
			(layer "F.SilkS")
		)
		(fp_line
			(start -1.18 -0.319)
			(end -1.18 0.321)
			(stroke
				(width 0.15)
				(type solid)
			)
			(layer "F.SilkS")
		)
		(fp_line
			(start 0.22 -0.35)
			(end -0.22 -0.35)
			(stroke
				(width 0.15)
				(type solid)
			)
			(layer "F.SilkS")
		)
		(fp_rect
			(start 1.25 0.65)
			(end -1.25 -0.65)
			(stroke
				(width 0.05)
				(type solid)
			)
			(fill none)
			(layer "F.CrtYd")
		)
		(fp_line
			(start -0.199 0.2)
			(end -0.199 0.1)
			(stroke
				(width 0.15)
				(type solid)
			)
			(layer "F.Fab")
		)
		(fp_line
			(start 0.201 0.2)
			(end 0.201 0)
			(stroke
				(width 0.15)
				(type solid)
			)
			(layer "F.Fab")
		)
		(fp_line
			(start -0.199 0)
			(end -0.597 0)
			(stroke
				(width 0.15)
				(type solid)
			)
			(layer "F.Fab")
		)
		(fp_line
			(start -0.101 0)
			(end 0.201 0.2)
			(stroke
				(width 0.15)
				(type solid)
			)
			(layer "F.Fab")
		)
		(fp_line
			(start 0.201 0)
			(end 0.201 -0.202)
			(stroke
				(width 0.15)
				(type solid)
			)
			(layer "F.Fab")
		)
		(fp_line
			(start 0.599 0)
			(end 0.201 0)
			(stroke
				(width 0.15)
				(type solid)
			)
			(layer "F.Fab")
		)
		(fp_line
			(start -0.199 -0.202)
			(end -0.199 0.1)
			(stroke
				(width 0.15)
				(type solid)
			)
			(layer "F.Fab")
		)
		(fp_line
			(start 0.201 -0.202)
			(end -0.101 0)
			(stroke
				(width 0.15)
				(type solid)
			)
			(layer "F.Fab")
		)
		(fp_rect
			(start 0.848 0.4)
			(end -0.85 -0.402)
			(stroke
				(width 0.15)
				(type solid)
			)
			(fill none)
			(layer "F.Fab")
		)
		(fp_text user "License: Apache-2.0"
			(at -1.4224 3.599 90)
			(layer "F.Fab")
			(hide yes)
			(effects
				(font
					(size 0.7 0.7)
					(thickness 0.15)
				)
				(justify right bottom)
			)
		)
		(fp_text user "${REFERENCE}"
			(at -1.4224 5.999 90)
			(layer "F.Fab")
			(hide yes)
			(effects
				(font
					(size 0.7 0.7)
					(thickness 0.15)
				)
				(justify right bottom)
			)
		)
		(fp_text user "Author: Antmicro"
			(at -1.4224 4.799 90)
			(layer "F.Fab")
			(hide yes)
			(effects
				(font
					(size 0.7 0.7)
					(thickness 0.15)
				)
				(justify right bottom)
			)
		)
		(pad "1" smd roundrect
			(at -0.7 0 90)
			(size 0.8 1)
			(layers "F.Cu" "F.Paste" "F.Mask")
			(roundrect_rratio 0.2)
			(net 73 "Net-(D8-C)")
			(pinfunction "C")
			(pintype "passive")
		)
		(pad "2" smd roundrect
			(at 0.7 0 90)
			(size 0.8 1)
			(layers "F.Cu" "F.Paste" "F.Mask")
			(roundrect_rratio 0.2)
			(net 74 "Net-(D8-A)")
			(pinfunction "A")
			(pintype "passive")
		)
	)
	(footprint "antmicro-footprints:MP_Pad6mm_Drill3mm"
		(layer "F.Cu")
		(at 163.15 81.35)
		(property "Reference" "MP2"
			(at 0 -3.2 0)
			(layer "F.SilkS")
			(hide yes)
			(effects
				(font
					(size 0.7 0.7)
					(thickness 0.15)
				)
				(justify left bottom)
			)
		)
		(property "Value" "MP_Pad6mm_Drill3mm"
			(at 0 3.9 0)
			(layer "F.Fab")
			(effects
				(font
					(size 0.7 0.7)
					(thickness 0.15)
				)
				(justify left bottom)
			)
		)
		(property "Footprint" "antmicro-footprints:MP_Pad6mm_Drill3mm"
			(at 0 0 0)
			(layer "F.Fab")
			(hide yes)
			(effects
				(font
					(size 1.27 1.27)
					(thickness 0.15)
				)
			)
		)
		(property "Author" "Antmicro"
			(at 0 0 0)
			(layer "F.Fab")
			(hide yes)
			(effects
				(font
					(size 1 1)
					(thickness 0.15)
				)
			)
		)
		(property "License" "Apache-2.0"
			(at 0 0 0)
			(layer "F.Fab")
			(hide yes)
			(effects
				(font
					(size 1 1)
					(thickness 0.15)
				)
			)
		)
		(sheetname "Root")
		(sheetfile "gmsl-serializer.kicad_sch")
		(attr exclude_from_pos_files exclude_from_bom)
		(fp_circle
			(center 0 0)
			(end 3.25 0)
			(stroke
				(width 0.05)
				(type default)
			)
			(fill none)
			(layer "F.CrtYd")
		)
		(fp_text user "License: Apache-2.0"
			(at -0.178 8.425 0)
			(layer "F.Fab")
			(hide yes)
			(effects
				(font
					(size 0.7 0.7)
					(thickness 0.15)
				)
				(justify left bottom)
			)
		)
		(fp_text user "Author: Antmicro"
			(at -0.178 7.225 0)
			(layer "F.Fab")
			(hide yes)
			(effects
				(font
					(size 0.7 0.7)
					(thickness 0.15)
				)
				(justify left bottom)
			)
		)
		(fp_text user "${REFERENCE}"
			(at -0.178 6.025 0)
			(layer "F.Fab")
			(hide yes)
			(effects
				(font
					(size 0.7 0.7)
					(thickness 0.15)
				)
				(justify left bottom)
			)
		)
		(pad "1" thru_hole circle
			(at 0 0)
			(size 6 6)
			(drill 3)
			(layers "*.Cu" "*.Mask")
			(remove_unused_layers no)
			(net 1 "GND")
			(pintype "passive")
			(solder_paste_margin_ratio -1)
		)
	)
	(footprint "antmicro-footprints:C_0402_1005Metric"
		(layer "F.Cu")
		(at 145.1 85.75 -90)
		(descr "Capacitor SMD 0402")
		(tags "capacitor SMD 0402")
		(property "Reference" "C35"
			(at 0.85 -0.95 90)
			(layer "F.SilkS")
			(effects
				(font
					(size 0.7 0.7)
					(thickness 0.15)
				)
				(justify right top)
			)
		)
		(property "Value" "C_22u_0402"
			(at -1.022927 2.155213 90)
			(layer "F.Fab")
			(effects
				(font
					(size 0.7 0.7)
					(thickness 0.15)
				)
				(justify right top)
			)
		)
		(property "Footprint" "antmicro-footprints:C_0402_1005Metric"
			(at 0 0 90)
			(layer "F.Fab")
			(hide yes)
			(effects
				(font
					(size 1.27 1.27)
					(thickness 0.15)
				)
			)
		)
		(property "Datasheet" "https://www.murata.com/products/productdetail?partno=GRM158R60J226ME01%23"
			(at 0 0 90)
			(layer "F.Fab")
			(hide yes)
			(effects
				(font
					(size 1.27 1.27)
					(thickness 0.15)
				)
			)
		)
		(property "MPN" "GRM158R60J226ME01D"
			(at 0 0 -90)
			(unlocked yes)
			(layer "F.Fab")
			(hide yes)
			(effects
				(font
					(size 1 1)
					(thickness 0.15)
				)
			)
		)
		(property "Manufacturer" "Murata"
			(at 0 0 -90)
			(unlocked yes)
			(layer "F.Fab")
			(hide yes)
			(effects
				(font
					(size 1 1)
					(thickness 0.15)
				)
			)
		)
		(property "License" "Apache-2.0"
			(at 0 0 -90)
			(unlocked yes)
			(layer "F.Fab")
			(hide yes)
			(effects
				(font
					(size 1 1)
					(thickness 0.15)
				)
			)
		)
		(property "Author" "Antmicro"
			(at 0 0 -90)
			(unlocked yes)
			(layer "F.Fab")
			(hide yes)
			(effects
				(font
					(size 1 1)
					(thickness 0.15)
				)
			)
		)
		(property "Val" "22u"
			(at 0 0 -90)
			(unlocked yes)
			(layer "F.Fab")
			(hide yes)
			(effects
				(font
					(size 1 1)
					(thickness 0.15)
				)
			)
		)
		(property "Voltage" ""
			(at 0 0 -90)
			(unlocked yes)
			(layer "F.Fab")
			(hide yes)
			(effects
				(font
					(size 1 1)
					(thickness 0.15)
				)
			)
		)
		(property "Dielectric" ""
			(at 0 0 -90)
			(unlocked yes)
			(layer "F.Fab")
			(hide yes)
			(effects
				(font
					(size 1 1)
					(thickness 0.15)
				)
			)
		)
		(sheetname "Supply")
		(sheetfile "supply.kicad_sch")
		(attr smd)
		(fp_rect
			(start -0.925 -0.47)
			(end 0.925 0.47)
			(stroke
				(width 0.05)
				(type default)
			)
			(fill none)
			(layer "F.CrtYd")
		)
		(fp_line
			(start -0.494 0.248)
			(end -0.494 -0.25)
			(stroke
				(width 0.15)
				(type solid)
			)
			(layer "F.Fab")
		)
		(fp_line
			(start 0.504 0.248)
			(end -0.494 0.248)
			(stroke
				(width 0.15)
				(type solid)
			)
			(layer "F.Fab")
		)
		(fp_line
			(start -0.494 -0.25)
			(end 0.504 -0.25)
			(stroke
				(width 0.15)
				(type solid)
			)
			(layer "F.Fab")
		)
		(fp_line
			(start 0.504 -0.25)
			(end 0.504 0.248)
			(stroke
				(width 0.15)
				(type solid)
			)
			(layer "F.Fab")
		)
		(fp_text user "License: Apache-2.0"
			(at -0.939 5.799 90)
			(layer "F.Fab")
			(hide yes)
			(effects
				(font
					(size 0.7 0.7)
					(thickness 0.15)
				)
				(justify right top)
			)
		)
		(fp_text user "${REFERENCE}"
			(at -0.939 4.599 90)
			(layer "F.Fab")
			(hide yes)
			(effects
				(font
					(size 0.7 0.7)
					(thickness 0.15)
				)
				(justify right top)
			)
		)
		(fp_text user "Author: Antmicro"
			(at -0.939 3.399 90)
			(layer "F.Fab")
			(hide yes)
			(effects
				(font
					(size 0.7 0.7)
					(thickness 0.15)
				)
				(justify right top)
			)
		)
		(pad "1" smd roundrect
			(at -0.48 0 270)
			(size 0.59 0.64)
			(layers "F.Cu" "F.Paste" "F.Mask")
			(roundrect_rratio 0.25)
			(net 1 "GND")
			(pintype "passive")
		)
		(pad "2" smd roundrect
			(at 0.48 0 270)
			(size 0.59 0.64)
			(layers "F.Cu" "F.Paste" "F.Mask")
			(roundrect_rratio 0.25)
			(net 94 "/Supply/OUT_3V3")
			(pintype "passive")
		)
	)
	(footprint "antmicro-footprints:C_0402_1005Metric"
		(layer "F.Cu")
		(at 152.69 103.33 -45)
		(descr "Capacitor SMD 0402")
		(tags "capacitor SMD 0402")
		(property "Reference" "C16"
			(at 0.92631 0.374767 -45)
			(unlocked yes)
			(layer "F.SilkS")
			(effects
				(font
					(size 0.7 0.7)
					(thickness 0.15)
				)
				(justify left bottom)
			)
		)
		(property "Value" "C_33p_0402"
			(at -1.022927 2.155213 135)
			(layer "F.Fab")
			(effects
				(font
					(size 0.7 0.7)
					(thickness 0.15)
				)
				(justify right bottom)
			)
		)
		(property "Footprint" "antmicro-footprints:C_0402_1005Metric"
			(at 0 0 -45)
			(layer "F.Fab")
			(hide yes)
			(effects
				(font
					(size 1.27 1.27)
					(thickness 0.15)
				)
			)
		)
		(property "Datasheet" "https://spicat.kyocera-avx.com/product/mlcc/chartview/04025A330FAT2A/"
			(at 0 0 -45)
			(layer "F.Fab")
			(hide yes)
			(effects
				(font
					(size 1.27 1.27)
					(thickness 0.15)
				)
			)
		)
		(property "Author" "Antmicro"
			(at -28.343478 138.23279 0)
			(layer "F.Fab")
			(hide yes)
			(effects
				(font
					(size 1 1)
					(thickness 0.15)
				)
			)
		)
		(property "Dielectric" ""
			(at -28.343478 138.23279 0)
			(layer "F.Fab")
			(hide yes)
			(effects
				(font
					(size 1 1)
					(thickness 0.15)
				)
			)
		)
		(property "License" "Apache-2.0"
			(at -28.343478 138.23279 0)
			(layer "F.Fab")
			(hide yes)
			(effects
				(font
					(size 1 1)
					(thickness 0.15)
				)
			)
		)
		(property "MPN" "04025A330FAT2A"
			(at -28.343478 138.23279 0)
			(layer "F.Fab")
			(hide yes)
			(effects
				(font
					(size 1 1)
					(thickness 0.15)
				)
			)
		)
		(property "Manufacturer" "KYOCERA AVX"
			(at -28.343478 138.23279 0)
			(layer "F.Fab")
			(hide yes)
			(effects
				(font
					(size 1 1)
					(thickness 0.15)
				)
			)
		)
		(property "Val" "33p"
			(at -28.343478 138.23279 0)
			(layer "F.Fab")
			(hide yes)
			(effects
				(font
					(size 1 1)
					(thickness 0.15)
				)
			)
		)
		(property "Voltage" ""
			(at -28.343478 138.23279 0)
			(layer "F.Fab")
			(hide yes)
			(effects
				(font
					(size 1 1)
					(thickness 0.15)
				)
			)
		)
		(sheetname "Serializer")
		(sheetfile "serializer.kicad_sch")
		(attr smd)
		(fp_poly
			(pts
				(xy -0.925 -0.47) (xy 0.925 -0.47) (xy 0.925 0.47) (xy -0.925 0.47)
			)
			(stroke
				(width 0.05)
				(type default)
			)
			(fill none)
			(layer "F.CrtYd")
		)
		(fp_line
			(start -0.494 0.248)
			(end -0.494 -0.25)
			(stroke
				(width 0.15)
				(type solid)
			)
			(layer "F.Fab")
		)
		(fp_line
			(start -0.494 -0.25)
			(end 0.504 -0.25)
			(stroke
				(width 0.15)
				(type solid)
			)
			(layer "F.Fab")
		)
		(fp_line
			(start 0.504 0.248)
			(end -0.494 0.248)
			(stroke
				(width 0.15)
				(type solid)
			)
			(layer "F.Fab")
		)
		(fp_line
			(start 0.504 -0.25)
			(end 0.504 0.248)
			(stroke
				(width 0.15)
				(type solid)
			)
			(layer "F.Fab")
		)
		(fp_text user "License: Apache-2.0"
			(at -0.939 5.799 135)
			(layer "F.Fab")
			(hide yes)
			(effects
				(font
					(size 0.7 0.7)
					(thickness 0.15)
				)
				(justify right bottom)
			)
		)
		(fp_text user "${REFERENCE}"
			(at -0.939 4.599 135)
			(layer "F.Fab")
			(hide yes)
			(effects
				(font
					(size 0.7 0.7)
					(thickness 0.15)
				)
				(justify right bottom)
			)
		)
		(fp_text user "Author: Antmicro"
			(at -0.939 3.399 135)
			(layer "F.Fab")
			(hide yes)
			(effects
				(font
					(size 0.7 0.7)
					(thickness 0.15)
				)
				(justify right bottom)
			)
		)
		(pad "1" smd roundrect
			(at -0.48 0 315)
			(size 0.59 0.64)
			(layers "F.Cu" "F.Paste" "F.Mask")
			(roundrect_rratio 0.25)
			(net 1 "GND")
			(pintype "passive")
		)
		(pad "2" smd roundrect
			(at 0.48 0 315)
			(size 0.59 0.64)
			(layers "F.Cu" "F.Paste" "F.Mask")
			(roundrect_rratio 0.25)
			(net 13 "/Serializer/X1")
			(pintype "passive")
		)
	)
	(footprint "antmicro-footprints:R_0402_1005Metric"
		(layer "F.Cu")
		(at 152.069483 99.847484 -135)
		(descr "Resistor SMD 0402")
		(tags "resistor SMD 0402")
		(property "Reference" "R23"
			(at -2.224489 -0.137712 45)
			(layer "F.SilkS")
			(effects
				(font
					(size 0.7 0.7)
					(thickness 0.15)
				)
				(justify left bottom)
			)
		)
		(property "Value" "R_402R_0402"
			(at -1.011843 1.772046 45)
			(layer "F.Fab")
			(effects
				(font
					(size 0.7 0.7)
					(thickness 0.15)
				)
				(justify right bottom)
			)
		)
		(property "Footprint" "antmicro-footprints:R_0402_1005Metric"
			(at 0 0 -135)
			(layer "F.Fab")
			(hide yes)
			(effects
				(font
					(size 1.27 1.27)
					(thickness 0.15)
				)
			)
		)
		(property "Datasheet" "https://www.mouser.com/datasheet/2/54/cr-1858361.pdf"
			(at 0 0 -135)
			(layer "F.Fab")
			(hide yes)
			(effects
				(font
					(size 1.27 1.27)
					(thickness 0.15)
				)
			)
		)
		(property "Author" "Antmicro"
			(at 188.996013 277.97968 0)
			(layer "F.Fab")
			(hide yes)
			(effects
				(font
					(size 1 1)
					(thickness 0.15)
				)
			)
		)
		(property "License" "Apache-2.0"
			(at 188.996013 277.97968 0)
			(layer "F.Fab")
			(hide yes)
			(effects
				(font
					(size 1 1)
					(thickness 0.15)
				)
			)
		)
		(property "MPN" "CR0402-FX-4020GLF"
			(at 188.996013 277.97968 0)
			(layer "F.Fab")
			(hide yes)
			(effects
				(font
					(size 1 1)
					(thickness 0.15)
				)
			)
		)
		(property "Manufacturer" "Bourns"
			(at 188.996013 277.97968 0)
			(layer "F.Fab")
			(hide yes)
			(effects
				(font
					(size 1 1)
					(thickness 0.15)
				)
			)
		)
		(property "Tolerance" "1%"
			(at 188.996013 277.97968 0)
			(layer "F.Fab")
			(hide yes)
			(effects
				(font
					(size 1 1)
					(thickness 0.15)
				)
			)
		)
		(property "Val" "402R"
			(at 188.996013 277.97968 0)
			(layer "F.Fab")
			(hide yes)
			(effects
				(font
					(size 1 1)
					(thickness 0.15)
				)
			)
		)
		(sheetname "Serializer")
		(sheetfile "serializer.kicad_sch")
		(attr smd)
		(fp_poly
			(pts
				(xy -0.925 -0.47) (xy 0.925 -0.47) (xy 0.925 0.47) (xy -0.925 0.47)
			)
			(stroke
				(width 0.05)
				(type default)
			)
			(fill none)
			(layer "F.CrtYd")
		)
		(fp_poly
			(pts
				(xy -0.5 -0.25) (xy 0.5 -0.25) (xy 0.5 0.25) (xy -0.5 0.25)
			)
			(stroke
				(width 0.15)
				(type solid)
			)
			(fill none)
			(layer "F.Fab")
		)
		(fp_text user "${REFERENCE}"
			(at -0.95 3.168 45)
			(layer "F.Fab")
			(hide yes)
			(effects
				(font
					(size 0.7 0.7)
					(thickness 0.15)
				)
				(justify right bottom)
			)
		)
		(fp_text user "License: Apache-2.0"
			(at -0.949999 5.169 45)
			(layer "F.Fab")
			(hide yes)
			(effects
				(font
					(size 0.7 0.7)
					(thickness 0.15)
				)
				(justify right bottom)
			)
		)
		(fp_text user "Author: Antmicro"
			(at -0.95 4.169 45)
			(layer "F.Fab")
			(hide yes)
			(effects
				(font
					(size 0.7 0.7)
					(thickness 0.15)
				)
				(justify right bottom)
			)
		)
		(pad "1" smd roundrect
			(at -0.48 0 225)
			(size 0.59 0.64)
			(layers "F.Cu" "F.Paste" "F.Mask")
			(roundrect_rratio 0.25)
			(net 1 "GND")
			(pintype "passive")
		)
		(pad "2" smd roundrect
			(at 0.48 0 225)
			(size 0.59 0.64)
			(layers "F.Cu" "F.Paste" "F.Mask")
			(roundrect_rratio 0.25)
			(net 76 "Net-(U6-XRES)")
			(pintype "passive")
		)
	)
	(footprint "antmicro-footprints:R_0402_1005Metric"
		(layer "F.Cu")
		(at 135.4 109.884)
		(descr "Resistor SMD 0402")
		(tags "resistor SMD 0402")
		(property "Reference" "R30"
			(at 0.9 0.341 0)
			(layer "F.SilkS")
			(effects
				(font
					(size 0.7 0.7)
					(thickness 0.15)
				)
				(justify left bottom)
			)
		)
		(property "Value" "R_0R_0402"
			(at -1.011843 1.772047 0)
			(layer "F.Fab")
			(effects
				(font
					(size 0.7 0.7)
					(thickness 0.15)
				)
				(justify left bottom)
			)
		)
		(property "Footprint" "antmicro-footprints:R_0402_1005Metric"
			(at 0 0 0)
			(layer "F.Fab")
			(hide yes)
			(effects
				(font
					(size 1.27 1.27)
					(thickness 0.15)
				)
			)
		)
		(property "Datasheet" "https://industrial.panasonic.com/cdbs/www-data/pdf/RDA0000/AOA0000C301.pdf"
			(at 0 0 0)
			(layer "F.Fab")
			(hide yes)
			(effects
				(font
					(size 1.27 1.27)
					(thickness 0.15)
				)
			)
		)
		(property "Author" "Antmicro"
			(at 0 0 0)
			(layer "F.Fab")
			(hide yes)
			(effects
				(font
					(size 1 1)
					(thickness 0.15)
				)
			)
		)
		(property "Current" "1A"
			(at 0 0 0)
			(layer "F.Fab")
			(hide yes)
			(effects
				(font
					(size 1 1)
					(thickness 0.15)
				)
			)
		)
		(property "License" "Apache-2.0"
			(at 0 0 0)
			(layer "F.Fab")
			(hide yes)
			(effects
				(font
					(size 1 1)
					(thickness 0.15)
				)
			)
		)
		(property "MPN" "ERJ2GE0R00X"
			(at 0 0 0)
			(layer "F.Fab")
			(hide yes)
			(effects
				(font
					(size 1 1)
					(thickness 0.15)
				)
			)
		)
		(property "Manufacturer" "Panasonic"
			(at 0 0 0)
			(layer "F.Fab")
			(hide yes)
			(effects
				(font
					(size 1 1)
					(thickness 0.15)
				)
			)
		)
		(property "Tolerance" ""
			(at 0 0 0)
			(layer "F.Fab")
			(hide yes)
			(effects
				(font
					(size 1 1)
					(thickness 0.15)
				)
			)
		)
		(property "Val" "0R"
			(at 0 0 0)
			(layer "F.Fab")
			(hide yes)
			(effects
				(font
					(size 1 1)
					(thickness 0.15)
				)
			)
		)
		(sheetname "Serializer")
		(sheetfile "serializer.kicad_sch")
		(attr smd exclude_from_bom dnp)
		(fp_rect
			(start -0.925 -0.47)
			(end 0.925 0.47)
			(stroke
				(width 0.05)
				(type default)
			)
			(fill none)
			(layer "F.CrtYd")
		)
		(fp_rect
			(start -0.5 -0.25)
			(end 0.5 0.25)
			(stroke
				(width 0.15)
				(type solid)
			)
			(fill none)
			(layer "F.Fab")
		)
		(fp_text user "Author: Antmicro"
			(at -0.95 4.169 0)
			(layer "F.Fab")
			(hide yes)
			(effects
				(font
					(size 0.7 0.7)
					(thickness 0.15)
				)
				(justify left bottom)
			)
		)
		(fp_text user "${REFERENCE}"
			(at -0.95 3.168 0)
			(layer "F.Fab")
			(hide yes)
			(effects
				(font
					(size 0.7 0.7)
					(thickness 0.15)
				)
				(justify left bottom)
			)
		)
		(fp_text user "License: Apache-2.0"
			(at -0.95 5.169 0)
			(layer "F.Fab")
			(hide yes)
			(effects
				(font
					(size 0.7 0.7)
					(thickness 0.15)
				)
				(justify left bottom)
			)
		)
		(pad "1" smd roundrect
			(at -0.48 0)
			(size 0.59 0.64)
			(layers "F.Cu" "F.Paste" "F.Mask")
			(roundrect_rratio 0.25)
			(net 88 "/CSI Connector/I2C.SDA")
			(pintype "passive")
		)
		(pad "2" smd roundrect
			(at 0.48 0)
			(size 0.59 0.64)
			(layers "F.Cu" "F.Paste" "F.Mask")
			(roundrect_rratio 0.25)
			(net 78 "Net-(U6-MFP7)")
			(pintype "passive")
		)
	)
	(footprint "antmicro-footprints:TP_SMD_1.5mm"
		(layer "F.Cu")
		(at 153.25 118)
		(property "Reference" "TP6"
			(at -0.8 -1 0)
			(layer "F.SilkS")
			(hide yes)
			(effects
				(font
					(size 0.7 0.7)
					(thickness 0.15)
				)
				(justify left bottom)
			)
		)
		(property "Value" "TP_1.5mm_SMD"
			(at 0 1.7 0)
			(layer "F.Fab")
			(effects
				(font
					(size 0.7 0.7)
					(thickness 0.15)
				)
				(justify left bottom)
			)
		)
		(property "Footprint" "antmicro-footprints:TP_SMD_1.5mm"
			(at 0 0 0)
			(layer "F.Fab")
			(hide yes)
			(effects
				(font
					(size 1.27 1.27)
					(thickness 0.15)
				)
			)
		)
		(property "Author" "Antmicro"
			(at 0 0 0)
			(layer "F.Fab")
			(hide yes)
			(effects
				(font
					(size 1 1)
					(thickness 0.15)
				)
			)
		)
		(property "License" "Apache-2.0"
			(at 0 0 0)
			(layer "F.Fab")
			(hide yes)
			(effects
				(font
					(size 1 1)
					(thickness 0.15)
				)
			)
		)
		(property "MPN" ""
			(at 0 0 0)
			(layer "F.Fab")
			(hide yes)
			(effects
				(font
					(size 1 1)
					(thickness 0.15)
				)
			)
		)
		(property "Manufacturer" ""
			(at 0 0 0)
			(layer "F.Fab")
			(hide yes)
			(effects
				(font
					(size 1 1)
					(thickness 0.15)
				)
			)
		)
		(sheetname "Serializer")
		(sheetfile "serializer.kicad_sch")
		(attr exclude_from_pos_files exclude_from_bom)
		(fp_circle
			(center 0 0)
			(end 0.85 0)
			(stroke
				(width 0.05)
				(type default)
			)
			(fill none)
			(layer "F.CrtYd")
		)
		(fp_text user "License: Apache-2.0"
			(at -0.7 5.301 0)
			(layer "F.Fab")
			(hide yes)
			(effects
				(font
					(size 0.7 0.7)
					(thickness 0.15)
				)
				(justify left bottom)
			)
		)
		(fp_text user "Author: Antmicro"
			(at -0.7 4.101 0)
			(layer "F.Fab")
			(hide yes)
			(effects
				(font
					(size 0.7 0.7)
					(thickness 0.15)
				)
				(justify left bottom)
			)
		)
		(fp_text user "${REFERENCE}"
			(at -0.7 2.9 0)
			(layer "F.Fab")
			(hide yes)
			(effects
				(font
					(size 0.7 0.7)
					(thickness 0.15)
				)
				(justify left bottom)
			)
		)
		(pad "1" smd circle
			(at 0 0 270)
			(size 1.5 1.5)
			(layers "F.Cu" "F.Mask")
			(net 83 "Net-(U6-MFP0)")
			(pinfunction "1")
			(pintype "passive")
		)
	)
	(footprint "antmicro-footprints:LED_0603_1608Metric_G"
		(layer "F.Cu")
		(at 150.5 115.75 -90)
		(descr "LED SMD 0603 Green")
		(tags "LED SMD 0603 Green")
		(property "Reference" "D6"
			(at 0.325 -1.525 90)
			(layer "F.SilkS")
			(effects
				(font
					(size 0.7 0.7)
					(thickness 0.15)
				)
				(justify right bottom)
			)
		)
		(property "Value" "LED_G_0603_LTST-C190GKT"
			(at -0.001 1.599 90)
			(layer "F.Fab")
			(effects
				(font
					(size 0.7 0.7)
					(thickness 0.15)
				)
				(justify right bottom)
			)
		)
		(property "Footprint" "antmicro-footprints:LED_0603_1608Metric_G"
			(at 0 0 -90)
			(layer "F.Fab")
			(hide yes)
			(effects
				(font
					(size 1.27 1.27)
					(thickness 0.15)
				)
			)
		)
		(property "Datasheet" "https://media.digikey.com/pdf/Data%20Sheets/Lite-On%20PDFs/LTST-C190GKT.pdf"
			(at 0 0 -90)
			(layer "F.Fab")
			(hide yes)
			(effects
				(font
					(size 1.27 1.27)
					(thickness 0.15)
				)
			)
		)
		(property "Author" "Antmicro"
			(at 34.75 266.25 0)
			(layer "F.Fab")
			(hide yes)
			(effects
				(font
					(size 1 1)
					(thickness 0.15)
				)
			)
		)
		(property "Color" "Green"
			(at 34.75 266.25 0)
			(layer "F.Fab")
			(hide yes)
			(effects
				(font
					(size 1 1)
					(thickness 0.15)
				)
			)
		)
		(property "License" "Apache-2.0"
			(at 34.75 266.25 0)
			(layer "F.Fab")
			(hide yes)
			(effects
				(font
					(size 1 1)
					(thickness 0.15)
				)
			)
		)
		(property "MPN" "LTST-C190GKT"
			(at 34.75 266.25 0)
			(layer "F.Fab")
			(hide yes)
			(effects
				(font
					(size 1 1)
					(thickness 0.15)
				)
			)
		)
		(property "Manufacturer" "Lite-On"
			(at 34.75 266.25 0)
			(layer "F.Fab")
			(hide yes)
			(effects
				(font
					(size 1 1)
					(thickness 0.15)
				)
			)
		)
		(property "VSD_class" "LED"
			(at 34.75 266.25 0)
			(layer "F.Fab")
			(hide yes)
			(effects
				(font
					(size 1 1)
					(thickness 0.15)
				)
			)
		)
		(sheetname "Supply")
		(sheetfile "supply.kicad_sch")
		(attr smd)
		(fp_line
			(start 0.22 0.35)
			(end -0.22 0.35)
			(stroke
				(width 0.15)
				(type solid)
			)
			(layer "F.SilkS")
		)
		(fp_line
			(start -0.094672 0.201008)
			(end -0.094672 -0.198992)
			(stroke
				(width 0.1)
				(type solid)
			)
			(layer "F.SilkS")
		)
		(fp_line
			(start 0.105328 0.201008)
			(end -0.094672 0.001008)
			(stroke
				(width 0.1)
				(type solid)
			)
			(layer "F.SilkS")
		)
		(fp_line
			(start 0.105328 0.201008)
			(end 0.105328 -0.198992)
			(stroke
				(width 0.1)
				(type solid)
			)
			(layer "F.SilkS")
		)
		(fp_line
			(start -0.094672 0.001008)
			(end -0.24 0.001008)
			(stroke
				(width 0.1)
				(type solid)
			)
			(layer "F.SilkS")
		)
		(fp_line
			(start -0.094672 0.001008)
			(end 0.105328 -0.198992)
			(stroke
				(width 0.1)
				(type solid)
			)
			(layer "F.SilkS")
		)
		(fp_line
			(start 0.105328 0.001008)
			(end 0.24 0.001)
			(stroke
				(width 0.1)
				(type solid)
			)
			(layer "F.SilkS")
		)
		(fp_line
			(start -1.18 -0.319)
			(end -1.18 0.321)
			(stroke
				(width 0.15)
				(type solid)
			)
			(layer "F.SilkS")
		)
		(fp_line
			(start 0.22 -0.35)
			(end -0.22 -0.35)
			(stroke
				(width 0.15)
				(type solid)
			)
			(layer "F.SilkS")
		)
		(fp_rect
			(start 1.25 0.65)
			(end -1.25 -0.65)
			(stroke
				(width 0.05)
				(type solid)
			)
			(fill none)
			(layer "F.CrtYd")
		)
		(fp_line
			(start -0.199 0.2)
			(end -0.199 0.1)
			(stroke
				(width 0.15)
				(type solid)
			)
			(layer "F.Fab")
		)
		(fp_line
			(start 0.201 0.2)
			(end 0.201 0)
			(stroke
				(width 0.15)
				(type solid)
			)
			(layer "F.Fab")
		)
		(fp_line
			(start -0.199 0)
			(end -0.597 0)
			(stroke
				(width 0.15)
				(type solid)
			)
			(layer "F.Fab")
		)
		(fp_line
			(start -0.101 0)
			(end 0.201 0.2)
			(stroke
				(width 0.15)
				(type solid)
			)
			(layer "F.Fab")
		)
		(fp_line
			(start 0.201 0)
			(end 0.201 -0.202)
			(stroke
				(width 0.15)
				(type solid)
			)
			(layer "F.Fab")
		)
		(fp_line
			(start 0.599 0)
			(end 0.201 0)
			(stroke
				(width 0.15)
				(type solid)
			)
			(layer "F.Fab")
		)
		(fp_line
			(start -0.199 -0.202)
			(end -0.199 0.1)
			(stroke
				(width 0.15)
				(type solid)
			)
			(layer "F.Fab")
		)
		(fp_line
			(start 0.201 -0.202)
			(end -0.101 0)
			(stroke
				(width 0.15)
				(type solid)
			)
			(layer "F.Fab")
		)
		(fp_rect
			(start 0.848 0.4)
			(end -0.85 -0.402)
			(stroke
				(width 0.15)
				(type solid)
			)
			(fill none)
			(layer "F.Fab")
		)
		(fp_text user "License: Apache-2.0"
			(at -1.4224 3.599 90)
			(layer "F.Fab")
			(hide yes)
			(effects
				(font
					(size 0.7 0.7)
					(thickness 0.15)
				)
				(justify right bottom)
			)
		)
		(fp_text user "${REFERENCE}"
			(at -1.4224 5.999 90)
			(layer "F.Fab")
			(hide yes)
			(effects
				(font
					(size 0.7 0.7)
					(thickness 0.15)
				)
				(justify right bottom)
			)
		)
		(fp_text user "Author: Antmicro"
			(at -1.4224 4.799 90)
			(layer "F.Fab")
			(hide yes)
			(effects
				(font
					(size 0.7 0.7)
					(thickness 0.15)
				)
				(justify right bottom)
			)
		)
		(pad "1" smd roundrect
			(at -0.7 0 90)
			(size 0.8 1)
			(layers "F.Cu" "F.Paste" "F.Mask")
			(roundrect_rratio 0.2)
			(net 70 "Net-(D6-C)")
			(pinfunction "C")
			(pintype "passive")
		)
		(pad "2" smd roundrect
			(at 0.7 0 90)
			(size 0.8 1)
			(layers "F.Cu" "F.Paste" "F.Mask")
			(roundrect_rratio 0.2)
			(net 71 "Net-(D6-A)")
			(pinfunction "A")
			(pintype "passive")
		)
	)
	(footprint "antmicro-footprints:R_0402_1005Metric"
		(layer "F.Cu")
		(at 161.6 85.598 180)
		(descr "Resistor SMD 0402")
		(tags "resistor SMD 0402")
		(property "Reference" "R16"
			(at 0.95 -0.39 0)
			(layer "F.SilkS")
			(effects
				(font
					(size 0.7 0.7)
					(thickness 0.15)
				)
				(justify right bottom)
			)
		)
		(property "Value" "R_5k1_0402"
			(at -1.011843 1.772047 0)
			(layer "F.Fab")
			(effects
				(font
					(size 0.7 0.7)
					(thickness 0.15)
				)
				(justify right bottom)
			)
		)
		(property "Footprint" "antmicro-footprints:R_0402_1005Metric"
			(at 0 0 180)
			(layer "F.Fab")
			(hide yes)
			(effects
				(font
					(size 1.27 1.27)
					(thickness 0.15)
				)
			)
		)
		(property "Datasheet" "https://www.bourns.com/docs/product-datasheets/cr.pdf"
			(at 0 0 180)
			(layer "F.Fab")
			(hide yes)
			(effects
				(font
					(size 1.27 1.27)
					(thickness 0.15)
				)
			)
		)
		(property "Author" "Antmicro"
			(at 323.2 171.196 0)
			(layer "F.Fab")
			(hide yes)
			(effects
				(font
					(size 1 1)
					(thickness 0.15)
				)
			)
		)
		(property "License" "Apache-2.0"
			(at 323.2 171.196 0)
			(layer "F.Fab")
			(hide yes)
			(effects
				(font
					(size 1 1)
					(thickness 0.15)
				)
			)
		)
		(property "MPN" "CR0402-FX-5101GLF"
			(at 323.2 171.196 0)
			(layer "F.Fab")
			(hide yes)
			(effects
				(font
					(size 1 1)
					(thickness 0.15)
				)
			)
		)
		(property "Manufacturer" "Bourns"
			(at 323.2 171.196 0)
			(layer "F.Fab")
			(hide yes)
			(effects
				(font
					(size 1 1)
					(thickness 0.15)
				)
			)
		)
		(property "Tolerance" "1%"
			(at 323.2 171.196 0)
			(layer "F.Fab")
			(hide yes)
			(effects
				(font
					(size 1 1)
					(thickness 0.15)
				)
			)
		)
		(property "Val" "5k1"
			(at 323.2 171.196 0)
			(layer "F.Fab")
			(hide yes)
			(effects
				(font
					(size 1 1)
					(thickness 0.15)
				)
			)
		)
		(sheetname "GMSL Connector")
		(sheetfile "GMSL.kicad_sch")
		(attr smd)
		(fp_rect
			(start -0.925 -0.47)
			(end 0.925 0.47)
			(stroke
				(width 0.05)
				(type default)
			)
			(fill none)
			(layer "F.CrtYd")
		)
		(fp_rect
			(start -0.5 -0.25)
			(end 0.5 0.25)
			(stroke
				(width 0.15)
				(type solid)
			)
			(fill none)
			(layer "F.Fab")
		)
		(fp_text user "${REFERENCE}"
			(at -0.95 3.168 0)
			(layer "F.Fab")
			(hide yes)
			(effects
				(font
					(size 0.7 0.7)
					(thickness 0.15)
				)
				(justify right bottom)
			)
		)
		(fp_text user "Author: Antmicro"
			(at -0.95 4.169 0)
			(layer "F.Fab")
			(hide yes)
			(effects
				(font
					(size 0.7 0.7)
					(thickness 0.15)
				)
				(justify right bottom)
			)
		)
		(fp_text user "License: Apache-2.0"
			(at -0.95 5.169 0)
			(layer "F.Fab")
			(hide yes)
			(effects
				(font
					(size 0.7 0.7)
					(thickness 0.15)
				)
				(justify right bottom)
			)
		)
		(pad "1" smd roundrect
			(at -0.48 0 180)
			(size 0.59 0.64)
			(layers "F.Cu" "F.Paste" "F.Mask")
			(roundrect_rratio 0.25)
			(net 2 "+12V")
			(pintype "passive")
		)
		(pad "2" smd roundrect
			(at 0.48 0 180)
			(size 0.59 0.64)
			(layers "F.Cu" "F.Paste" "F.Mask")
			(roundrect_rratio 0.25)
			(net 58 "Net-(L3-Pad2)")
			(pintype "passive")
		)
	)
	(footprint "antmicro-footprints:C_0402_1005Metric"
		(layer "B.Cu")
		(at 150.17 101.44 45)
		(descr "Capacitor SMD 0402")
		(tags "capacitor SMD 0402")
		(property "Reference" "C28"
			(at -3.563818 0.381838 45)
			(layer "B.SilkS")
			(effects
				(font
					(size 0.7 0.7)
					(thickness 0.15)
				)
				(justify right bottom mirror)
			)
		)
		(property "Value" "C_10n_0402"
			(at -0.676445 -2.119857 45)
			(layer "B.Fab")
			(effects
				(font
					(size 0.7 0.7)
					(thickness 0.15)
				)
				(justify right bottom mirror)
			)
		)
		(property "Footprint" "antmicro-footprints:C_0402_1005Metric"
			(at 0 0 45)
			(layer "F.Fab")
			(hide yes)
			(effects
				(font
					(size 1.27 1.27)
					(thickness 0.15)
				)
			)
		)
		(property "Datasheet" "https://www.murata.com/products/productdetail?partno=GRM155R71H103KA88%23"
			(at 0 0 45)
			(layer "F.Fab")
			(hide yes)
			(effects
				(font
					(size 1.27 1.27)
					(thickness 0.15)
				)
			)
		)
		(property "Author" "Antmicro"
			(at 115.712686 -76.475137 0)
			(layer "B.Fab")
			(hide yes)
			(effects
				(font
					(size 1 1)
					(thickness 0.15)
				)
				(justify mirror)
			)
		)
		(property "Dielectric" "X7R"
			(at 115.712686 -76.475137 0)
			(layer "B.Fab")
			(hide yes)
			(effects
				(font
					(size 1 1)
					(thickness 0.15)
				)
				(justify mirror)
			)
		)
		(property "License" "Apache-2.0"
			(at 115.712686 -76.475137 0)
			(layer "B.Fab")
			(hide yes)
			(effects
				(font
					(size 1 1)
					(thickness 0.15)
				)
				(justify mirror)
			)
		)
		(property "MPN" "GRM155R71H103KA88D"
			(at 115.712686 -76.475137 0)
			(layer "B.Fab")
			(hide yes)
			(effects
				(font
					(size 1 1)
					(thickness 0.15)
				)
				(justify mirror)
			)
		)
		(property "Manufacturer" "Murata"
			(at 115.712686 -76.475137 0)
			(layer "B.Fab")
			(hide yes)
			(effects
				(font
					(size 1 1)
					(thickness 0.15)
				)
				(justify mirror)
			)
		)
		(property "Val" "10n"
			(at 115.712686 -76.475137 0)
			(layer "B.Fab")
			(hide yes)
			(effects
				(font
					(size 1 1)
					(thickness 0.15)
				)
				(justify mirror)
			)
		)
		(property "Voltage" "50V"
			(at 115.712686 -76.475137 0)
			(layer "B.Fab")
			(hide yes)
			(effects
				(font
					(size 1 1)
					(thickness 0.15)
				)
				(justify mirror)
			)
		)
		(sheetname "Serializer")
		(sheetfile "serializer.kicad_sch")
		(attr smd)
		(fp_poly
			(pts
				(xy -0.925 0.47) (xy 0.925 0.47) (xy 0.925 -0.47) (xy -0.925 -0.47)
			)
			(stroke
				(width 0.05)
				(type default)
			)
			(fill none)
			(layer "B.CrtYd")
		)
		(fp_line
			(start -0.494 -0.248)
			(end 0.504 -0.248)
			(stroke
				(width 0.15)
				(type solid)
			)
			(layer "B.Fab")
		)
		(fp_line
			(start -0.494 0.25)
			(end -0.494 -0.248)
			(stroke
				(width 0.15)
				(type solid)
			)
			(layer "B.Fab")
		)
		(fp_line
			(start 0.504 -0.248)
			(end 0.504 0.25)
			(stroke
				(width 0.15)
				(type solid)
			)
			(layer "B.Fab")
		)
		(fp_line
			(start 0.504 0.25)
			(end -0.494 0.25)
			(stroke
				(width 0.15)
				(type solid)
			)
			(layer "B.Fab")
		)
		(fp_text user "${REFERENCE}"
			(at -0.939 -4.599 45)
			(layer "B.Fab")
			(hide yes)
			(effects
				(font
					(size 0.7 0.7)
					(thickness 0.15)
				)
				(justify right bottom mirror)
			)
		)
		(fp_text user "License: Apache-2.0"
			(at -0.939 -5.799 45)
			(layer "B.Fab")
			(hide yes)
			(effects
				(font
					(size 0.7 0.7)
					(thickness 0.15)
				)
				(justify right bottom mirror)
			)
		)
		(fp_text user "Author: Antmicro"
			(at -0.939 -3.399 45)
			(layer "B.Fab")
			(hide yes)
			(effects
				(font
					(size 0.7 0.7)
					(thickness 0.15)
				)
				(justify right bottom mirror)
			)
		)
		(pad "1" smd roundrect
			(at -0.48 0 45)
			(size 0.59 0.64)
			(layers "B.Cu" "B.Paste" "B.Mask")
			(roundrect_rratio 0.25)
			(net 1 "GND")
			(pintype "passive")
		)
		(pad "2" smd roundrect
			(at 0.48 0 45)
			(size 0.59 0.64)
			(layers "B.Cu" "B.Paste" "B.Mask")
			(roundrect_rratio 0.25)
			(net 11 "+1V8")
			(pintype "passive")
		)
	)
	(footprint "antmicro-footprints:C_0402_1005Metric"
		(layer "B.Cu")
		(at 148.090036 99.360037 45)
		(descr "Capacitor SMD 0402")
		(tags "capacitor SMD 0402")
		(property "Reference" "C24"
			(at -3.570889 0.431284 45)
			(layer "B.SilkS")
			(effects
				(font
					(size 0.7 0.7)
					(thickness 0.15)
				)
				(justify right bottom mirror)
			)
		)
		(property "Value" "C_100n_0402"
			(at -1.022927 -2.155213 45)
			(layer "B.Fab")
			(effects
				(font
					(size 0.7 0.7)
					(thickness 0.15)
				)
				(justify right bottom mirror)
			)
		)
		(property "Footprint" "antmicro-footprints:C_0402_1005Metric"
			(at 0 0 45)
			(layer "F.Fab")
			(hide yes)
			(effects
				(font
					(size 1.27 1.27)
					(thickness 0.15)
				)
			)
		)
		(property "Datasheet" "https://www.murata.com/products/productdetail?partno=GRM155R61H104KE14%23"
			(at 0 0 45)
			(layer "F.Fab")
			(hide yes)
			(effects
				(font
					(size 1.27 1.27)
					(thickness 0.15)
				)
			)
		)
		(property "Author" "Antmicro"
			(at 113.632724 -75.613588 0)
			(layer "B.Fab")
			(hide yes)
			(effects
				(font
					(size 1 1)
					(thickness 0.15)
				)
				(justify mirror)
			)
		)
		(property "Dielectric" "X5R"
			(at 113.632724 -75.613588 0)
			(layer "B.Fab")
			(hide yes)
			(effects
				(font
					(size 1 1)
					(thickness 0.15)
				)
				(justify mirror)
			)
		)
		(property "License" "Apache-2.0"
			(at 113.632724 -75.613588 0)
			(layer "B.Fab")
			(hide yes)
			(effects
				(font
					(size 1 1)
					(thickness 0.15)
				)
				(justify mirror)
			)
		)
		(property "MPN" "GRM155R61H104KE14D"
			(at 113.632724 -75.613588 0)
			(layer "B.Fab")
			(hide yes)
			(effects
				(font
					(size 1 1)
					(thickness 0.15)
				)
				(justify mirror)
			)
		)
		(property "Manufacturer" "Murata"
			(at 113.632724 -75.613588 0)
			(layer "B.Fab")
			(hide yes)
			(effects
				(font
					(size 1 1)
					(thickness 0.15)
				)
				(justify mirror)
			)
		)
		(property "Val" "100n"
			(at 113.632724 -75.613588 0)
			(layer "B.Fab")
			(hide yes)
			(effects
				(font
					(size 1 1)
					(thickness 0.15)
				)
				(justify mirror)
			)
		)
		(property "Voltage" "50V"
			(at 113.632724 -75.613588 0)
			(layer "B.Fab")
			(hide yes)
			(effects
				(font
					(size 1 1)
					(thickness 0.15)
				)
				(justify mirror)
			)
		)
		(sheetname "Serializer")
		(sheetfile "serializer.kicad_sch")
		(attr smd)
		(fp_poly
			(pts
				(xy -0.925 0.47) (xy 0.925 0.47) (xy 0.925 -0.47) (xy -0.925 -0.47)
			)
			(stroke
				(width 0.05)
				(type default)
			)
			(fill none)
			(layer "B.CrtYd")
		)
		(fp_line
			(start -0.494 -0.248)
			(end 0.504 -0.248)
			(stroke
				(width 0.15)
				(type solid)
			)
			(layer "B.Fab")
		)
		(fp_line
			(start -0.494 0.25)
			(end -0.494 -0.248)
			(stroke
				(width 0.15)
				(type solid)
			)
			(layer "B.Fab")
		)
		(fp_line
			(start 0.504 -0.248)
			(end 0.504 0.25)
			(stroke
				(width 0.15)
				(type solid)
			)
			(layer "B.Fab")
		)
		(fp_line
			(start 0.504 0.25)
			(end -0.494 0.25)
			(stroke
				(width 0.15)
				(type solid)
			)
			(layer "B.Fab")
		)
		(fp_text user "Author: Antmicro"
			(at -0.939 -3.399 45)
			(layer "B.Fab")
			(hide yes)
			(effects
				(font
					(size 0.7 0.7)
					(thickness 0.15)
				)
				(justify right bottom mirror)
			)
		)
		(fp_text user "License: Apache-2.0"
			(at -0.939 -5.799 45)
			(layer "B.Fab")
			(hide yes)
			(effects
				(font
					(size 0.7 0.7)
					(thickness 0.15)
				)
				(justify right bottom mirror)
			)
		)
		(fp_text user "${REFERENCE}"
			(at -0.939 -4.599 45)
			(layer "B.Fab")
			(hide yes)
			(effects
				(font
					(size 0.7 0.7)
					(thickness 0.15)
				)
				(justify right bottom mirror)
			)
		)
		(pad "1" smd roundrect
			(at -0.48 0 45)
			(size 0.59 0.64)
			(layers "B.Cu" "B.Paste" "B.Mask")
			(roundrect_rratio 0.25)
			(net 1 "GND")
			(pintype "passive")
		)
		(pad "2" smd roundrect
			(at 0.48 0 45)
			(size 0.59 0.64)
			(layers "B.Cu" "B.Paste" "B.Mask")
			(roundrect_rratio 0.25)
			(net 15 "Net-(U6-CAP_VDD)")
			(pintype "passive")
		)
	)
	(footprint "antmicro-footprints:C_0402_1005Metric"
		(layer "B.Cu")
		(at 150.86 102.13 45)
		(descr "Capacitor SMD 0402")
		(tags "capacitor SMD 0402")
		(property "Reference" "C25"
			(at -3.563818 0.367696 45)
			(layer "B.SilkS")
			(effects
				(font
					(size 0.7 0.7)
					(thickness 0.15)
				)
				(justify right bottom mirror)
			)
		)
		(property "Value" "C_10u_0402"
			(at -0.676445 -2.119857 45)
			(layer "B.Fab")
			(effects
				(font
					(size 0.7 0.7)
					(thickness 0.15)
				)
				(justify right bottom mirror)
			)
		)
		(property "Footprint" "antmicro-footprints:C_0402_1005Metric"
			(at 0 0 45)
			(layer "F.Fab")
			(hide yes)
			(effects
				(font
					(size 1.27 1.27)
					(thickness 0.15)
				)
			)
		)
		(property "Datasheet" "https://www.yageo.com/en/Chart/Download/pdf/CC0402MRX5R5BB106"
			(at 0 0 45)
			(layer "F.Fab")
			(hide yes)
			(effects
				(font
					(size 1.27 1.27)
					(thickness 0.15)
				)
			)
		)
		(property "Author" "Antmicro"
			(at 116.402687 -76.760944 0)
			(layer "B.Fab")
			(hide yes)
			(effects
				(font
					(size 1 1)
					(thickness 0.15)
				)
				(justify mirror)
			)
		)
		(property "Dielectric" ""
			(at 116.402687 -76.760944 0)
			(layer "B.Fab")
			(hide yes)
			(effects
				(font
					(size 1 1)
					(thickness 0.15)
				)
				(justify mirror)
			)
		)
		(property "License" "Apache-2.0"
			(at 116.402687 -76.760944 0)
			(layer "B.Fab")
			(hide yes)
			(effects
				(font
					(size 1 1)
					(thickness 0.15)
				)
				(justify mirror)
			)
		)
		(property "MPN" "CC0402MRX5R5BB106"
			(at 116.402687 -76.760944 0)
			(layer "B.Fab")
			(hide yes)
			(effects
				(font
					(size 1 1)
					(thickness 0.15)
				)
				(justify mirror)
			)
		)
		(property "Manufacturer" "YAGEO"
			(at 116.402687 -76.760944 0)
			(layer "B.Fab")
			(hide yes)
			(effects
				(font
					(size 1 1)
					(thickness 0.15)
				)
				(justify mirror)
			)
		)
		(property "Val" "10u"
			(at 116.402687 -76.760944 0)
			(layer "B.Fab")
			(hide yes)
			(effects
				(font
					(size 1 1)
					(thickness 0.15)
				)
				(justify mirror)
			)
		)
		(property "Voltage" ""
			(at 116.402687 -76.760944 0)
			(layer "B.Fab")
			(hide yes)
			(effects
				(font
					(size 1 1)
					(thickness 0.15)
				)
				(justify mirror)
			)
		)
		(sheetname "Serializer")
		(sheetfile "serializer.kicad_sch")
		(attr smd)
		(fp_poly
			(pts
				(xy -0.925 0.47) (xy 0.925 0.47) (xy 0.925 -0.47) (xy -0.925 -0.47)
			)
			(stroke
				(width 0.05)
				(type default)
			)
			(fill none)
			(layer "B.CrtYd")
		)
		(fp_line
			(start -0.494 -0.248)
			(end 0.504 -0.248)
			(stroke
				(width 0.15)
				(type solid)
			)
			(layer "B.Fab")
		)
		(fp_line
			(start -0.494 0.25)
			(end -0.494 -0.248)
			(stroke
				(width 0.15)
				(type solid)
			)
			(layer "B.Fab")
		)
		(fp_line
			(start 0.504 -0.248)
			(end 0.504 0.25)
			(stroke
				(width 0.15)
				(type solid)
			)
			(layer "B.Fab")
		)
		(fp_line
			(start 0.504 0.25)
			(end -0.494 0.25)
			(stroke
				(width 0.15)
				(type solid)
			)
			(layer "B.Fab")
		)
		(fp_text user "${REFERENCE}"
			(at -0.939 -4.599 45)
			(layer "B.Fab")
			(hide yes)
			(effects
				(font
					(size 0.7 0.7)
					(thickness 0.15)
				)
				(justify right bottom mirror)
			)
		)
		(fp_text user "Author: Antmicro"
			(at -0.939 -3.399 45)
			(layer "B.Fab")
			(hide yes)
			(effects
				(font
					(size 0.7 0.7)
					(thickness 0.15)
				)
				(justify right bottom mirror)
			)
		)
		(fp_text user "License: Apache-2.0"
			(at -0.939 -5.799 45)
			(layer "B.Fab")
			(hide yes)
			(effects
				(font
					(size 0.7 0.7)
					(thickness 0.15)
				)
				(justify right bottom mirror)
			)
		)
		(pad "1" smd roundrect
			(at -0.48 0 45)
			(size 0.59 0.64)
			(layers "B.Cu" "B.Paste" "B.Mask")
			(roundrect_rratio 0.25)
			(net 1 "GND")
			(pintype "passive")
		)
		(pad "2" smd roundrect
			(at 0.48 0 45)
			(size 0.59 0.64)
			(layers "B.Cu" "B.Paste" "B.Mask")
			(roundrect_rratio 0.25)
			(net 11 "+1V8")
			(pintype "passive")
		)
	)
	(footprint "antmicro-footprints:C_0402_1005Metric"
		(layer "B.Cu")
		(at 147.39 98.66 45)
		(descr "Capacitor SMD 0402")
		(tags "capacitor SMD 0402")
		(property "Reference" "C26"
			(at -3.592102 0.410122 45)
			(layer "B.SilkS")
			(effects
				(font
					(size 0.7 0.7)
					(thickness 0.15)
				)
				(justify right bottom mirror)
			)
		)
		(property "Value" "C_10u_0402"
			(at -1.022927 -2.155213 45)
			(layer "B.Fab")
			(effects
				(font
					(size 0.7 0.7)
					(thickness 0.15)
				)
				(justify right bottom mirror)
			)
		)
		(property "Footprint" "antmicro-footprints:C_0402_1005Metric"
			(at 0 0 45)
			(layer "F.Fab")
			(hide yes)
			(effects
				(font
					(size 1.27 1.27)
					(thickness 0.15)
				)
			)
		)
		(property "Datasheet" "https://www.yageo.com/en/Chart/Download/pdf/CC0402MRX5R5BB106"
			(at 0 0 45)
			(layer "F.Fab")
			(hide yes)
			(effects
				(font
					(size 1.27 1.27)
					(thickness 0.15)
				)
			)
		)
		(property "Author" "Antmicro"
			(at 112.932687 -75.323623 0)
			(layer "B.Fab")
			(hide yes)
			(effects
				(font
					(size 1 1)
					(thickness 0.15)
				)
				(justify mirror)
			)
		)
		(property "Dielectric" ""
			(at 112.932687 -75.323623 0)
			(layer "B.Fab")
			(hide yes)
			(effects
				(font
					(size 1 1)
					(thickness 0.15)
				)
				(justify mirror)
			)
		)
		(property "License" "Apache-2.0"
			(at 112.932687 -75.323623 0)
			(layer "B.Fab")
			(hide yes)
			(effects
				(font
					(size 1 1)
					(thickness 0.15)
				)
				(justify mirror)
			)
		)
		(property "MPN" "CC0402MRX5R5BB106"
			(at 112.932687 -75.323623 0)
			(layer "B.Fab")
			(hide yes)
			(effects
				(font
					(size 1 1)
					(thickness 0.15)
				)
				(justify mirror)
			)
		)
		(property "Manufacturer" "YAGEO"
			(at 112.932687 -75.323623 0)
			(layer "B.Fab")
			(hide yes)
			(effects
				(font
					(size 1 1)
					(thickness 0.15)
				)
				(justify mirror)
			)
		)
		(property "Val" "10u"
			(at 112.932687 -75.323623 0)
			(layer "B.Fab")
			(hide yes)
			(effects
				(font
					(size 1 1)
					(thickness 0.15)
				)
				(justify mirror)
			)
		)
		(property "Voltage" ""
			(at 112.932687 -75.323623 0)
			(layer "B.Fab")
			(hide yes)
			(effects
				(font
					(size 1 1)
					(thickness 0.15)
				)
				(justify mirror)
			)
		)
		(sheetname "Serializer")
		(sheetfile "serializer.kicad_sch")
		(attr smd)
		(fp_poly
			(pts
				(xy -0.925 0.47) (xy 0.925 0.47) (xy 0.925 -0.47) (xy -0.925 -0.47)
			)
			(stroke
				(width 0.05)
				(type default)
			)
			(fill none)
			(layer "B.CrtYd")
		)
		(fp_line
			(start -0.494 -0.248)
			(end 0.504 -0.248)
			(stroke
				(width 0.15)
				(type solid)
			)
			(layer "B.Fab")
		)
		(fp_line
			(start -0.494 0.25)
			(end -0.494 -0.248)
			(stroke
				(width 0.15)
				(type solid)
			)
			(layer "B.Fab")
		)
		(fp_line
			(start 0.504 -0.248)
			(end 0.504 0.25)
			(stroke
				(width 0.15)
				(type solid)
			)
			(layer "B.Fab")
		)
		(fp_line
			(start 0.504 0.25)
			(end -0.494 0.25)
			(stroke
				(width 0.15)
				(type solid)
			)
			(layer "B.Fab")
		)
		(fp_text user "${REFERENCE}"
			(at -0.939 -4.599 45)
			(layer "B.Fab")
			(hide yes)
			(effects
				(font
					(size 0.7 0.7)
					(thickness 0.15)
				)
				(justify right bottom mirror)
			)
		)
		(fp_text user "License: Apache-2.0"
			(at -0.939 -5.799 45)
			(layer "B.Fab")
			(hide yes)
			(effects
				(font
					(size 0.7 0.7)
					(thickness 0.15)
				)
				(justify right bottom mirror)
			)
		)
		(fp_text user "Author: Antmicro"
			(at -0.939 -3.399 45)
			(layer "B.Fab")
			(hide yes)
			(effects
				(font
					(size 0.7 0.7)
					(thickness 0.15)
				)
				(justify right bottom mirror)
			)
		)
		(pad "1" smd roundrect
			(at -0.48 0 45)
			(size 0.59 0.64)
			(layers "B.Cu" "B.Paste" "B.Mask")
			(roundrect_rratio 0.25)
			(net 1 "GND")
			(pintype "passive")
		)
		(pad "2" smd roundrect
			(at 0.48 0 45)
			(size 0.59 0.64)
			(layers "B.Cu" "B.Paste" "B.Mask")
			(roundrect_rratio 0.25)
			(net 15 "Net-(U6-CAP_VDD)")
			(pintype "passive")
		)
	)
	(footprint "antmicro-footprints:C_0402_1005Metric"
		(layer "B.Cu")
		(at 149.48 100.75 45)
		(descr "Capacitor SMD 0402")
		(tags "capacitor SMD 0402")
		(property "Reference" "C27"
			(at -3.570889 0.403051 45)
			(layer "B.SilkS")
			(effects
				(font
					(size 0.7 0.7)
					(thickness 0.15)
				)
				(justify right bottom mirror)
			)
		)
		(property "Value" "C_10n_0402"
			(at -0.676445 -2.119857 45)
			(layer "B.Fab")
			(effects
				(font
					(size 0.7 0.7)
					(thickness 0.15)
				)
				(justify right bottom mirror)
			)
		)
		(property "Footprint" "antmicro-footprints:C_0402_1005Metric"
			(at 0 0 45)
			(layer "F.Fab")
			(hide yes)
			(effects
				(font
					(size 1.27 1.27)
					(thickness 0.15)
				)
			)
		)
		(property "Datasheet" "https://www.murata.com/products/productdetail?partno=GRM155R71H103KA88%23"
			(at 0 0 45)
			(layer "F.Fab")
			(hide yes)
			(effects
				(font
					(size 1.27 1.27)
					(thickness 0.15)
				)
			)
		)
		(property "Author" "Antmicro"
			(at 115.022686 -76.189329 0)
			(layer "B.Fab")
			(hide yes)
			(effects
				(font
					(size 1 1)
					(thickness 0.15)
				)
				(justify mirror)
			)
		)
		(property "Dielectric" "X7R"
			(at 115.022686 -76.189329 0)
			(layer "B.Fab")
			(hide yes)
			(effects
				(font
					(size 1 1)
					(thickness 0.15)
				)
				(justify mirror)
			)
		)
		(property "License" "Apache-2.0"
			(at 115.022686 -76.189329 0)
			(layer "B.Fab")
			(hide yes)
			(effects
				(font
					(size 1 1)
					(thickness 0.15)
				)
				(justify mirror)
			)
		)
		(property "MPN" "GRM155R71H103KA88D"
			(at 115.022686 -76.189329 0)
			(layer "B.Fab")
			(hide yes)
			(effects
				(font
					(size 1 1)
					(thickness 0.15)
				)
				(justify mirror)
			)
		)
		(property "Manufacturer" "Murata"
			(at 115.022686 -76.189329 0)
			(layer "B.Fab")
			(hide yes)
			(effects
				(font
					(size 1 1)
					(thickness 0.15)
				)
				(justify mirror)
			)
		)
		(property "Val" "10n"
			(at 115.022686 -76.189329 0)
			(layer "B.Fab")
			(hide yes)
			(effects
				(font
					(size 1 1)
					(thickness 0.15)
				)
				(justify mirror)
			)
		)
		(property "Voltage" "50V"
			(at 115.022686 -76.189329 0)
			(layer "B.Fab")
			(hide yes)
			(effects
				(font
					(size 1 1)
					(thickness 0.15)
				)
				(justify mirror)
			)
		)
		(sheetname "Serializer")
		(sheetfile "serializer.kicad_sch")
		(attr smd)
		(fp_poly
			(pts
				(xy -0.925 0.47) (xy 0.925 0.47) (xy 0.925 -0.47) (xy -0.925 -0.47)
			)
			(stroke
				(width 0.05)
				(type default)
			)
			(fill none)
			(layer "B.CrtYd")
		)
		(fp_line
			(start -0.494 -0.248)
			(end 0.504 -0.248)
			(stroke
				(width 0.15)
				(type solid)
			)
			(layer "B.Fab")
		)
		(fp_line
			(start -0.494 0.25)
			(end -0.494 -0.248)
			(stroke
				(width 0.15)
				(type solid)
			)
			(layer "B.Fab")
		)
		(fp_line
			(start 0.504 -0.248)
			(end 0.504 0.25)
			(stroke
				(width 0.15)
				(type solid)
			)
			(layer "B.Fab")
		)
		(fp_line
			(start 0.504 0.25)
			(end -0.494 0.25)
			(stroke
				(width 0.15)
				(type solid)
			)
			(layer "B.Fab")
		)
		(fp_text user "${REFERENCE}"
			(at -0.939 -4.599 45)
			(layer "B.Fab")
			(hide yes)
			(effects
				(font
					(size 0.7 0.7)
					(thickness 0.15)
				)
				(justify right bottom mirror)
			)
		)
		(fp_text user "License: Apache-2.0"
			(at -0.939 -5.799 45)
			(layer "B.Fab")
			(hide yes)
			(effects
				(font
					(size 0.7 0.7)
					(thickness 0.15)
				)
				(justify right bottom mirror)
			)
		)
		(fp_text user "Author: Antmicro"
			(at -0.939 -3.399 45)
			(layer "B.Fab")
			(hide yes)
			(effects
				(font
					(size 0.7 0.7)
					(thickness 0.15)
				)
				(justify right bottom mirror)
			)
		)
		(pad "1" smd roundrect
			(at -0.48 0 45)
			(size 0.59 0.64)
			(layers "B.Cu" "B.Paste" "B.Mask")
			(roundrect_rratio 0.25)
			(net 1 "GND")
			(pintype "passive")
		)
		(pad "2" smd roundrect
			(at 0.48 0 45)
			(size 0.59 0.64)
			(layers "B.Cu" "B.Paste" "B.Mask")
			(roundrect_rratio 0.25)
			(net 11 "+1V8")
			(pintype "passive")
		)
	)
	(footprint "antmicro-footprints:C_0402_1005Metric"
		(layer "B.Cu")
		(at 148.790071 100.060072 45)
		(descr "Capacitor SMD 0402")
		(tags "capacitor SMD 0402")
		(property "Reference" "C23"
			(at -3.563817 0.438305 45)
			(layer "B.SilkS")
			(effects
				(font
					(size 0.7 0.7)
					(thickness 0.15)
				)
				(justify right bottom mirror)
			)
		)
		(property "Value" "C_10n_0402"
			(at -1.022927 -2.155213 45)
			(layer "B.Fab")
			(effects
				(font
					(size 0.7 0.7)
					(thickness 0.15)
				)
				(justify right bottom mirror)
			)
		)
		(property "Footprint" "antmicro-footprints:C_0402_1005Metric"
			(at 0 0 45)
			(layer "F.Fab")
			(hide yes)
			(effects
				(font
					(size 1.27 1.27)
					(thickness 0.15)
				)
			)
		)
		(property "Datasheet" "https://www.murata.com/products/productdetail?partno=GRM155R71H103KA88%23"
			(at 0 0 45)
			(layer "F.Fab")
			(hide yes)
			(effects
				(font
					(size 1.27 1.27)
					(thickness 0.15)
				)
			)
		)
		(property "Author" "Antmicro"
			(at 114.332759 -75.903552 0)
			(layer "B.Fab")
			(hide yes)
			(effects
				(font
					(size 1 1)
					(thickness 0.15)
				)
				(justify mirror)
			)
		)
		(property "Dielectric" "X7R"
			(at 114.332759 -75.903552 0)
			(layer "B.Fab")
			(hide yes)
			(effects
				(font
					(size 1 1)
					(thickness 0.15)
				)
				(justify mirror)
			)
		)
		(property "License" "Apache-2.0"
			(at 114.332759 -75.903552 0)
			(layer "B.Fab")
			(hide yes)
			(effects
				(font
					(size 1 1)
					(thickness 0.15)
				)
				(justify mirror)
			)
		)
		(property "MPN" "GRM155R71H103KA88D"
			(at 114.332759 -75.903552 0)
			(layer "B.Fab")
			(hide yes)
			(effects
				(font
					(size 1 1)
					(thickness 0.15)
				)
				(justify mirror)
			)
		)
		(property "Manufacturer" "Murata"
			(at 114.332759 -75.903552 0)
			(layer "B.Fab")
			(hide yes)
			(effects
				(font
					(size 1 1)
					(thickness 0.15)
				)
				(justify mirror)
			)
		)
		(property "Val" "10n"
			(at 114.332759 -75.903552 0)
			(layer "B.Fab")
			(hide yes)
			(effects
				(font
					(size 1 1)
					(thickness 0.15)
				)
				(justify mirror)
			)
		)
		(property "Voltage" "50V"
			(at 114.332759 -75.903552 0)
			(layer "B.Fab")
			(hide yes)
			(effects
				(font
					(size 1 1)
					(thickness 0.15)
				)
				(justify mirror)
			)
		)
		(sheetname "Serializer")
		(sheetfile "serializer.kicad_sch")
		(attr smd)
		(fp_poly
			(pts
				(xy -0.925 0.47) (xy 0.925 0.47) (xy 0.925 -0.47) (xy -0.925 -0.47)
			)
			(stroke
				(width 0.05)
				(type default)
			)
			(fill none)
			(layer "B.CrtYd")
		)
		(fp_line
			(start -0.494 -0.248)
			(end 0.504 -0.248)
			(stroke
				(width 0.15)
				(type solid)
			)
			(layer "B.Fab")
		)
		(fp_line
			(start -0.494 0.25)
			(end -0.494 -0.248)
			(stroke
				(width 0.15)
				(type solid)
			)
			(layer "B.Fab")
		)
		(fp_line
			(start 0.504 -0.248)
			(end 0.504 0.25)
			(stroke
				(width 0.15)
				(type solid)
			)
			(layer "B.Fab")
		)
		(fp_line
			(start 0.504 0.25)
			(end -0.494 0.25)
			(stroke
				(width 0.15)
				(type solid)
			)
			(layer "B.Fab")
		)
		(fp_text user "${REFERENCE}"
			(at -0.939 -4.599 45)
			(layer "B.Fab")
			(hide yes)
			(effects
				(font
					(size 0.7 0.7)
					(thickness 0.15)
				)
				(justify right bottom mirror)
			)
		)
		(fp_text user "Author: Antmicro"
			(at -0.939 -3.399 45)
			(layer "B.Fab")
			(hide yes)
			(effects
				(font
					(size 0.7 0.7)
					(thickness 0.15)
				)
				(justify right bottom mirror)
			)
		)
		(fp_text user "License: Apache-2.0"
			(at -0.939 -5.799 45)
			(layer "B.Fab")
			(hide yes)
			(effects
				(font
					(size 0.7 0.7)
					(thickness 0.15)
				)
				(justify right bottom mirror)
			)
		)
		(pad "1" smd roundrect
			(at -0.48 0 45)
			(size 0.59 0.64)
			(layers "B.Cu" "B.Paste" "B.Mask")
			(roundrect_rratio 0.25)
			(net 1 "GND")
			(pintype "passive")
		)
		(pad "2" smd roundrect
			(at 0.48 0 45)
			(size 0.59 0.64)
			(layers "B.Cu" "B.Paste" "B.Mask")
			(roundrect_rratio 0.25)
			(net 15 "Net-(U6-CAP_VDD)")
			(pintype "passive")
		)
	)
	(gr_line
		(start 123.65 120.85)
		(end 123.65 77.85)
		(stroke
			(width 0.05)
			(type solid)
		)
		(layer "Edge.Cuts")
	)
	(gr_line
		(start 166.65 120.85)
		(end 123.65 120.85)
		(stroke
			(width 0.05)
			(type solid)
		)
		(layer "Edge.Cuts")
	)
	(gr_line
		(start 123.65 77.85)
		(end 166.65 77.85)
		(stroke
			(width 0.05)
			(type solid)
		)
		(layer "Edge.Cuts")
	)
	(gr_line
		(start 166.65 77.85)
		(end 166.65 120.85)
		(stroke
			(width 0.05)
			(type solid)
		)
		(layer "Edge.Cuts")
	)
	(segment
		(start 153.412347 99.337653)
		(end 153.412347 98.914715)
		(width 0.2)
		(layer "F.Cu")
		(net 1)
	)
	(segment
		(start 146.975 94.775)
		(end 146.975 94.835)
		(width 0.3)
		(layer "F.Cu")
		(net 1)
	)
	(segment
		(start 141.1 116.03)
		(end 141.1 116.875)
		(width 0.2)
		(layer "F.Cu")
		(net 1)
	)
	(segment
		(start 127.575 102.6)
		(end 127.577 102.598)
		(width 0.2)
		(layer "F.Cu")
		(net 1)
	)
	(segment
		(start 145.81 96.45)
		(end 146.42776 97.06776)
		(width 0.3)
		(layer "F.Cu")
		(net 1)
	)
	(segment
		(start 155.2 107.846)
		(end 155.2 108.525)
		(width 0.3)
		(layer "F.Cu")
		(net 1)
	)
	(segment
		(start 152.350589 102.990589)
		(end 152.350589 102.98733)
		(width 0.3)
		(layer "F.Cu")
		(net 1)
	)
	(segment
		(start 151.26 109.085)
		(end 151.26 108.46)
		(width 0.3)
		(layer "F.Cu")
		(net 1)
	)
	(segment
		(start 146.87776 96.11776)
		(end 146.3 95.54)
		(width 0.3)
		(layer "F.Cu")
		(net 1)
	)
	(segment
		(start 126.85 98.1)
		(end 128.35 98.1)
		(width 0.2)
		(layer "F.Cu")
		(net 1)
	)
	(segment
		(start 130.97 80.15)
		(end 131.685 80.15)
		(width 0.2)
		(layer "F.Cu")
		(net 1)
	)
	(segment
		(start 131.749 109.349)
		(end 131.75 109.35)
		(width 0.3)
		(layer "F.Cu")
		(net 1)
	)
	(segment
		(start 127.577 102.598)
		(end 128.35 102.598)
		(width 0.2)
		(layer "F.Cu")
		(net 1)
	)
	(segment
		(start 151.82 112.802)
		(end 151.82 111.705)
		(width 0.2)
		(layer "F.Cu")
		(net 1)
	)
	(segment
		(start 143.670142 80.2)
		(end 143.69 80.180142)
		(width 0.3)
		(layer "F.Cu")
		(net 1)
	)
	(segment
		(start 135.195 80.035)
		(end 134.68 80.55)
		(width 0.3)
		(layer "F.Cu")
		(net 1)
	)
	(segment
		(start 163.127 93.775)
		(end 163.342 93.56)
		(width 0.3)
		(layer "F.Cu")
		(net 1)
	)
	(segment
		(start 161.471 97)
		(end 161.471 97.8)
		(width 0.3)
		(layer "F.Cu")
		(net 1)
	)
	(segment
		(start 151.23 108.24)
		(end 151.23 108.524)
		(width 0.5)
		(layer "F.Cu")
		(net 1)
	)
	(segment
		(start 156.204865 101.675135)
		(end 157.16 100.72)
		(width 0.3)
		(layer "F.Cu")
		(net 1)
	)
	(segment
		(start 150.253768 109.371232)
		(end 150.63 109.747464)
		(width 0.2)
		(layer "F.Cu")
		(net 1)
	)
	(segment
		(start 146.975 94.835)
		(end 147.56776 95.42776)
		(width 0.3)
		(layer "F.Cu")
		(net 1)
	)
	(segment
		(start 138.35 116.85)
		(end 138.35 116.23)
		(width 0.2)
		(layer "F.Cu")
		(net 1)
	)
	(segment
		(start 126.5 116.048)
		(end 126.5 118)
		(width 0.5)
		(layer "F.Cu")
		(net 1)
	)
	(segment
		(start 128.35 95.1)
		(end 129.625 95.1)
		(width 0.2)
		(layer "F.Cu")
		(net 1)
	)
	(segment
		(start 156.57224 100.13224)
		(end 157.16 100.72)
		(width 0.3)
		(layer "F.Cu")
		(net 1)
	)
	(segment
		(start 153.412347 98.914715)
		(end 152.861802 98.36417)
		(width 0.2)
		(layer "F.Cu")
		(net 1)
	)
	(segment
		(start 129.45 93.6)
		(end 130.5 94.65)
		(width 0.2)
		(layer "F.Cu")
		(net 1)
	)
	(segment
		(start 126.775 104.125)
		(end 126.801 104.099)
		(width 0.2)
		(layer "F.Cu")
		(net 1)
	)
	(segment
		(start 151.7 114.875)
		(end 151.175 114.35)
		(width 0.2)
		(layer "F.Cu")
		(net 1)
	)
	(segment
		(start 132.301 106.65)
		(end 131.75 106.099)
		(width 0.2)
		(layer "F.Cu")
		(net 1)
	)
	(segment
		(start 151.175 113.025)
		(end 151.398 112.802)
		(width 0.2)
		(layer "F.Cu")
		(net 1)
	)
	(segment
		(start 147.445 112.72)
		(end 149.1 112.72)
		(width 0.2)
		(layer "F.Cu")
		(net 1)
	)
	(segment
		(start 151.82 111.705)
		(end 151.825 111.7)
		(width 0.2)
		(layer "F.Cu")
		(net 1)
	)
	(segment
		(start 130.075 109.349)
		(end 131.749 109.349)
		(width 0.3)
		(layer "F.Cu")
		(net 1)
	)
	(segment
		(start 126.5 87.652)
		(end 126.5 85.7)
		(width 0.5)
		(layer "F.Cu")
		(net 1)
	)
	(segment
		(start 130.075 113.349)
		(end 131.75 113.35)
		(width 0.3)
		(layer "F.Cu")
		(net 1)
	)
	(segment
		(start 126.8 102.775)
		(end 126.975 102.6)
		(width 0.2)
		(layer "F.Cu")
		(net 1)
	)
	(segment
		(start 126.975 102.6)
		(end 127.575 102.6)
		(width 0.2)
		(layer "F.Cu")
		(net 1)
	)
	(segment
		(start 130.075 106.099)
		(end 131.75 106.099)
		(width 0.3)
		(layer "F.Cu")
		(net 1)
	)
	(segment
		(start 150.63 109.747464)
		(end 150.63 110.28)
		(width 0.2)
		(layer "F.Cu")
		(net 1)
	)
	(segment
		(start 164.435 96.3)
		(end 164.435 97.125)
		(width 0.3)
		(layer "F.Cu")
		(net 1)
	)
	(segment
		(start 152.05 109.34)
		(end 151.515 109.34)
		(width 0.3)
		(layer "F.Cu")
		(net 1)
	)
	(segment
		(start 152.350589 102.98733)
		(end 153.306435 102.031484)
		(width 0.3)
		(layer "F.Cu")
		(net 1)
	)
	(segment
		(start 150.253768 109.371232)
		(end 150.64 109.757464)
		(width 0.2)
		(layer "F.Cu")
		(net 1)
	)
	(segment
		(start 151.175 114.35)
		(end 151.175 113.025)
		(width 0.2)
		(layer "F.Cu")
		(net 1)
	)
	(segment
		(start 153.237347 99.337653)
		(end 153.412347 99.337653)
		(width 0.2)
		(layer "F.Cu")
		(net 1)
	)
	(segment
		(start 126.5 116.048)
		(end 128.5 116.048)
		(width 0.5)
		(layer "F.Cu")
		(net 1)
	)
	(segment
		(start 153.066927 99.508073)
		(end 153.237347 99.337653)
		(width 0.2)
		(layer "F.Cu")
		(net 1)
	)
	(segment
		(start 126.5 87.652)
		(end 128.5 87.652)
		(width 0.5)
		(layer "F.Cu")
		(net 1)
	)
	(segment
		(start 129.625 95.1)
		(end 129.65 95.125)
		(width 0.2)
		(layer "F.Cu")
		(net 1)
	)
	(segment
		(start 127.575 102.6)
		(end 127.681243 102.6)
		(width 0.2)
		(layer "F.Cu")
		(net 1)
	)
	(segment
		(start 150.64 109.757464)
		(end 150.64 111.355)
		(width 0.2)
		(layer "F.Cu")
		(net 1)
	)
	(segment
		(start 159.037 105.927)
		(end 160.191 105.927)
		(width 0.3)
		(layer "F.Cu")
		(net 1)
	)
	(segment
		(start 143.85 116.005)
		(end 143.85 116.85)
		(width 0.2)
		(layer "F.Cu")
		(net 1)
	)
	(segment
		(start 160.208 105.91)
		(end 160.95 105.91)
		(width 0.3)
		(layer "F.Cu")
		(net 1)
	)
	(segment
		(start 152.861802 98.36417)
		(end 153.525972 97.7)
		(width 0.2)
		(layer "F.Cu")
		(net 1)
	)
	(segment
		(start 128.35 93.6)
		(end 129.45 93.6)
		(width 0.2)
		(layer "F.Cu")
		(net 1)
	)
	(segment
		(start 135.83 80.035)
		(end 135.195 80.035)
		(width 0.3)
		(layer "F.Cu")
		(net 1)
	)
	(segment
		(start 130.5 94.65)
		(end 130.5 95.1)
		(width 0.2)
		(layer "F.Cu")
		(net 1)
	)
	(segment
		(start 146.880589 96.520589)
		(end 146.380589 97.020589)
		(width 0.3)
		(layer "F.Cu")
		(net 1)
	)
	(segment
		(start 153.525972 97.7)
		(end 154.25 97.7)
		(width 0.2)
		(layer "F.Cu")
		(net 1)
	)
	(segment
		(start 129.675 96.625)
		(end 128.375 96.625)
		(width 0.2)
		(layer "F.Cu")
		(net 1)
	)
	(segment
		(start 151.398 112.802)
		(end 151.82 112.802)
		(width 0.2)
		(layer "F.Cu")
		(net 1)
	)
	(segment
		(start 151.23 108.24)
		(end 151.23 107.1405)
		(width 0.5)
		(layer "F.Cu")
		(net 1)
	)
	(segment
		(start 155.2 108.525)
		(end 155.375 108.7)
		(width 0.3)
		(layer "F.Cu")
		(net 1)
	)
	(segment
		(start 126.801 104.099)
		(end 128.35 104.099)
		(width 0.2)
		(layer "F.Cu")
		(net 1)
	)
	(segment
		(start 152.114411 95.764411)
		(end 152.114411 96.335589)
		(width 0.2)
		(layer "F.Cu")
		(net 1)
	)
	(segment
		(start 145.75 96.45)
		(end 145.81 96.45)
		(width 0.3)
		(layer "F.Cu")
		(net 1)
	)
	(segment
		(start 147.025 112.3)
		(end 147.445 112.72)
		(width 0.2)
		(layer "F.Cu")
		(net 1)
	)
	(segment
		(start 146.3 95.54)
		(end 146.3 95.45)
		(width 0.3)
		(layer "F.Cu")
		(net 1)
	)
	(segment
		(start 149.1 112.72)
		(end 148.082 112.72)
		(width 0.2)
		(layer "F.Cu")
		(net 1)
	)
	(segment
		(start 148.082 112.72)
		(end 148.075 112.727)
		(width 0.2)
		(layer "F.Cu")
		(net 1)
	)
	(segment
		(start 165.55 85.2)
		(end 165.55 85.989)
		(width 0.3)
		(layer "F.Cu")
		(net 1)
	)
	(segment
		(start 162.525 93.775)
		(end 163.127 93.775)
		(width 0.3)
		(layer "F.Cu")
		(net 1)
	)
	(segment
		(start 151.515 109.34)
		(end 151.26 109.085)
		(width 0.3)
		(layer "F.Cu")
		(net 1)
	)
	(segment
		(start 143.03 80.2)
		(end 143.670142 80.2)
		(width 0.3)
		(layer "F.Cu")
		(net 1)
	)
	(segment
		(start 146.880589 96.120589)
		(end 146.880589 96.520589)
		(width 0.3)
		(layer "F.Cu")
		(net 1)
	)
	(segment
		(start 152.408894 99.508073)
		(end 153.066927 99.508073)
		(width 0.2)
		(layer "F.Cu")
		(net 1)
	)
	(segment
		(start 151.8 95.45)
		(end 152.114411 95.764411)
		(width 0.2)
		(layer "F.Cu")
		(net 1)
	)
	(segment
		(start 132.615 106.65)
		(end 132.301 106.65)
		(width 0.2)
		(layer "F.Cu")
		(net 1)
	)
	(via
		(at 145.75 96.45)
		(size 0.6)
		(drill 0.35)
		(layers "F.Cu" "B.Cu")
		(net 1)
	)
	(via
		(at 138.505 84.375)
		(size 0.6)
		(drill 0.35)
		(layers "F.Cu" "B.Cu")
		(free yes)
		(net 1)
	)
	(via
		(at 144.725 110.575)
		(size 0.6)
		(drill 0.35)
		(layers "F.Cu" "B.Cu")
		(free yes)
		(net 1)
	)
	(via
		(at 164.435 96.3)
		(size 0.6)
		(drill 0.35)
		(layers "F.Cu" "B.Cu")
		(free yes)
		(net 1)
	)
	(via
		(at 165.55 108.15)
		(size 0.6)
		(drill 0.35)
		(layers "F.Cu" "B.Cu")
		(free yes)
		(net 1)
	)
	(via
		(at 146.975 94.775)
		(size 0.6)
		(drill 0.35)
		(layers "F.Cu" "B.Cu")
		(net 1)
	)
	(via
		(at 148.975 101.975)
		(size 0.6)
		(drill 0.35)
		(layers "F.Cu" "B.Cu")
		(net 1)
	)
	(via
		(at 130.5 95.1)
		(size 0.6)
		(drill 0.35)
		(layers "F.Cu" "B.Cu")
		(net 1)
	)
	(via
		(at 143.05 106.2)
		(size 0.6)
		(drill 0.35)
		(layers "F.Cu" "B.Cu")
		(free yes)
		(net 1)
	)
	(via
		(at 147.65 90.3)
		(size 0.6)
		(drill 0.35)
		(layers "F.Cu" "B.Cu")
		(free yes)
		(net 1)
	)
	(via
		(at 154.025 113.025)
		(size 0.6)
		(drill 0.35)
		(layers "F.Cu" "B.Cu")
		(free yes)
		(net 1)
	)
	(via
		(at 138.747943 105.608077)
		(size 0.6)
		(drill 0.35)
		(layers "F.Cu" "B.Cu")
		(free yes)
		(net 1)
	)
	(via
		(at 146.92 84.49)
		(size 0.6)
		(drill 0.35)
		(layers "F.Cu" "B.Cu")
		(free yes)
		(net 1)
	)
	(via
		(at 126.5 85.7)
		(size 0.6)
		(drill 0.35)
		(layers "F.Cu" "B.Cu")
		(net 1)
	)
	(via
		(at 165.875 100.3)
		(size 0.6)
		(drill 0.35)
		(layers "F.Cu" "B.Cu")
		(free yes)
		(net 1)
	)
	(via
		(at 138.15 111.775)
		(size 0.6)
		(drill 0.35)
		(layers "F.Cu" "B.Cu")
		(free yes)
		(net 1)
	)
	(via
		(at 131.75 109.35)
		(size 0.6)
		(drill 0.35)
		(layers "F.Cu" "B.Cu")
		(net 1)
	)
	(via
		(at 147.025 112.3)
		(size 0.6)
		(drill 0.35)
		(layers "F.Cu" "B.Cu")
		(net 1)
	)
	(via
		(at 150.55 94.125)
		(size 0.6)
		(drill 0.35)
		(layers "F.Cu" "B.Cu")
		(free yes)
		(net 1)
	)
	(via
		(at 150.425 95.125)
		(size 0.6)
		(drill 0.35)
		(layers "F.Cu" "B.Cu")
		(free yes)
		(net 1)
	)
	(via
		(at 140.25 100.525)
		(size 0.6)
		(drill 0.35)
		(layers "F.Cu" "B.Cu")
		(free yes)
		(net 1)
	)
	(via
		(at 129.65 95.125)
		(size 0.6)
		(drill 0.35)
		(layers "F.Cu" "B.Cu")
		(net 1)
	)
	(via
		(at 130.075 78.8)
		(size 0.6)
		(drill 0.35)
		(layers "F.Cu" "B.Cu")
		(free yes)
		(net 1)
	)
	(via
		(at 141.675 100.5)
		(size 0.6)
		(drill 0.35)
		(layers "F.Cu" "B.Cu")
		(free yes)
		(net 1)
	)
	(via
		(at 138.35 116.85)
		(size 0.6)
		(drill 0.35)
		(layers "F.Cu" "B.Cu")
		(net 1)
	)
	(via
		(at 137.73 83.55)
		(size 0.6)
		(drill 0.35)
		(layers "F.Cu" "B.Cu")
		(free yes)
		(net 1)
	)
	(via
		(at 153.306435 102.031484)
		(size 0.6)
		(drill 0.35)
		(layers "F.Cu" "B.Cu")
		(net 1)
	)
	(via
		(at 156.275 105.925)
		(size 0.6)
		(drill 0.35)
		(layers "F.Cu" "B.Cu")
		(free yes)
		(net 1)
	)
	(via
		(at 149.825 94.575)
		(size 0.6)
		(drill 0.35)
		(layers "F.Cu" "B.Cu")
		(free yes)
		(net 1)
	)
	(via
		(at 160.95 105.91)
		(size 0.6)
		(drill 0.35)
		(layers "F.Cu" "B.Cu")
		(net 1)
	)
	(via
		(at 131.75 113.35)
		(size 0.6)
		(drill 0.35)
		(layers "F.Cu" "B.Cu")
		(net 1)
	)
	(via
		(at 138.6 106.5)
		(size 0.6)
		(drill 0.35)
		(layers "F.Cu" "B.Cu")
		(free yes)
		(net 1)
	)
	(via
		(at 145.56 78.58)
		(size 0.6)
		(drill 0.35)
		(layers "F.Cu" "B.Cu")
		(free yes)
		(net 1)
	)
	(via
		(at 125.5 96.525)
		(size 0.6)
		(drill 0.35)
		(layers "F.Cu" "B.Cu")
		(free yes)
		(net 1)
	)
	(via
		(at 126.85 98.1)
		(size 0.6)
		(drill 0.35)
		(layers "F.Cu" "B.Cu")
		(net 1)
	)
	(via
		(at 130.475 96.95)
		(size 0.6)
		(drill 0.35)
		(layers "F.Cu" "B.Cu")
		(free yes)
		(net 1)
	)
	(via
		(at 163.55 111.35)
		(size 0.6)
		(drill 0.35)
		(layers "F.Cu" "B.Cu")
		(net 1)
	)
	(via
		(at 141.225 103.175)
		(size 0.6)
		(drill 0.35)
		(layers "F.Cu" "B.Cu")
		(free yes)
		(net 1)
	)
	(via
		(at 129.05 84.86)
		(size 0.6)
		(drill 0.35)
		(layers "F.Cu" "B.Cu")
		(net 1)
	)
	(via
		(at 131.155 86.225)
		(size 0.6)
		(drill 0.35)
		(layers "F.Cu" "B.Cu")
		(free yes)
		(net 1)
	)
	(via
		(at 126.725 99.7)
		(size 0.6)
		(drill 0.35)
		(layers "F.Cu" "B.Cu")
		(free yes)
		(net 1)
	)
	(via
		(at 147.975 108.075)
		(size 0.6)
		(drill 0.35)
		(layers "F.Cu" "B.Cu")
		(free yes)
		(net 1)
	)
	(via
		(at 139.47 79.950142)
		(size 0.6)
		(drill 0.35)
		(layers "F.Cu" "B.Cu")
		(free yes)
		(net 1)
	)
	(via
		(at 141.225 104.7)
		(size 0.6)
		(drill 0.35)
		(layers "F.Cu" "B.Cu")
		(free yes)
		(net 1)
	)
	(via
		(at 140.781051 106.473005)
		(size 0.6)
		(drill 0.35)
		(layers "F.Cu" "B.Cu")
		(free yes)
		(net 1)
	)
	(via
		(at 165.875 99.475)
		(size 0.6)
		(drill 0.35)
		(layers "F.Cu" "B.Cu")
		(free yes)
		(net 1)
	)
	(via
		(at 163.65 102.75)
		(size 0.6)
		(drill 0.35)
		(layers "F.Cu" "B.Cu")
		(free yes)
		(net 1)
	)
	(via
		(at 129.675 96.625)
		(size 0.6)
		(drill 0.35)
		(layers "F.Cu" "B.Cu")
		(net 1)
	)
	(via
		(at 133.5 97.025)
		(size 0.6)
		(drill 0.35)
		(layers "F.Cu" "B.Cu")
		(free yes)
		(net 1)
	)
	(via
		(at 147.7 84.48)
		(size 0.6)
		(drill 0.35)
		(layers "F.Cu" "B.Cu")
		(free yes)
		(net 1)
	)
	(via
		(at 137.85 100.525)
		(size 0.6)
		(drill 0.35)
		(layers "F.Cu" "B.Cu")
		(free yes)
		(net 1)
	)
	(via
		(at 150.253768 109.371232)
		(size 0.6)
		(drill 0.35)
		(layers "F.Cu" "B.Cu")
		(net 1)
	)
	(via
		(at 136.749499 105.577581)
		(size 0.6)
		(drill 0.35)
		(layers "F.Cu" "B.Cu")
		(free yes)
		(net 1)
	)
	(via
		(at 135.805 85.175)
		(size 0.6)
		(drill 0.35)
		(layers "F.Cu" "B.Cu")
		(free yes)
		(net 1)
	)
	(via
		(at 133.55 98.7)
		(size 0.6)
		(drill 0.35)
		(layers "F.Cu" "B.Cu")
		(free yes)
		(net 1)
	)
	(via
		(at 146.97 85.27)
		(size 0.6)
		(drill 0.35)
		(layers "F.Cu" "B.Cu")
		(free yes)
		(net 1)
	)
	(via
		(at 154.25 97.7)
		(size 0.6)
		(drill 0.35)
		(layers "F.Cu" "B.Cu")
		(net 1)
	)
	(via
		(at 165.925 101.075)
		(size 0.6)
		(drill 0.35)
		(layers "F.Cu" "B.Cu")
		(free yes)
		(net 1)
	)
	(via
		(at 151.8 95.45)
		(size 0.6)
		(drill 0.35)
		(layers "F.Cu" "B.Cu")
		(net 1)
	)
	(via
		(at 143.025 104.725)
		(size 0.6)
		(drill 0.35)
		(layers "F.Cu" "B.Cu")
		(free yes)
		(net 1)
	)
	(via
		(at 147.65 101.9)
		(size 0.6)
		(drill 0.35)
		(layers "F.Cu" "B.Cu")
		(net 1)
	)
	(via
		(at 144.69 93.19)
		(size 0.6)
		(drill 0.35)
		(layers "F.Cu" "B.Cu")
		(free yes)
		(net 1)
	)
	(via
		(at 126.8 102.775)
		(size 0.6)
		(drill 0.35)
		(layers "F.Cu" "B.Cu")
		(net 1)
	)
	(via
		(at 145.98 84.49)
		(size 0.6)
		(drill 0.35)
		(layers "F.Cu" "B.Cu")
		(free yes)
		(net 1)
	)
	(via
		(at 148.35 102.6)
		(size 0.6)
		(drill 0.35)
		(layers "F.Cu" "B.Cu")
		(net 1)
	)
	(via
		(at 143.752536 101.199582)
		(size 0.6)
		(drill 0.35)
		(layers "F.Cu" "B.Cu")
		(free yes)
		(net 1)
	)
	(via
		(at 162.525 93.775)
		(size 0.6)
		(drill 0.35)
		(layers "F.Cu" "B.Cu")
		(free yes)
		(net 1)
	)
	(via
		(at 138.505 83.55)
		(size 0.6)
		(drill 0.35)
		(layers "F.Cu" "B.Cu")
		(free yes)
		(net 1)
	)
	(via
		(at 147.525 100.6)
		(size 0.6)
		(drill 0.35)
		(layers "F.Cu" "B.Cu")
		(net 1)
	)
	(via
		(at 151.825 111.7)
		(size 0.6)
		(drill 0.35)
		(layers "F.Cu" "B.Cu")
		(net 1)
	)
	(via
		(at 131.06 88.06)
		(size 0.6)
		(drill 0.35)
		(layers "F.Cu" "B.Cu")
		(free yes)
		(net 1)
	)
	(via
		(at 146.3 95.45)
		(size 0.6)
		(drill 0.35)
		(layers "F.Cu" "B.Cu")
		(net 1)
	)
	(via
		(at 143.03 80.2)
		(size 0.6)
		(drill 0.35)
		(layers "F.Cu" "B.Cu")
		(free yes)
		(net 1)
	)
	(via
		(at 146.2 101.825)
		(size 0.6)
		(drill 0.35)
		(layers "F.Cu" "B.Cu")
		(net 1)
	)
	(via
		(at 137.73 84.375)
		(size 0.6)
		(drill 0.35)
		(layers "F.Cu" "B.Cu")
		(free yes)
		(net 1)
	)
	(via
		(at 126.5 118)
		(size 0.6)
		(drill 0.35)
		(layers "F.Cu" "B.Cu")
		(net 1)
	)
	(via
		(at 146.9 101.225)
		(size 0.6)
		(drill 0.35)
		(layers "F.Cu" "B.Cu")
		(net 1)
	)
	(via
		(at 141.1 116.875)
		(size 0.6)
		(drill 0.35)
		(layers "F.Cu" "B.Cu")
		(net 1)
	)
	(via
		(at 156.75 116.725)
		(size 0.6)
		(drill 0.35)
		(layers "F.Cu" "B.Cu")
		(free yes)
		(net 1)
	)
	(via
		(at 147.075 93.15)
		(size 0.6)
		(drill 0.35)
		(layers "F.Cu" "B.Cu")
		(free yes)
		(net 1)
	)
	(via
		(at 147.65 103.2)
		(size 0.6)
		(drill 0.35)
		(layers "F.Cu" "B.Cu")
		(net 1)
	)
	(via
		(at 146.95 102.5)
		(size 0.6)
		(drill 0.35)
		(layers "F.Cu" "B.Cu")
		(net 1)
	)
	(via
		(at 138.79 88.19)
		(size 0.6)
		(drill 0.35)
		(layers "F.Cu" "B.Cu")
		(free yes)
		(net 1)
	)
	(via
		(at 132.792503 96.95)
		(size 0.6)
		(drill 0.35)
		(layers "F.Cu" "B.Cu")
		(free yes)
		(net 1)
	)
	(via
		(at 135.225 106.7)
		(size 0.6)
		(drill 0.35)
		(layers "F.Cu" "B.Cu")
		(free yes)
		(net 1)
	)
	(via
		(at 148.275 101.275)
		(size 0.6)
		(drill 0.35)
		(layers "F.Cu" "B.Cu")
		(net 1)
	)
	(via
		(at 165.55 85.2)
		(size 0.6)
		(drill 0.35)
		(layers "F.Cu" "B.Cu")
		(net 1)
	)
	(via
		(at 126.775 104.125)
		(size 0.6)
		(drill 0.35)
		(layers "F.Cu" "B.Cu")
		(net 1)
	)
	(via
		(at 143.85 116.85)
		(size 0.6)
		(drill 0.35)
		(layers "F.Cu" "B.Cu")
		(net 1)
	)
	(via
		(at 153.412347 99.337653)
		(size 0.6)
		(drill 0.35)
		(layers "F.Cu" "B.Cu")
		(net 1)
	)
	(via
		(at 131.75 106.099)
		(size 0.6)
		(drill 0.35)
		(layers "F.Cu" "B.Cu")
		(net 1)
	)
	(via
		(at 160.425 113.9)
		(size 0.6)
		(drill 0.35)
		(layers "F.Cu" "B.Cu")
		(free yes)
		(net 1)
	)
	(via
		(at 165.9 101.825)
		(size 0.6)
		(drill 0.35)
		(layers "F.Cu" "B.Cu")
		(free yes)
		(net 1)
	)
	(via
		(at 128.5 87.652)
		(size 0.6)
		(drill 0.35)
		(layers "F.Cu" "B.Cu")
		(net 1)
	)
	(via
		(at 147.71 85.28)
		(size 0.6)
		(drill 0.35)
		(layers "F.Cu" "B.Cu")
		(free yes)
		(net 1)
	)
	(via
		(at 128.5 116.048)
		(size 0.6)
		(drill 0.35)
		(layers "F.Cu" "B.Cu")
		(net 1)
	)
	(via
		(at 161.471 97)
		(size 0.6)
		(drill 0.35)
		(layers "F.Cu" "B.Cu")
		(free yes)
		(net 1)
	)
	(via
		(at 139.06 78.69)
		(size 0.6)
		(drill 0.35)
		(layers "F.Cu" "B.Cu")
		(free yes)
		(net 1)
	)
	(via
		(at 155.375 108.7)
		(size 0.6)
		(drill 0.35)
		(layers "F.Cu" "B.Cu")
		(net 1)
	)
	(via
		(at 159.025 113.775)
		(size 0.6)
		(drill 0.35)
		(layers "F.Cu" "B.Cu")
		(free yes)
		(net 1)
	)
	(via
		(at 126.7 100.85)
		(size 0.6)
		(drill 0.35)
		(layers "F.Cu" "B.Cu")
		(free yes)
		(net 1)
	)
	(via
		(at 151.26 108.46)
		(size 0.6)
		(drill 0.35)
		(layers "F.Cu" "B.Cu")
		(net 1)
	)
	(via
		(at 158.7 109.35)
		(size 0.6)
		(drill 0.35)
		(layers "F.Cu" "B.Cu")
		(free yes)
		(net 1)
	)
	(via
		(at 130.97 80.15)
		(size 0.6)
		(drill 0.35)
		(layers "F.Cu" "B.Cu")
		(net 1)
	)
	(via
		(at 134.68 80.55)
		(size 0.6)
		(drill 0.35)
		(layers "F.Cu" "B.Cu")
		(net 1)
	)
	(via
		(at 157.16 100.72)
		(size 0.6)
		(drill 0.35)
		(layers "F.Cu" "B.Cu")
		(net 1)
	)
	(via
		(at 138.58 85.15)
		(size 0.6)
		(drill 0.35)
		(layers "F.Cu" "B.Cu")
		(free yes)
		(net 1)
	)
	(via
		(at 144.3 85.1)
		(size 0.6)
		(drill 0.35)
		(layers "F.Cu" "B.Cu")
		(free yes)
		(net 1)
	)
	(segment
		(start 149.830589 101.779411)
		(end 149.140589 101.089411)
		(width 0.3)
		(layer "B.Cu")
		(net 1)
	)
	(segment
		(start 149.140589 101.089411)
		(end 148.45066 100.399483)
		(width 0.3)
		(layer "B.Cu")
		(net 1)
	)
	(segment
		(start 147.750625 99.699448)
		(end 147.050589 98.999411)
		(width 0.3)
		(layer "B.Cu")
		(net 1)
	)
	(segment
		(start 150.520589 102.469411)
		(end 149.830589 101.779411)
		(width 0.3)
		(layer "B.Cu")
		(net 1)
	)
	(segment
		(start 148.45066 100.399483)
		(end 147.750625 99.699448)
		(width 0.3)
		(layer "B.Cu")
		(net 1)
	)
	(segment
		(start 144.75 81.150142)
		(end 144.96 81.360142)
		(width 0.3)
		(layer "F.Cu")
		(net 2)
	)
	(segment
		(start 164.347 89.625)
		(end 164.31 89.662)
		(width 0.3)
		(layer "F.Cu")
		(net 2)
	)
	(segment
		(start 136.83 80.035)
		(end 136.83 81.4)
		(width 0.3)
		(layer "F.Cu")
		(net 2)
	)
	(segment
		(start 164.454 100.046)
		(end 164.525 99.975)
		(width 0.5)
		(layer "F.Cu")
		(net 2)
	)
	(segment
		(start 164.31 89.662)
		(end 164.31 87.96)
		(width 0.5)
		(layer "F.Cu")
		(net 2)
	)
	(segment
		(start 165.5265 91.4)
		(end 164.3235 91.4)
		(width 0.3)
		(layer "F.Cu")
		(net 2)
	)
	(segment
		(start 165.5515 87.875)
		(end 164.3485 87.875)
		(width 0.3)
		(layer "F.Cu")
		(net 2)
	)
	(segment
		(start 164.025 99)
		(end 164.75 99)
		(width 0.3)
		(layer "F.Cu")
		(net 2)
	)
	(segment
		(start 165.675 98.125)
		(end 165.7 98.1)
		(width 0.5)
		(layer "F.Cu")
		(net 2)
	)
	(segment
		(start 163.45 87.1)
		(end 163.45 86.223)
		(width 0.5)
		(layer "F.Cu")
		(net 2)
	)
	(segment
		(start 162.825 85.598)
		(end 163.076 85.849)
		(width 0.3)
		(layer "F.Cu")
		(net 2)
	)
	(segment
		(start 165.7 91.525)
		(end 165.55 91.375)
		(width 0.5)
		(layer "F.Cu")
		(net 2)
	)
	(segment
		(start 165.675 98.125)
		(end 165.055 98.745)
		(width 0.3)
		(layer "F.Cu")
		(net 2)
	)
	(segment
		(start 164.775 99.025)
		(end 164.775 99.925)
		(width 0.5)
		(layer "F.Cu")
		(net 2)
	)
	(segment
		(start 165.55 89.625)
		(end 164.347 89.625)
		(width 0.3)
		(layer "F.Cu")
		(net 2)
	)
	(segment
		(start 165.055 98.745)
		(end 164.435 98.125)
		(width 0.3)
		(layer "F.Cu")
		(net 2)
	)
	(segment
		(start 139.5 116.45)
		(end 139.5 118)
		(width 0.5)
		(layer "F.Cu")
		(net 2)
	)
	(segment
		(start 163.101 100.046)
		(end 164.454 100.046)
		(width 0.5)
		(layer "F.Cu")
		(net 2)
	)
	(segment
		(start 164.75 99)
		(end 164.775 99.025)
		(width 0.3)
		(layer "F.Cu")
		(net 2)
	)
	(segment
		(start 165.675 98.125)
		(end 164.775 99.025)
		(width 0.5)
		(layer "F.Cu")
		(net 2)
	)
	(segment
		(start 163.45 86.223)
		(end 163.076 85.849)
		(width 0.5)
		(layer "F.Cu")
		(net 2)
	)
	(segment
		(start 165.7 98.1)
		(end 165.7 91.525)
		(width 0.5)
		(layer "F.Cu")
		(net 2)
	)
	(segment
		(start 164.31 87.96)
		(end 163.45 87.1)
		(width 0.5)
		(layer "F.Cu")
		(net 2)
	)
	(segment
		(start 144.75 80.167642)
		(end 144.75 81.150142)
		(width 0.3)
		(layer "F.Cu")
		(net 2)
	)
	(segment
		(start 162.08 85.598)
		(end 162.825 85.598)
		(width 0.3)
		(layer "F.Cu")
		(net 2)
	)
	(via
		(at 137.79 82.38)
		(size 0.6)
		(drill 0.35)
		(layers "F.Cu" "B.Cu")
		(free yes)
		(net 2)
	)
	(via
		(at 165.55 89.625)
		(size 0.6)
		(drill 0.35)
		(layers "F.Cu" "B.Cu")
		(net 2)
	)
	(via
		(at 165.55 91.375)
		(size 0.6)
		(drill 0.35)
		(layers "F.Cu" "B.Cu")
		(net 2)
	)
	(via
		(at 139.5 118)
		(size 0.6)
		(drill 0.35)
		(layers "F.Cu" "B.Cu")
		(net 2)
	)
	(via
		(at 143.25 81.35)
		(size 0.6)
		(drill 0.35)
		(layers "F.Cu" "B.Cu")
		(free yes)
		(net 2)
	)
	(via
		(at 165.55 88.75)
		(size 0.6)
		(drill 0.35)
		(layers "F.Cu" "B.Cu")
		(net 2)
	)
	(via
		(at 165.55 87.875)
		(size 0.6)
		(drill 0.35)
		(layers "F.Cu" "B.Cu")
		(net 2)
	)
	(via
		(at 165.55 90.5)
		(size 0.6)
		(drill 0.35)
		(layers "F.Cu" "B.Cu")
		(net 2)
	)
	(via
		(at 146.05 81.35)
		(size 0.6)
		(drill 0.35)
		(layers "F.Cu" "B.Cu")
		(free yes)
		(net 2)
	)
	(via
		(at 146.05 82.180142)
		(size 0.6)
		(drill 0.35)
		(layers "F.Cu" "B.Cu")
		(free yes)
		(net 2)
	)
	(via
		(at 135.55 81.4)
		(size 0.6)
		(drill 0.35)
		(layers "F.Cu" "B.Cu")
		(free yes)
		(net 2)
	)
	(via
		(at 137.95 81.4)
		(size 0.6)
		(drill 0.35)
		(layers "F.Cu" "B.Cu")
		(free yes)
		(net 2)
	)
	(via
		(at 145.35 81.35)
		(size 0.6)
		(drill 0.35)
		(layers "F.Cu" "B.Cu")
		(free yes)
		(net 2)
	)
	(via
		(at 143.95 81.35)
		(size 0.6)
		(drill 0.35)
		(layers "F.Cu" "B.Cu")
		(free yes)
		(net 2)
	)
	(via
		(at 144.65 81.35)
		(size 0.6)
		(drill 0.35)
		(layers "F.Cu" "B.Cu")
		(free yes)
		(net 2)
	)
	(via
		(at 134.75 81.4)
		(size 0.6)
		(drill 0.35)
		(layers "F.Cu" "B.Cu")
		(free yes)
		(net 2)
	)
	(via
		(at 137.15 81.4)
		(size 0.6)
		(drill 0.35)
		(layers "F.Cu" "B.Cu")
		(free yes)
		(net 2)
	)
	(via
		(at 136.35 81.4)
		(size 0.6)
		(drill 0.35)
		(layers "F.Cu" "B.Cu")
		(free yes)
		(net 2)
	)
	(via
		(at 164.025 99)
		(size 0.6)
		(drill 0.35)
		(layers "F.Cu" "B.Cu")
		(net 2)
	)
	(segment
		(start 159.75 110.3)
		(end 159.75 118.75)
		(width 0.3)
		(layer "B.Cu")
		(net 2)
	)
	(segment
		(start 140.75 119.25)
		(end 139.5 118)
		(width 0.3)
		(layer "B.Cu")
		(net 2)
	)
	(segment
		(start 146.24 81.340142)
		(end 146.165 81.340142)
		(width 0.8)
		(layer "B.Cu")
		(net 2)
	)
	(segment
		(start 137.855 82.35)
		(end 137.855 81.45)
		(width 0.8)
		(layer "B.Cu")
		(net 2)
	)
	(segment
		(start 164.85 99.825)
		(end 164.85 105.2)
		(width 0.3)
		(layer "B.Cu")
		(net 2)
	)
	(segment
		(start 159.25 119.25)
		(end 140.75 119.25)
		(width 0.3)
		(layer "B.Cu")
		(net 2)
	)
	(segment
		(start 164.85 105.2)
		(end 159.75 110.3)
		(width 0.3)
		(layer "B.Cu")
		(net 2)
	)
	(segment
		(start 164.025 99)
		(end 164.85 99.825)
		(width 0.3)
		(layer "B.Cu")
		(net 2)
	)
	(segment
		(start 137.83 81.425)
		(end 137.755 81.425)
		(width 0.8)
		(layer "B.Cu")
		(net 2)
	)
	(segment
		(start 159.75 118.75)
		(end 159.25 119.25)
		(width 0.3)
		(layer "B.Cu")
		(net 2)
	)
	(segment
		(start 146.265 81.865142)
		(end 146.815 81.315142)
		(width 0.8)
		(layer "B.Cu")
		(net 2)
	)
	(segment
		(start 146.165 81.340142)
		(end 146.04 81.465142)
		(width 0.8)
		(layer "B.Cu")
		(net 2)
	)
	(segment
		(start 137.855 81.95)
		(end 138.405 81.4)
		(width 0.8)
		(layer "B.Cu")
		(net 2)
	)
	(segment
		(start 146.265 82.265142)
		(end 146.265 81.365142)
		(width 0.8)
		(layer "B.Cu")
		(net 2)
	)
	(segment
		(start 137.855 82.35)
		(end 137.855 81.95)
		(width 0.8)
		(layer "B.Cu")
		(net 2)
	)
	(segment
		(start 136.005 81.4)
		(end 138.405 81.4)
		(width 0.8)
		(layer "B.Cu")
		(net 2)
	)
	(segment
		(start 144.415 81.315142)
		(end 146.815 81.315142)
		(width 0.8)
		(layer "B.Cu")
		(net 2)
	)
	(segment
		(start 137.755 81.425)
		(end 137.63 81.55)
		(width 0.8)
		(layer "B.Cu")
		(net 2)
	)
	(segment
		(start 165.55 87.875)
		(end 165.55 91.375)
		(width 0.8)
		(layer "B.Cu")
		(net 2)
	)
	(segment
		(start 137.855 81.45)
		(end 137.83 81.425)
		(width 0.8)
		(layer "B.Cu")
		(net 2)
	)
	(segment
		(start 146.265 81.365142)
		(end 146.24 81.340142)
		(width 0.8)
		(layer "B.Cu")
		(net 2)
	)
	(segment
		(start 132.48 84.397)
		(end 131.12 84.397)
		(width 0.3)
		(layer "F.Cu")
		(net 3)
	)
	(segment
		(start 131.745 85.365)
		(end 131.12 85.365)
		(width 0.3)
		(layer "F.Cu")
		(net 4)
	)
	(segment
		(start 132.604 86.224)
		(end 131.745 85.365)
		(width 0.3)
		(layer "F.Cu")
		(net 4)
	)
	(segment
		(start 159.3 101.947)
		(end 160.501 101.947)
		(width 0.3)
		(layer "F.Cu")
		(net 5)
	)
	(segment
		(start 160.115 102.915)
		(end 159.3 102.915)
		(width 0.3)
		(layer "F.Cu")
		(net 6)
	)
	(segment
		(start 160.5 103.3)
		(end 160.115 102.915)
		(width 0.3)
		(layer "F.Cu")
		(net 6)
	)
	(segment
		(start 135.102 87.947)
		(end 134.954 87.799)
		(width 0.3)
		(layer "F.Cu")
		(net 7)
	)
	(segment
		(start 134.954 87.799)
		(end 134.954 86.95)
		(width 0.3)
		(layer "F.Cu")
		(net 7)
	)
	(segment
		(start 136.58 86.127)
		(end 134.954 86.127)
		(width 0.3)
		(layer "F.Cu")
		(net 7)
	)
	(segment
		(start 131.685 81.196)
		(end 130.97 81.196)
		(width 0.2)
		(layer "F.Cu")
		(net 7)
	)
	(segment
		(start 136.929 87.947)
		(end 135.102 87.947)
		(width 0.3)
		(layer "F.Cu")
		(net 7)
	)
	(segment
		(start 134.954 86.127)
		(end 134.954 86.95)
		(width 0.3)
		(layer "F.Cu")
		(net 7)
	)
	(via
		(at 137.03 86.95)
		(size 0.6)
		(drill 0.35)
		(layers "F.Cu" "B.Cu")
		(net 7)
	)
	(via
		(at 130.97 81.196)
		(size 0.6)
		(drill 0.35)
		(layers "F.Cu" "B.Cu")
		(net 7)
	)
	(segment
		(start 133.53 86.95)
		(end 130.97 84.39)
		(width 0.2)
		(layer "B.Cu")
		(net 7)
	)
	(segment
		(start 130.97 84.39)
		(end 130.97 81.196)
		(width 0.2)
		(layer "B.Cu")
		(net 7)
	)
	(segment
		(start 137.03 86.95)
		(end 133.53 86.95)
		(width 0.2)
		(layer "B.Cu")
		(net 7)
	)
	(segment
		(start 162.819 103.68)
		(end 162.7 103.799)
		(width 0.3)
		(layer "F.Cu")
		(net 8)
	)
	(segment
		(start 162.46 98.8)
		(end 161.471 98.8)
		(width 0.3)
		(layer "F.Cu")
		(net 8)
	)
	(segment
		(start 165.3 103.68)
		(end 164.325 103.68)
		(width 0.3)
		(layer "F.Cu")
		(net 8)
	)
	(segment
		(start 164.325 103.68)
		(end 162.819 103.68)
		(width 0.3)
		(layer "F.Cu")
		(net 8)
	)
	(via
		(at 164.2 104.5)
		(size 0.6)
		(drill 0.35)
		(layers "F.Cu" "B.Cu")
		(net 8)
	)
	(via
		(at 162.46 98.8)
		(size 0.6)
		(drill 0.35)
		(layers "F.Cu" "B.Cu")
		(net 8)
	)
	(segment
		(start 162.47 102.795)
		(end 164.175 104.5)
		(width 0.3)
		(layer "B.Cu")
		(net 8)
	)
	(segment
		(start 164.175 104.5)
		(end 164.2 104.5)
		(width 0.3)
		(layer "B.Cu")
		(net 8)
	)
	(segment
		(start 162.46 98.8)
		(end 162.47 98.81)
		(width 0.3)
		(layer "B.Cu")
		(net 8)
	)
	(segment
		(start 162.47 98.81)
		(end 162.47 102.795)
		(width 0.3)
		(layer "B.Cu")
		(net 8)
	)
	(segment
		(start 131.675 113.875)
		(end 130.951 113.875)
		(width 0.2)
		(layer "F.Cu")
		(net 9)
	)
	(segment
		(start 153.01 109.34)
		(end 153.43 108.92)
		(width 0.3)
		(layer "F.Cu")
		(net 9)
	)
	(segment
		(start 129.099 114.099)
		(end 128.35 114.099)
		(width 0.2)
		(layer "F.Cu")
		(net 9)
	)
	(segment
		(start 128.35 113.599)
		(end 127.001 113.599)
		(width 0.3)
		(layer "F.Cu")
		(net 9)
	)
	(segment
		(start 130.075 114.349)
		(end 129.349 114.349)
		(width 0.2)
		(layer "F.Cu")
		(net 9)
	)
	(segment
		(start 130.925 113.849)
		(end 130.075 113.849)
		(width 0.2)
		(layer "F.Cu")
		(net 9)
	)
	(segment
		(start 153.014 110.5)
		(end 153.014 109.344)
		(width 0.3)
		(layer "F.Cu")
		(net 9)
	)
	(segment
		(start 129.399 113.599)
		(end 128.35 113.599)
		(width 0.2)
		(layer "F.Cu")
		(net 9)
	)
	(segment
		(start 124.55 112.85)
		(end 124.55 91.4)
		(width 1)
		(layer "F.Cu")
		(net 9)
	)
	(segment
		(start 131.8625 114.0875)
		(end 131.601 114.349)
		(width 0.2)
		(layer "F.Cu")
		(net 9)
	)
	(segment
		(start 127.1 113.9)
		(end 125.6 113.9)
		(width 1)
		(layer "F.Cu")
		(net 9)
	)
	(segment
		(start 129.649 113.849)
		(end 129.399 113.599)
		(width 0.2)
		(layer "F.Cu")
		(net 9)
	)
	(segment
		(start 131.8625 114.0625)
		(end 131.675 113.875)
		(width 0.2)
		(layer "F.Cu")
		(net 9)
	)
	(segment
		(start 142.25 116.45)
		(end 142.25 118)
		(width 0.5)
		(layer "F.Cu")
		(net 9)
	)
	(segment
		(start 146.55 115.515)
		(end 146.55 114.875)
		(width 0.2)
		(layer "F.Cu")
		(net 9)
	)
	(segment
		(start 131.8625 114.0875)
		(end 131.8625 114.0625)
		(width 0.2)
		(layer "F.Cu")
		(net 9)
	)
	(segment
		(start 153.014 109.344)
		(end 153.01 109.34)
		(width 0.3)
		(layer "F.Cu")
		(net 9)
	)
	(segment
		(start 129.349 114.349)
		(end 129.099 114.099)
		(width 0.2)
		(layer "F.Cu")
		(net 9)
	)
	(segment
		(start 132.55 113.4)
		(end 131.8625 114.0875)
		(width 0.2)
		(layer "F.Cu")
		(net 9)
	)
	(segment
		(start 125.6 113.9)
		(end 124.55 112.85)
		(width 1)
		(layer "F.Cu")
		(net 9)
	)
	(segment
		(start 132.075 113.875)
		(end 131.675 113.875)
		(width 0.2)
		(layer "F.Cu")
		(net 9)
	)
	(segment
		(start 153.43 108.92)
		(end 153.43 108.091)
		(width 0.3)
		(layer "F.Cu")
		(net 9)
	)
	(segment
		(start 131.601 114.349)
		(end 130.925 114.349)
		(width 0.2)
		(layer "F.Cu")
		(net 9)
	)
	(segment
		(start 130.925 114.349)
		(end 130.075 114.349)
		(width 0.2)
		(layer "F.Cu")
		(net 9)
	)
	(segment
		(start 130.075 113.849)
		(end 129.649 113.849)
		(width 0.2)
		(layer "F.Cu")
		(net 9)
	)
	(segment
		(start 132.55 113.4)
		(end 132.075 113.875)
		(width 0.2)
		(layer "F.Cu")
		(net 9)
	)
	(segment
		(start 146.55 114.875)
		(end 146.225 114.55)
		(width 0.2)
		(layer "F.Cu")
		(net 9)
	)
	(segment
		(start 149.345 115.47)
		(end 149.345 114.67)
		(width 0.2)
		(layer "F.Cu")
		(net 9)
	)
	(segment
		(start 128.35 114.099)
		(end 127.099 114.099)
		(width 0.3)
		(layer "F.Cu")
		(net 9)
	)
	(segment
		(start 149.345 114.67)
		(end 149.325 114.65)
		(width 0.2)
		(layer "F.Cu")
		(net 9)
	)
	(segment
		(start 130.951 113.875)
		(end 130.925 113.849)
		(width 0.2)
		(layer "F.Cu")
		(net 9)
	)
	(via
		(at 134.7 89.55)
		(size 0.6)
		(drill 0.35)
		(layers "F.Cu" "B.Cu")
		(free yes)
		(net 9)
	)
	(via
		(at 153.014 110.5)
		(size 0.6)
		(drill 0.35)
		(layers "F.Cu" "B.Cu")
		(net 9)
	)
	(via
		(at 124.45 91.75)
		(size 0.6)
		(drill 0.35)
		(layers "F.Cu" "B.Cu")
		(net 9)
	)
	(via
		(at 142.25 118)
		(size 0.6)
		(drill 0.35)
		(layers "F.Cu" "B.Cu")
		(net 9)
	)
	(via
		(at 124.45 91)
		(size 0.6)
		(drill 0.35)
		(layers "F.Cu" "B.Cu")
		(net 9)
	)
	(via
		(at 133.55 89.55)
		(size 0.6)
		(drill 0.35)
		(layers "F.Cu" "B.Cu")
		(free yes)
		(net 9)
	)
	(via
		(at 149.325 114.65)
		(size 0.6)
		(drill 0.35)
		(layers "F.Cu" "B.Cu")
		(net 9)
	)
	(via
		(at 135.83 89.55)
		(size 0.6)
		(drill 0.35)
		(layers "F.Cu" "B.Cu")
		(free yes)
		(net 9)
	)
	(via
		(at 132.55 113.4)
		(size 0.6)
		(drill 0.35)
		(layers "F.Cu" "B.Cu")
		(net 9)
	)
	(via
		(at 124.45 90.25)
		(size 0.6)
		(drill 0.35)
		(layers "F.Cu" "B.Cu")
		(net 9)
	)
	(via
		(at 125.2 90.25)
		(size 0.6)
		(drill 0.35)
		(layers "F.Cu" "B.Cu")
		(net 9)
	)
	(via
		(at 125.2 91)
		(size 0.6)
		(drill 0.35)
		(layers "F.Cu" "B.Cu")
		(net 9)
	)
	(via
		(at 135.85 90.35)
		(size 0.6)
		(drill 0.35)
		(layers "F.Cu" "B.Cu")
		(net 9)
	)
	(via
		(at 125.2 91.75)
		(size 0.6)
		(drill 0.35)
		(layers "F.Cu" "B.Cu")
		(net 9)
	)
	(via
		(at 134.72 90.35)
		(size 0.6)
		(drill 0.35)
		(layers "F.Cu" "B.Cu")
		(net 9)
	)
	(via
		(at 146.225 114.55)
		(size 0.6)
		(drill 0.35)
		(layers "F.Cu" "B.Cu")
		(net 9)
	)
	(via
		(at 132.5 89.55)
		(size 0.6)
		(drill 0.35)
		(layers "F.Cu" "B.Cu")
		(free yes)
		(net 9)
	)
	(segment
		(start 132.6 113.35)
		(end 145.75 113.35)
		(width 0.5)
		(layer "B.Cu")
		(net 9)
	)
	(segment
		(start 149.325 113.7)
		(end 149.425 113.6)
		(width 0.2)
		(layer "B.Cu")
		(net 9)
	)
	(segment
		(start 153.014 111.861)
		(end 151.275 113.6)
		(width 0.5)
		(layer "B.Cu")
		(net 9)
	)
	(segment
		(start 146 114.325)
		(end 146 113.6)
		(width 0.2)
		(layer "B.Cu")
		(net 9)
	)
	(segment
		(start 149.325 114.65)
		(end 149.325 113.7)
		(width 0.2)
		(layer "B.Cu")
		(net 9)
	)
	(segment
		(start 142.25 118)
		(end 142.25 113.6)
		(width 0.3)
		(layer "B.Cu")
		(net 9)
	)
	(segment
		(start 153.014 110.5)
		(end 153.014 111.861)
		(width 0.5)
		(layer "B.Cu")
		(net 9)
	)
	(segment
		(start 146.225 114.55)
		(end 146 114.325)
		(width 0.2)
		(layer "B.Cu")
		(net 9)
	)
	(segment
		(start 151.275 113.6)
		(end 149.425 113.6)
		(width 0.5)
		(layer "B.Cu")
		(net 9)
	)
	(segment
		(start 149.425 113.6)
		(end 146 113.6)
		(width 0.5)
		(layer "B.Cu")
		(net 9)
	)
	(segment
		(start 132.55 113.4)
		(end 132.6 113.35)
		(width 0.5)
		(layer "B.Cu")
		(net 9)
	)
	(segment
		(start 145.75 113.35)
		(end 146 113.6)
		(width 0.5)
		(layer "B.Cu")
		(net 9)
	)
	(segment
		(start 131.6 112.62)
		(end 132.505 112.62)
		(width 0.3)
		(layer "F.Cu")
		(net 10)
	)
	(segment
		(start 130.925 112.849)
		(end 130.075 112.849)
		(width 0.2)
		(layer "F.Cu")
		(net 10)
	)
	(segment
		(start 126.601 112.599)
		(end 126.525 112.675)
		(width 0.3)
		(layer "F.Cu")
		(net 10)
	)
	(segment
		(start 148.96 95.40448)
		(end 148.96 93.035142)
		(width 0.5)
		(layer "F.Cu")
		(net 10)
	)
	(segment
		(start 131.329 112.349)
		(end 131.6 112.62)
		(width 0.2)
		(layer "F.Cu")
		(net 10)
	)
	(segment
		(start 143.75 118)
		(end 144.436827 118)
		(width 0.3)
		(layer "F.Cu")
		(net 10)
	)
	(segment
		(start 147.67 111.355)
		(end 147.67 109.205)
		(width 0.3)
		(layer "F.Cu")
		(net 10)
	)
	(segment
		(start 147.834556 98.640444)
		(end 147.605 98.410888)
		(width 0.3)
		(layer "F.Cu")
		(net 10)
	)
	(segment
		(start 129.4 113.1)
		(end 129.399 113.099)
		(width 0.2)
		(layer "F.Cu")
		(net 10)
	)
	(segment
		(start 128.35 112.599)
		(end 126.601 112.599)
		(width 0.3)
		(layer "F.Cu")
		(net 10)
	)
	(segment
		(start 125.95 112.15)
		(end 126.5 112.7)
		(width 1)
		(layer "F.Cu")
		(net 10)
	)
	(segment
		(start 126.525 112.675)
		(end 126.525 112.7)
		(width 0.3)
		(layer "F.Cu")
		(net 10)
	)
	(segment
		(start 132.615 112.51)
		(end 132.505 112.62)
		(width 0.2)
		(layer "F.Cu")
		(net 10)
	)
	(segment
		(start 125.9 112.15)
		(end 125.95 112.15)
		(width 1)
		(layer "F.Cu")
		(net 10)
	)
	(segment
		(start 135.885 112.565)
		(end 135.83 112.62)
		(width 0.2)
		(layer "F.Cu")
		(net 10)
	)
	(segment
		(start 143.075 112.62)
		(end 135.83 112.62)
		(width 0.3)
		(layer "F.Cu")
		(net 10)
	)
	(segment
		(start 146.234858 90.31)
		(end 146.22 90.31)
		(width 0.5)
		(layer "F.Cu")
		(net 10)
	)
	(segment
		(start 129.399 113.099)
		(end 128.35 113.099)
		(width 0.2)
		(layer "F.Cu")
		(net 10)
	)
	(segment
		(start 135.885 111.98)
		(end 135.885 112.565)
		(width 0.2)
		(layer "F.Cu")
		(net 10)
	)
	(segment
		(start 131.371 112.849)
		(end 131.6 112.62)
		(width 0.2)
		(layer "F.Cu")
		(net 10)
	)
	(segment
		(start 130.925 112.349)
		(end 130.075 112.349)
		(width 0.2)
		(layer "F.Cu")
		(net 10)
	)
	(segment
		(start 125.9 112.1)
		(end 125.9 112.15)
		(width 1)
		(layer "F.Cu")
		(net 10)
	)
	(segment
		(start 144.34 111.355)
		(end 147.67 111.355)
		(width 0.3)
		(layer "F.Cu")
		(net 10)
	)
	(segment
		(start 147.11224 97.75224)
		(end 147.11224 97.25224)
		(width 0.3)
		(layer "F.Cu")
		(net 10)
	)
	(segment
		(start 130.925 112.349)
		(end 131.329 112.349)
		(width 0.2)
		(layer "F.Cu")
		(net 10)
	)
	(segment
		(start 125.775 111.975)
		(end 125.825 111.2)
		(width 1)
		(layer "F.Cu")
		(net 10)
	)
	(segment
		(start 130.075 112.349)
		(end 129.351 112.349)
		(width 0.2)
		(layer "F.Cu")
		(net 10)
	)
	(segment
		(start 129.351 112.349)
		(end 129.101 112.599)
		(width 0.2)
		(layer "F.Cu")
		(net 10)
	)
	(segment
		(start 148.25224 96.11224)
		(end 148.71974 95.64474)
		(width 0.3)
		(layer "F.Cu")
		(net 10)
	)
	(segment
		(start 143.075 117.325)
		(end 143.75 118)
		(width 0.3)
		(layer "F.Cu")
		(net 10)
	)
	(segment
		(start 130.075 112.849)
		(end 129.651 112.849)
		(width 0.2)
		(layer "F.Cu")
		(net 10)
	)
	(segment
		(start 132.615 111.98)
		(end 132.615 112.51)
		(width 0.2)
		(layer "F.Cu")
		(net 10)
	)
	(segment
		(start 132.505 112.62)
		(end 135.83 112.62)
		(width 0.3)
		(layer "F.Cu")
		(net 10)
	)
	(segment
		(start 147.56224 96.80224)
		(end 148.25224 96.11224)
		(width 0.3)
		(layer "F.Cu")
		(net 10)
	)
	(segment
		(start 126.525 112.7)
		(end 126.5 112.7)
		(width 0.3)
		(layer "F.Cu")
		(net 10)
	)
	(segment
		(start 147.11224 97.25224)
		(end 147.56224 96.80224)
		(width 0.3)
		(layer "F.Cu")
		(net 10)
	)
	(segment
		(start 145 116.45)
		(end 145 118)
		(width 0.5)
		(layer "F.Cu")
		(net 10)
	)
	(segment
		(start 129.651 112.849)
		(end 129.4 113.1)
		(width 0.2)
		(layer "F.Cu")
		(net 10)
	)
	(segment
		(start 148.71974 95.64474)
		(end 148.96 95.40448)
		(width 0.5)
		(layer "F.Cu")
		(net 10)
	)
	(segment
		(start 143.075 112.62)
		(end 143.075 117.325)
		(width 0.3)
		(layer "F.Cu")
		(net 10)
	)
	(segment
		(start 148.96 93.035142)
		(end 146.234858 90.31)
		(width 0.5)
		(layer "F.Cu")
		(net 10)
	)
	(segment
		(start 128.35 113.099)
		(end 126.5 113.099)
		(width 0.3)
		(layer "F.Cu")
		(net 10)
	)
	(segment
		(start 147.605 98.410888)
		(end 147.605 98.245)
		(width 0.3)
		(layer "F.Cu")
		(net 10)
	)
	(segment
		(start 143.075 112.62)
		(end 144.34 111.355)
		(width 0.3)
		(layer "F.Cu")
		(net 10)
	)
	(segment
		(start 129.101 112.599)
		(end 128.35 112.599)
		(width 0.2)
		(layer "F.Cu")
		(net 10)
	)
	(segment
		(start 125.825 111.2)
		(end 125.9 112.1)
		(width 1)
		(layer "F.Cu")
		(net 10)
	)
	(segment
		(start 148.109619 98.915507)
		(end 147.834556 98.640444)
		(width 0.2)
		(layer "F.Cu")
		(net 10)
	)
	(segment
		(start 126.5 113.099)
		(end 126.5 112.7)
		(width 0.3)
		(layer "F.Cu")
		(net 10)
	)
	(segment
		(start 130.925 112.849)
		(end 131.371 112.849)
		(width 0.2)
		(layer "F.Cu")
		(net 10)
	)
	(segment
		(start 147.605 98.245)
		(end 147.11224 97.75224)
		(width 0.3)
		(layer "F.Cu")
		(net 10)
	)
	(via
		(at 145 118)
		(size 0.6)
		(drill 0.35)
		(layers "F.Cu" "B.Cu")
		(net 10)
	)
	(via
		(at 144.15 90.15)
		(size 0.6)
		(drill 0.35)
		(layers "F.Cu" "B.Cu")
		(free yes)
		(net 10)
	)
	(via
		(at 143.05 89.35)
		(size 0.6)
		(drill 0.35)
		(layers "F.Cu" "B.Cu")
		(free yes)
		(net 10)
	)
	(via
		(at 125.825 111.2)
		(size 0.6)
		(drill 0.35)
		(layers "F.Cu" "B.Cu")
		(net 10)
	)
	(via
		(at 125.9 112.15)
		(size 0.6)
		(drill 0.35)
		(layers "F.Cu" "B.Cu")
		(net 10)
	)
	(via
		(at 140.75 89.35)
		(size 0.6)
		(drill 0.35)
		(layers "F.Cu" "B.Cu")
		(free yes)
		(net 10)
	)
	(via
		(at 126.525 112.7)
		(size 0.6)
		(drill 0.35)
		(layers "F.Cu" "B.Cu")
		(net 10)
	)
	(via
		(at 144.15 89.35)
		(size 0.6)
		(drill 0.35)
		(layers "F.Cu" "B.Cu")
		(free yes)
		(net 10)
	)
	(via
		(at 143.05 90.15)
		(size 0.6)
		(drill 0.35)
		(layers "F.Cu" "B.Cu")
		(free yes)
		(net 10)
	)
	(via
		(at 141.9 89.35)
		(size 0.6)
		(drill 0.35)
		(layers "F.Cu" "B.Cu")
		(free yes)
		(net 10)
	)
	(segment
		(start 148.475 114.725)
		(end 148.475 117.275)
		(width 0.2)
		(layer "F.Cu")
		(net 11)
	)
	(segment
		(start 148.075 113.725)
		(end 149.055 113.725)
		(width 0.2)
		(layer "F.Cu")
		(net 11)
	)
	(segment
		(start 164.4 107)
		(end 164.4 107.85)
		(width 0.6)
		(layer "F.Cu")
		(net 11)
	)
	(segment
		(start 164.4 107)
		(end 163.45 107)
		(width 0.3)
		(layer "F.Cu")
		(net 11)
	)
	(segment
		(start 162.178 106.878)
		(end 162.3 107)
		(width 0.6)
		(layer "F.Cu")
		(net 11)
	)
	(segment
		(start 157.85 105.25)
		(end 157.85 106.55)
		(width 0.3)
		(layer "F.Cu")
		(net 11)
	)
	(segment
		(start 164.4 107.85)
		(end 164.05 108.2)
		(width 0.6)
		(layer "F.Cu")
		(net 11)
	)
	(segment
		(start 149.055 113.725)
		(end 149.055 114.145)
		(width 0.2)
		(layer "F.Cu")
		(net 11)
	)
	(segment
		(start 164.05 108.2)
		(end 161 108.2)
		(width 0.6)
		(layer "F.Cu")
		(net 11)
	)
	(segment
		(start 149.25 119.5)
		(end 156.75 119.5)
		(width 0.3)
		(layer "F.Cu")
		(net 11)
	)
	(segment
		(start 157.85 106.55)
		(end 158.178 106.878)
		(width 0.3)
		(layer "F.Cu")
		(net 11)
	)
	(segment
		(start 161.025 106.878)
		(end 162.178 106.878)
		(width 0.6)
		(layer "F.Cu")
		(net 11)
	)
	(segment
		(start 159.037 104.978)
		(end 158.122 104.978)
		(width 0.3)
		(layer "F.Cu")
		(net 11)
	)
	(segment
		(start 149.055 114.145)
		(end 148.475 114.725)
		(width 0.2)
		(layer "F.Cu")
		(net 11)
	)
	(segment
		(start 148.475 117.275)
		(end 147.75 118)
		(width 0.2)
		(layer "F.Cu")
		(net 11)
	)
	(segment
		(start 158.75 116.75)
		(end 161 114.5)
		(width 0.3)
		(layer "F.Cu")
		(net 11)
	)
	(segment
		(start 158.178 106.878)
		(end 159.037 106.878)
		(width 0.3)
		(layer "F.Cu")
		(net 11)
	)
	(segment
		(start 160.208 106.878)
		(end 161.025 106.878)
		(width 0.3)
		(layer "F.Cu")
		(net 11)
	)
	(segment
		(start 149.877386 100.683274)
		(end 150.47566 100.085)
		(width 0.2)
		(layer "F.Cu")
		(net 11)
	)
	(segment
		(start 159.037 106.878)
		(end 160.208 106.878)
		(width 0.3)
		(layer "F.Cu")
		(net 11)
	)
	(segment
		(start 157.25 117.25)
		(end 157.75 116.75)
		(width 0.3)
		(layer "F.Cu")
		(net 11)
	)
	(segment
		(start 150.47566 100.085)
		(end 150.535 100.085)
		(width 0.2)
		(layer "F.Cu")
		(net 11)
	)
	(segment
		(start 158.122 104.978)
		(end 157.85 105.25)
		(width 0.3)
		(layer "F.Cu")
		(net 11)
	)
	(segment
		(start 147.75 118)
		(end 149.25 119.5)
		(width 0.3)
		(layer "F.Cu")
		(net 11)
	)
	(segment
		(start 161 114.5)
		(end 161 108.2)
		(width 0.3)
		(layer "F.Cu")
		(net 11)
	)
	(segment
		(start 157.22 108.2)
		(end 161 108.2)
		(width 0.6)
		(layer "F.Cu")
		(net 11)
	)
	(segment
		(start 157.25 119)
		(end 157.25 117.25)
		(width 0.3)
		(layer "F.Cu")
		(net 11)
	)
	(segment
		(start 162.3 107)
		(end 163.45 107)
		(width 0.6)
		(layer "F.Cu")
		(net 11)
	)
	(segment
		(start 156.75 119.5)
		(end 157.25 119)
		(width 0.3)
		(layer "F.Cu")
		(net 11)
	)
	(segment
		(start 157.75 116.75)
		(end 158.75 116.75)
		(width 0.3)
		(layer "F.Cu")
		(net 11)
	)
	(via
		(at 157.22 108.2)
		(size 0.6)
		(drill 0.35)
		(layers "F.Cu" "B.Cu")
		(net 11)
	)
	(via
		(at 150.535 100.085)
		(size 0.6)
		(drill 0.35)
		(layers "F.Cu" "B.Cu")
		(net 11)
	)
	(segment
		(start 151.9 102.475)
		(end 151.9 102.48552)
		(width 0.6)
		(layer "B.Cu")
		(net 11)
	)
	(segment
		(start 149.819411 100.410589)
		(end 150.145 100.085)
		(width 0.3)
		(layer "B.Cu")
		(net 11)
	)
	(segment
		(start 153.4 103.98552)
		(end 153.4 105.3)
		(width 0.6)
		(layer "B.Cu")
		(net 11)
	)
	(segment
		(start 149.819411 100.410589)
		(end 150.509411 101.100589)
		(width 0.3)
		(layer "B.Cu")
		(net 11)
	)
	(segment
		(start 150.509411 101.100589)
		(end 151.199411 101.790589)
		(width 0.3)
		(layer "B.Cu")
		(net 11)
	)
	(segment
		(start 150.535 100.085)
		(end 150.85 100.4)
		(width 0.3)
		(layer "B.Cu")
		(net 11)
	)
	(segment
		(start 151.9 102.48552)
		(end 153.4 103.98552)
		(width 0.6)
		(layer "B.Cu")
		(net 11)
	)
	(segment
		(start 151.9 102.475)
		(end 151.883822 102.475)
		(width 0.3)
		(layer "B.Cu")
		(net 11)
	)
	(segment
		(start 150.85 100.4)
		(end 150.85 100.76)
		(width 0.3)
		(layer "B.Cu")
		(net 11)
	)
	(segment
		(start 151.883822 102.475)
		(end 151.199411 101.790589)
		(width 0.3)
		(layer "B.Cu")
		(net 11)
	)
	(segment
		(start 150.145 100.085)
		(end 150.535 100.085)
		(width 0.3)
		(layer "B.Cu")
		(net 11)
	)
	(segment
		(start 153.4 105.3)
		(end 156.3 108.2)
		(width 0.6)
		(layer "B.Cu")
		(net 11)
	)
	(segment
		(start 156.3 108.2)
		(end 157.22 108.2)
		(width 0.6)
		(layer "B.Cu")
		(net 11)
	)
	(segment
		(start 150.85 100.76)
		(end 150.509411 101.100589)
		(width 0.3)
		(layer "B.Cu")
		(net 11)
	)
	(segment
		(start 155.2 104.7)
		(end 155.2 106)
		(width 0.3)
		(layer "F.Cu")
		(net 12)
	)
	(segment
		(start 152.525 115.55)
		(end 152.24 115.835)
		(width 0.3)
		(layer "F.Cu")
		(net 12)
	)
	(segment
		(start 151.1 96)
		(end 151.1 96.018822)
		(width 0.3)
		(layer "F.Cu")
		(net 12)
	)
	(segment
		(start 148.875 98.855)
		(end 148.463173 99.266827)
		(width 0.2)
		(layer "F.Cu")
		(net 12)
	)
	(segment
		(start 152.24 115.835)
		(end 151.7 115.835)
		(width 0.3)
		(layer "F.Cu")
		(net 12)
	)
	(segment
		(start 155.2 106.878)
		(end 155.2 106)
		(width 0.3)
		(layer "F.Cu")
		(net 12)
	)
	(segment
		(start 148.875 98.6)
		(end 148.875 98.855)
		(width 0.2)
		(layer "F.Cu")
		(net 12)
	)
	(segment
		(start 156.336 106.878)
		(end 155.2 106.878)
		(width 0.3)
		(layer "F.Cu")
		(net 12)
	)
	(segment
		(start 154.25 106.4)
		(end 154.25 110.4)
		(width 0.3)
		(layer "F.Cu")
		(net 12)
	)
	(segment
		(start 151.7 116.8)
		(end 150.5 118)
		(width 0.2)
		(layer "F.Cu")
		(net 12)
	)
	(segment
		(start 152.525 113.8)
		(end 151.82 113.8)
		(width 0.3)
		(layer "F.Cu")
		(net 12)
	)
	(segment
		(start 154.25 110.4)
		(end 152.825 111.825)
		(width 0.3)
		(layer "F.Cu")
		(net 12)
	)
	(segment
		(start 151.7 115.835)
		(end 151.7 116.8)
		(width 0.2)
		(layer "F.Cu")
		(net 12)
	)
	(segment
		(start 151.1 96.018822)
		(end 150.559411 96.559411)
		(width 0.3)
		(layer "F.Cu")
		(net 12)
	)
	(segment
		(start 151.1 96)
		(end 151.1 96.02448)
		(width 0.6)
		(layer "F.Cu")
		(net 12)
	)
	(segment
		(start 152.825 111.825)
		(end 152.825 113.5)
		(width 0.3)
		(layer "F.Cu")
		(net 12)
	)
	(segment
		(start 154.65 106)
		(end 154.25 106.4)
		(width 0.3)
		(layer "F.Cu")
		(net 12)
	)
	(segment
		(start 148.875 98.26948)
		(end 149.19224 97.95224)
		(width 0.3)
		(layer "F.Cu")
		(net 12)
	)
	(segment
		(start 155.2 106)
		(end 154.65 106)
		(width 0.3)
		(layer "F.Cu")
		(net 12)
	)
	(segment
		(start 152.525 113.8)
		(end 152.525 115.55)
		(width 0.3)
		(layer "F.Cu")
		(net 12)
	)
	(segment
		(start 148.875 98.6)
		(end 148.875 98.26948)
		(width 0.3)
		(layer "F.Cu")
		(net 12)
	)
	(segment
		(start 152.825 113.5)
		(end 152.525 113.8)
		(width 0.3)
		(layer "F.Cu")
		(net 12)
	)
	(segment
		(start 149.19224 97.93224)
		(end 150.56224 96.56224)
		(width 0.3)
		(layer "F.Cu")
		(net 12)
	)
	(segment
		(start 148.463173 99.266827)
		(end 148.463173 99.26906)
		(width 0.2)
		(layer "F.Cu")
		(net 12)
	)
	(via
		(at 155.2 104.7)
		(size 0.6)
		(drill 0.35)
		(layers "F.Cu" "B.Cu")
		(net 12)
	)
	(via
		(at 151.1 96)
		(size 0.6)
		(drill 0.35)
		(layers "F.Cu" "B.Cu")
		(net 12)
	)
	(segment
		(start 155.2 100.1)
		(end 151.1 96)
		(width 0.6)
		(layer "B.Cu")
		(net 12)
	)
	(segment
		(start 155.2 104.65)
		(end 155.2 104.7)
		(width 0.3)
		(layer "B.Cu")
		(net 12)
	)
	(segment
		(start 155.2 104.65)
		(end 155.2 100.1)
		(width 0.6)
		(layer "B.Cu")
		(net 12)
	)
	(segment
		(start 154.57852 103.303569)
		(end 153.822089 104.06)
		(width 0.2)
		(layer "F.Cu")
		(net 13)
	)
	(segment
		(start 153.822089 104.06)
		(end 153.42 104.06)
		(width 0.2)
		(layer "F.Cu")
		(net 13)
	)
	(segment
		(start 152.22224 103.67224)
		(end 151.35 102.8)
		(width 0.2)
		(layer "F.Cu")
		(net 13)
	)
	(segment
		(start 151.074874 102.8)
		(end 150.584493 102.309619)
		(width 0.2)
		(layer "F.Cu")
		(net 13)
	)
	(segment
		(start 151.35 102.8)
		(end 151.074874 102.8)
		(width 0.2)
		(layer "F.Cu")
		(net 13)
	)
	(segment
		(start 153.03224 103.67224)
		(end 152.22224 103.67224)
		(width 0.2)
		(layer "F.Cu")
		(net 13)
	)
	(segment
		(start 153.42 104.06)
		(end 153.03224 103.67224)
		(width 0.2)
		(layer "F.Cu")
		(net 13)
	)
	(segment
		(start 155.88776 99.450158)
		(end 154.93278 100.405138)
		(width 0.2)
		(layer "F.Cu")
		(net 14)
	)
	(segment
		(start 153.682 99.81)
		(end 153.250947 100.241053)
		(width 0.2)
		(layer "F.Cu")
		(net 14)
	)
	(segment
		(start 154.337642 99.81)
		(end 153.682 99.81)
		(width 0.2)
		(layer "F.Cu")
		(net 14)
	)
	(segment
		(start 154.93278 100.405138)
		(end 154.337642 99.81)
		(width 0.2)
		(layer "F.Cu")
		(net 14)
	)
	(segment
		(start 149.46 98.97934)
		(end 149.46 98.89)
		(width 0.2)
		(layer "F.Cu")
		(net 15)
	)
	(segment
		(start 148.816726 99.622614)
		(end 149.46 98.97934)
		(width 0.2)
		(layer "F.Cu")
		(net 15)
	)
	(segment
		(start 149.46 98.89)
		(end 149.46 99.010453)
		(width 0.2)
		(layer "F.Cu")
		(net 15)
	)
	(via
		(at 149.46 98.89)
		(size 0.6)
		(drill 0.35)
		(layers "F.Cu" "B.Cu")
		(net 15)
	)
	(segment
		(start 149.245 98.675)
		(end 148.775073 98.675)
		(width 0.3)
		(layer "B.Cu")
		(net 15)
	)
	(segment
		(start 149.46 99.390143)
		(end 149.46 98.89)
		(width 0.3)
		(layer "B.Cu")
		(net 15)
	)
	(segment
		(start 149.46 98.89)
		(end 149.245 98.675)
		(width 0.3)
		(layer "B.Cu")
		(net 15)
	)
	(segment
		(start 148.429447 99.020626)
		(end 149.129482 99.720661)
		(width 0.3)
		(layer "B.Cu")
		(net 15)
	)
	(segment
		(start 149.129482 99.720661)
		(end 149.46 99.390143)
		(width 0.3)
		(layer "B.Cu")
		(net 15)
	)
	(segment
		(start 148.775073 98.675)
		(end 148.429447 99.020626)
		(width 0.3)
		(layer "B.Cu")
		(net 15)
	)
	(segment
		(start 147.729411 98.320589)
		(end 148.429447 99.020626)
		(width 0.3)
		(layer "B.Cu")
		(net 15)
	)
	(segment
		(start 150.79224 97.68276)
		(end 151.507053 96.967947)
		(width 0.2)
		(layer "F.Cu")
		(net 16)
	)
	(segment
		(start 150.693037 99.160515)
		(end 150.693037 99.149411)
		(width 0.2)
		(layer "F.Cu")
		(net 17)
	)
	(segment
		(start 149.523833 100.32972)
		(end 150.693037 99.160515)
		(width 0.2)
		(layer "F.Cu")
		(net 17)
	)
	(segment
		(start 153 96.247008)
		(end 153 79.998)
		(width 0.2)
		(layer "F.Cu")
		(net 18)
	)
	(segment
		(start 152.15798 97.710348)
		(end 152.1321 97.710348)
		(width 0.2)
		(layer "F.Cu")
		(net 18)
	)
	(segment
		(start 152.1321 97.710348)
		(end 151.371859 98.470589)
		(width 0.2)
		(layer "F.Cu")
		(net 18)
	)
	(segment
		(start 152.15798 97.710348)
		(end 152.56066 97.307668)
		(width 0.2)
		(layer "F.Cu")
		(net 18)
	)
	(arc
		(start 153 96.247008)
		(mid 152.885819 96.821033)
		(end 152.56066 97.307668)
		(width 0.2)
		(layer "F.Cu")
		(net 18)
	)
	(segment
		(start 150.10776 98.36724)
		(end 150.10776 98.624474)
		(width 0.2)
		(layer "F.Cu")
		(net 33)
	)
	(segment
		(start 149.814866 99.331581)
		(end 149.17028 99.976167)
		(width 0.2)
		(layer "F.Cu")
		(net 33)
	)
	(arc
		(start 149.814866 99.331581)
		(mid 150.031639 99.007158)
		(end 150.10776 98.624474)
		(width 0.2)
		(layer "F.Cu")
		(net 33)
	)
	(segment
		(start 129.151 108.599)
		(end 128.35 108.599)
		(width 0.2)
		(layer "F.Cu")
		(net 34)
	)
	(segment
		(start 129.401 108.349)
		(end 129.151 108.599)
		(width 0.2)
		(layer "F.Cu")
		(net 34)
	)
	(segment
		(start 132.1075 107.7)
		(end 131.4585 108.349)
		(width 0.2)
		(layer "F.Cu")
		(net 34)
	)
	(segment
		(start 130.925 108.349)
		(end 131.4585 108.349)
		(width 0.2)
		(layer "F.Cu")
		(net 34)
	)
	(segment
		(start 130.925 108.349)
		(end 130.075 108.349)
		(width 0.2)
		(layer "F.Cu")
		(net 34)
	)
	(segment
		(start 130.075 108.349)
		(end 129.401 108.349)
		(width 0.2)
		(layer "F.Cu")
		(net 34)
	)
	(segment
		(start 132.615 107.7)
		(end 132.1075 107.7)
		(width 0.2)
		(layer "F.Cu")
		(net 34)
	)
	(segment
		(start 131.55 108.75)
		(end 131.451 108.849)
		(width 0.2)
		(layer "F.Cu")
		(net 35)
	)
	(segment
		(start 131.451 108.849)
		(end 130.925 108.849)
		(width 0.2)
		(layer "F.Cu")
		(net 35)
	)
	(segment
		(start 130.925 108.849)
		(end 130.075 108.849)
		(width 0.2)
		(layer "F.Cu")
		(net 35)
	)
	(segment
		(start 132.615 108.75)
		(end 131.55 108.75)
		(width 0.2)
		(layer "F.Cu")
		(net 35)
	)
	(segment
		(start 128.35 109.099)
		(end 129.251 109.099)
		(width 0.2)
		(layer "F.Cu")
		(net 35)
	)
	(segment
		(start 129.251 109.099)
		(end 129.501 108.849)
		(width 0.2)
		(layer "F.Cu")
		(net 35)
	)
	(segment
		(start 129.501 108.849)
		(end 130.075 108.849)
		(width 0.2)
		(layer "F.Cu")
		(net 35)
	)
	(segment
		(start 129.249 109.599)
		(end 129.499 109.849)
		(width 0.2)
		(layer "F.Cu")
		(net 36)
	)
	(segment
		(start 128.35 109.599)
		(end 129.249 109.599)
		(width 0.2)
		(layer "F.Cu")
		(net 36)
	)
	(segment
		(start 132.616 109.884)
		(end 131.484 109.884)
		(width 0.2)
		(layer "F.Cu")
		(net 36)
	)
	(segment
		(start 131.484 109.884)
		(end 131.449 109.849)
		(width 0.2)
		(layer "F.Cu")
		(net 36)
	)
	(segment
		(start 130.925 109.849)
		(end 130.075 109.849)
		(width 0.2)
		(layer "F.Cu")
		(net 36)
	)
	(segment
		(start 129.499 109.849)
		(end 130.075 109.849)
		(width 0.2)
		(layer "F.Cu")
		(net 36)
	)
	(segment
		(start 130.925 109.849)
		(end 131.449 109.849)
		(width 0.2)
		(layer "F.Cu")
		(net 36)
	)
	(segment
		(start 129.199 110.099)
		(end 129.449 110.349)
		(width 0.2)
		(layer "F.Cu")
		(net 37)
	)
	(segment
		(start 132.615 110.95)
		(end 132.1 110.95)
		(width 0.2)
		(layer "F.Cu")
		(net 37)
	)
	(segment
		(start 130.925 110.349)
		(end 131.499 110.349)
		(width 0.2)
		(layer "F.Cu")
		(net 37)
	)
	(segment
		(start 129.449 110.349)
		(end 130.075 110.349)
		(width 0.2)
		(layer "F.Cu")
		(net 37)
	)
	(segment
		(start 132.1 110.95)
		(end 131.499 110.349)
		(width 0.2)
		(layer "F.Cu")
		(net 37)
	)
	(segment
		(start 130.925 110.349)
		(end 130.075 110.349)
		(width 0.2)
		(layer "F.Cu")
		(net 37)
	)
	(segment
		(start 128.35 110.099)
		(end 129.199 110.099)
		(width 0.2)
		(layer "F.Cu")
		(net 37)
	)
	(segment
		(start 145.55 97.675)
		(end 146.017463 97.675)
		(width 0.2)
		(layer "F.Cu")
		(net 38)
	)
	(segment
		(start 147.190381 98.915507)
		(end 146.621232 98.346358)
		(width 0.2)
		(layer "F.Cu")
		(net 38)
	)
	(segment
		(start 130.925 105.099)
		(end 128.35 105.099)
		(width 0.2)
		(layer "F.Cu")
		(net 38)
	)
	(segment
		(start 130.925 105.099)
		(end 131.676 105.099)
		(width 0.2)
		(layer "F.Cu")
		(net 38)
	)
	(segment
		(start 146.621232 98.346358)
		(end 146.621232 98.278768)
		(width 0.2)
		(layer "F.Cu")
		(net 38)
	)
	(segment
		(start 146.017463 97.675)
		(end 146.621232 98.278768)
		(width 0.2)
		(layer "F.Cu")
		(net 38)
	)
	(segment
		(start 131.676 105.099)
		(end 132.125 104.65)
		(width 0.2)
		(layer "F.Cu")
		(net 38)
	)
	(via
		(at 132.125 104.65)
		(size 0.6)
		(drill 0.35)
		(layers "F.Cu" "B.Cu")
		(net 38)
	)
	(via
		(at 145.55 97.675)
		(size 0.6)
		(drill 0.35)
		(layers "F.Cu" "B.Cu")
		(net 38)
	)
	(segment
		(start 145.55 97.675)
		(end 143.897917 97.675)
		(width 0.2)
		(layer "B.Cu")
		(net 38)
	)
	(segment
		(start 134.85 104.65)
		(end 132.125 104.65)
		(width 0.2)
		(layer "B.Cu")
		(net 38)
	)
	(segment
		(start 138.225 108.025)
		(end 134.85 104.65)
		(width 0.2)
		(layer "B.Cu")
		(net 38)
	)
	(segment
		(start 143.897917 97.675)
		(end 143.15 98.422917)
		(width 0.2)
		(layer "B.Cu")
		(net 38)
	)
	(segment
		(start 143.14038 108.025)
		(end 138.225 108.025)
		(width 0.2)
		(layer "B.Cu")
		(net 38)
	)
	(segment
		(start 143.15 98.422917)
		(end 143.15 99.644547)
		(width 0.2)
		(layer "B.Cu")
		(net 38)
	)
	(segment
		(start 143.15 99.644547)
		(end 144.6 101.094547)
		(width 0.2)
		(layer "B.Cu")
		(net 38)
	)
	(segment
		(start 144.6 102.894238)
		(end 145.075 103.369239)
		(width 0.2)
		(layer "B.Cu")
		(net 38)
	)
	(segment
		(start 145.075 103.369239)
		(end 145.075 106.09038)
		(width 0.2)
		(layer "B.Cu")
		(net 38)
	)
	(segment
		(start 144.6 101.094547)
		(end 144.6 102.894238)
		(width 0.2)
		(layer "B.Cu")
		(net 38)
	)
	(segment
		(start 145.075 106.09038)
		(end 143.14038 108.025)
		(width 0.2)
		(layer "B.Cu")
		(net 38)
	)
	(segment
		(start 133.585 106.635)
		(end 132.615 105.665)
		(width 0.2)
		(layer "F.Cu")
		(net 39)
	)
	(segment
		(start 129.601 105.599)
		(end 130.075 105.599)
		(width 0.2)
		(layer "F.Cu")
		(net 39)
	)
	(segment
		(start 132.615 105.574)
		(end 131.532537 105.574)
		(width 0.2)
		(layer "F.Cu")
		(net 39)
	)
	(segment
		(start 130.925 105.599)
		(end 131.507537 105.599)
		(width 0.2)
		(layer "F.Cu")
		(net 39)
	)
	(segment
		(start 131.532537 105.574)
		(end 131.507537 105.599)
		(width 0.2)
		(layer "F.Cu")
		(net 39)
	)
	(segment
		(start 129.102 106.098)
		(end 129.601 105.599)
		(width 0.2)
		(layer "F.Cu")
		(net 39)
	)
	(segment
		(start 130.925 105.599)
		(end 130.075 105.599)
		(width 0.2)
		(layer "F.Cu")
		(net 39)
	)
	(segment
		(start 128.35 106.098)
		(end 129.102 106.098)
		(width 0.2)
		(layer "F.Cu")
		(net 39)
	)
	(segment
		(start 141.65 99.557101)
		(end 142.977687 99.557101)
		(width 0.18)
		(layer "F.Cu")
		(net 40)
	)
	(segment
		(start 141.282425 99.689527)
		(end 141.282425 99.689526)
		(width 0.18)
		(layer "F.Cu")
		(net 40)
	)
	(segment
		(start 139.2075 99.975594)
		(end 139.625993 99.557101)
		(width 0.18)
		(layer "F.Cu")
		(net 40)
	)
	(segment
		(start 141.41485 99.557101)
		(end 141.65 99.557101)
		(width 0.18)
		(layer "F.Cu")
		(net 40)
	)
	(segment
		(start 139.4175 100.5)
		(end 139.2075 100.29)
		(width 0.18)
		(layer "F.Cu")
		(net 40)
	)
	(segment
		(start 127.449999 98.6)
		(end 127.382499 98.6675)
		(width 0.18)
		(layer "F.Cu")
		(net 40)
	)
	(segment
		(start 140.91485 99.821952)
		(end 141.15 99.821952)
		(width 0.18)
		(layer "F.Cu")
		(net 40)
	)
	(segment
		(start 142.977687 99.557101)
		(end 144.372793 100.952207)
		(width 0.18)
		(layer "F.Cu")
		(net 40)
	)
	(segment
		(start 139.625993 99.557101)
		(end 140.65 99.557101)
		(width 0.18)
		(layer "F.Cu")
		(net 40)
	)
	(segment
		(start 144.372793 101.047667)
		(end 144.715507 101.390381)
		(width 0.18)
		(layer "F.Cu")
		(net 40)
	)
	(segment
		(start 126.346618 98.6675)
		(end 126.136618 98.4575)
		(width 0.18)
		(layer "F.Cu")
		(net 40)
	)
	(segment
		(start 127.382499 98.6675)
		(end 126.346618 98.6675)
		(width 0.18)
		(layer "F.Cu")
		(net 40)
	)
	(segment
		(start 128.35 98.6)
		(end 127.449999 98.6)
		(width 0.18)
		(layer "F.Cu")
		(net 40)
	)
	(segment
		(start 139.2075 100.29)
		(end 139.2075 99.975594)
		(width 0.18)
		(layer "F.Cu")
		(net 40)
	)
	(segment
		(start 144.372793 100.952207)
		(end 144.372793 101.047667)
		(width 0.18)
		(layer "F.Cu")
		(net 40)
	)
	(segment
		(start 140.782425 99.689526)
		(end 140.782425 99.689527)
		(width 0.18)
		(layer "F.Cu")
		(net 40)
	)
	(via
		(at 126.136618 98.4575)
		(size 0.6)
		(drill 0.35)
		(layers "F.Cu" "B.Cu")
		(net 40)
	)
	(via
		(at 139.4175 100.5)
		(size 0.6)
		(drill 0.35)
		(layers "F.Cu" "B.Cu")
		(net 40)
	)
	(arc
		(start 140.65 99.557101)
		(mid 140.743639 99.595887)
		(end 140.782425 99.689526)
		(width 0.18)
		(layer "F.Cu")
		(net 40)
	)
	(arc
		(start 140.782425 99.689527)
		(mid 140.821211 99.783166)
		(end 140.91485 99.821952)
		(width 0.18)
		(layer "F.Cu")
		(net 40)
	)
	(arc
		(start 141.15 99.821952)
		(mid 141.243639 99.783166)
		(end 141.282425 99.689527)
		(width 0.18)
		(layer "F.Cu")
		(net 40)
	)
	(arc
		(start 141.282425 99.689526)
		(mid 141.321211 99.595887)
		(end 141.41485 99.557101)
		(width 0.18)
		(layer "F.Cu")
		(net 40)
	)
	(segment
		(start 128.150594 98.6675)
		(end 126.346618 98.6675)
		(width 0.18)
		(layer "B.Cu")
		(net 40)
	)
	(segment
		(start 128.825594 99.3425)
		(end 128.150594 98.6675)
		(width 0.18)
		(layer "B.Cu")
		(net 40)
	)
	(segment
		(start 138.800594 99.3425)
		(end 128.825594 99.3425)
		(width 0.18)
		(layer "B.Cu")
		(net 40)
	)
	(segment
		(start 139.2075 100.29)
		(end 139.2075 99.749406)
		(width 0.18)
		(layer "B.Cu")
		(net 40)
	)
	(segment
		(start 126.346618 98.6675)
		(end 126.136618 98.4575)
		(width 0.18)
		(layer "B.Cu")
		(net 40)
	)
	(segment
		(start 139.2075 99.749406)
		(end 138.800594 99.3425)
		(width 0.18)
		(layer "B.Cu")
		(net 40)
	)
	(segment
		(start 139.4175 100.5)
		(end 139.2075 100.29)
		(width 0.18)
		(layer "B.Cu")
		(net 40)
	)
	(segment
		(start 138.8425 100.29)
		(end 138.8425 99.824406)
		(width 0.18)
		(layer "F.Cu")
		(net 41)
	)
	(segment
		(start 143.128875 99.192101)
		(end 144.618387 100.681613)
		(width 0.18)
		(layer "F.Cu")
		(net 41)
	)
	(segment
		(start 138.6325 100.5)
		(end 138.8425 100.29)
		(width 0.18)
		(layer "F.Cu")
		(net 41)
	)
	(segment
		(start 144.713846 100.681613)
		(end 145.06906 101.036827)
		(width 0.18)
		(layer "F.Cu")
		(net 41)
	)
	(segment
		(start 144.618387 100.681613)
		(end 144.713846 100.681613)
		(width 0.18)
		(layer "F.Cu")
		(net 41)
	)
	(segment
		(start 139.474805 99.192101)
		(end 143.128875 99.192101)
		(width 0.18)
		(layer "F.Cu")
		(net 41)
	)
	(segment
		(start 138.8425 99.824406)
		(end 139.474805 99.192101)
		(width 0.18)
		(layer "F.Cu")
		(net 41)
	)
	(segment
		(start 126.346618 99.0325)
		(end 126.136618 99.2425)
		(width 0.18)
		(layer "F.Cu")
		(net 41)
	)
	(segment
		(start 128.35 99.1)
		(end 127.449999 99.1)
		(width 0.18)
		(layer "F.Cu")
		(net 41)
	)
	(segment
		(start 127.382499 99.0325)
		(end 126.346618 99.0325)
		(width 0.18)
		(layer "F.Cu")
		(net 41)
	)
	(segment
		(start 127.449999 99.1)
		(end 127.382499 99.0325)
		(width 0.18)
		(layer "F.Cu")
		(net 41)
	)
	(via
		(at 138.6325 100.5)
		(size 0.6)
		(drill 0.35)
		(layers "F.Cu" "B.Cu")
		(net 41)
	)
	(via
		(at 126.136618 99.2425)
		(size 0.6)
		(drill 0.35)
		(layers "F.Cu" "B.Cu")
		(net 41)
	)
	(segment
		(start 127.999406 99.0325)
		(end 126.346618 99.0325)
		(width 0.18)
		(layer "B.Cu")
		(net 41)
	)
	(segment
		(start 138.8425 99.900594)
		(end 138.649406 99.7075)
		(width 0.18)
		(layer "B.Cu")
		(net 41)
	)
	(segment
		(start 138.6325 100.5)
		(end 138.8425 100.29)
		(width 0.18)
		(layer "B.Cu")
		(net 41)
	)
	(segment
		(start 128.674406 99.7075)
		(end 127.999406 99.0325)
		(width 0.18)
		(layer "B.Cu")
		(net 41)
	)
	(segment
		(start 126.346618 99.0325)
		(end 126.136618 99.2425)
		(width 0.18)
		(layer "B.Cu")
		(net 41)
	)
	(segment
		(start 138.8425 100.29)
		(end 138.8425 99.900594)
		(width 0.18)
		(layer "B.Cu")
		(net 41)
	)
	(segment
		(start 138.649406 99.7075)
		(end 128.674406 99.7075)
		(width 0.18)
		(layer "B.Cu")
		(net 41)
	)
	(segment
		(start 130.996389 98.670953)
		(end 130.830117 98.837224)
		(width 0.18)
		(layer "F.Cu")
		(net 42)
	)
	(segment
		(start 134.783113 98.074981)
		(end 134.375251 98.074981)
		(width 0.18)
		(layer "F.Cu")
		(net 42)
	)
	(segment
		(start 130.830117 99.211787)
		(end 130.374406 99.6675)
		(width 0.18)
		(layer "F.Cu")
		(net 42)
	)
	(segment
		(start 135.48 97.4575)
		(end 135.400594 97.4575)
		(width 0.18)
		(layer "F.Cu")
		(net 42)
	)
	(segment
		(start 130.374406 99.6675)
		(end 129.317501 99.6675)
		(width 0.18)
		(layer "F.Cu")
		(net 42)
	)
	(segment
		(start 136.68 98.54)
		(end 136.48 98.54)
		(width 0.18)
		(layer "F.Cu")
		(net 42)
	)
	(segment
		(start 130.830116 99.211787)
		(end 130.830117 99.211787)
		(width 0.18)
		(layer "F.Cu")
		(net 42)
	)
	(segment
		(start 135.68 97.4575)
		(end 135.48 97.4575)
		(width 0.18)
		(layer "F.Cu")
		(net 42)
	)
	(segment
		(start 134.375251 98.074981)
		(end 134.165251 98.284981)
		(width 0.18)
		(layer "F.Cu")
		(net 42)
	)
	(segment
		(start 137.2625 97.675)
		(end 137.2625 97.9575)
		(width 0.18)
		(layer "F.Cu")
		(net 42)
	)
	(segment
		(start 130.830116 99.024505)
		(end 130.830117 99.024506)
		(width 0.18)
		(layer "F.Cu")
		(net 42)
	)
	(segment
		(start 143.706512 97.4575)
		(end 137.48 97.4575)
		(width 0.18)
		(layer "F.Cu")
		(net 42)
	)
	(segment
		(start 145.787006 99.633453)
		(end 145.787006 99.537994)
		(width 0.18)
		(layer "F.Cu")
		(net 42)
	)
	(segment
		(start 135.380297 97.477797)
		(end 134.783113 98.074981)
		(width 0.18)
		(layer "F.Cu")
		(net 42)
	)
	(segment
		(start 145.787006 99.537994)
		(end 143.706512 97.4575)
		(width 0.18)
		(layer "F.Cu")
		(net 42)
	)
	(segment
		(start 129.250001 99.6)
		(end 128.35 99.6)
		(width 0.18)
		(layer "F.Cu")
		(net 42)
	)
	(segment
		(start 130.99639 98.670952)
		(end 130.996389 98.670953)
		(width 0.18)
		(layer "F.Cu")
		(net 42)
	)
	(segment
		(start 131.4925 98.549406)
		(end 131.370953 98.670953)
		(width 0.18)
		(layer "F.Cu")
		(net 42)
	)
	(segment
		(start 135.400594 97.4575)
		(end 135.380297 97.477797)
		(width 0.18)
		(layer "F.Cu")
		(net 42)
	)
	(segment
		(start 129.317501 99.6675)
		(end 129.250001 99.6)
		(width 0.18)
		(layer "F.Cu")
		(net 42)
	)
	(segment
		(start 131.4925 97.16)
		(end 131.4925 98.549406)
		(width 0.18)
		(layer "F.Cu")
		(net 42)
	)
	(segment
		(start 146.12972 99.976167)
		(end 145.787006 99.633453)
		(width 0.18)
		(layer "F.Cu")
		(net 42)
	)
	(segment
		(start 131.2825 96.95)
		(end 131.4925 97.16)
		(width 0.18)
		(layer "F.Cu")
		(net 42)
	)
	(segment
		(start 135.8975 97.9575)
		(end 135.8975 97.675)
		(width 0.18)
		(layer "F.Cu")
		(net 42)
	)
	(via
		(at 131.2825 96.95)
		(size 0.6)
		(drill 0.35)
		(layers "F.Cu" "B.Cu")
		(net 42)
	)
	(via
		(at 134.165251 98.284981)
		(size 0.6)
		(drill 0.35)
		(layers "F.Cu" "B.Cu")
		(net 42)
	)
	(arc
		(start 130.830117 98.837224)
		(mid 130.791329 98.930864)
		(end 130.830116 99.024505)
		(width 0.18)
		(layer "F.Cu")
		(net 42)
	)
	(arc
		(start 131.183671 98.670953)
		(mid 131.090031 98.632165)
		(end 130.99639 98.670952)
		(width 0.18)
		(layer "F.Cu")
		(net 42)
	)
	(arc
		(start 130.830117 99.024506)
		(mid 130.868904 99.118147)
		(end 130.830116 99.211787)
		(width 0.18)
		(layer "F.Cu")
		(net 42)
	)
	(arc
		(start 136.48 98.54)
		(mid 136.06811 98.36939)
		(end 135.8975 97.9575)
		(width 0.18)
		(layer "F.Cu")
		(net 42)
	)
	(arc
		(start 135.8975 97.675)
		(mid 135.833796 97.521204)
		(end 135.68 97.4575)
		(width 0.18)
		(layer "F.Cu")
		(net 42)
	)
	(arc
		(start 137.48 97.4575)
		(mid 137.326204 97.521204)
		(end 137.2625 97.675)
		(width 0.18)
		(layer "F.Cu")
		(net 42)
	)
	(arc
		(start 131.370953 98.670953)
		(mid 131.277312 98.70974)
		(end 131.183671 98.670953)
		(width 0.18)
		(layer "F.Cu")
		(net 42)
	)
	(arc
		(start 137.2625 97.9575)
		(mid 137.09189 98.36939)
		(end 136.68 98.54)
		(width 0.18)
		(layer "F.Cu")
		(net 42)
	)
	(segment
		(start 131.991887 98.074981)
		(end 133.955251 98.074981)
		(width 0.18)
		(layer "B.Cu")
		(net 42)
	)
	(segment
		(start 131.2825 96.95)
		(end 131.4925 97.16)
		(width 0.18)
		(layer "B.Cu")
		(net 42)
	)
	(segment
		(start 133.955251 98.074981)
		(end 134.165251 98.284981)
		(width 0.18)
		(layer "B.Cu")
		(net 42)
	)
	(segment
		(start 131.4925 97.16)
		(end 131.4925 97.575594)
		(width 0.18)
		(layer "B.Cu")
		(net 42)
	)
	(segment
		(start 131.4925 97.575594)
		(end 131.991887 98.074981)
		(width 0.18)
		(layer "B.Cu")
		(net 42)
	)
	(segment
		(start 131.8575 97.16)
		(end 132.0675 96.95)
		(width 0.18)
		(layer "F.Cu")
		(net 44)
	)
	(segment
		(start 128.35 100.1)
		(end 129.250001 100.1)
		(width 0.18)
		(layer "F.Cu")
		(net 44)
	)
	(segment
		(start 129.250001 100.1)
		(end 129.317501 100.0325)
		(width 0.18)
		(layer "F.Cu")
		(net 44)
	)
	(segment
		(start 135.48 97.0925)
		(end 135.249406 97.0925)
		(width 0.18)
		(layer "F.Cu")
		(net 44)
	)
	(segment
		(start 146.0451 99.2799)
		(end 143.8577 97.0925)
		(width 0.18)
		(layer "F.Cu")
		(net 44)
	)
	(segment
		(start 146.14056 99.2799)
		(end 146.0451 99.2799)
		(width 0.18)
		(layer "F.Cu")
		(net 44)
	)
	(segment
		(start 146.483274 99.622614)
		(end 146.14056 99.2799)
		(width 0.18)
		(layer "F.Cu")
		(net 44)
	)
	(segment
		(start 136.68 98.175)
		(end 136.48 98.175)
		(width 0.18)
		(layer "F.Cu")
		(net 44)
	)
	(segment
		(start 135.122203 97.219703)
		(end 134.631925 97.709981)
		(width 0.18)
		(layer "F.Cu")
		(net 44)
	)
	(segment
		(start 134.631925 97.709981)
		(end 134.375251 97.709981)
		(width 0.18)
		(layer "F.Cu")
		(net 44)
	)
	(segment
		(start 136.2625 97.9575)
		(end 136.2625 97.675)
		(width 0.18)
		(layer "F.Cu")
		(net 44)
	)
	(segment
		(start 130.525594 100.0325)
		(end 131.8575 98.700594)
		(width 0.18)
		(layer "F.Cu")
		(net 44)
	)
	(segment
		(start 135.249406 97.0925)
		(end 135.122203 97.219703)
		(width 0.18)
		(layer "F.Cu")
		(net 44)
	)
	(segment
		(start 135.68 97.0925)
		(end 135.48 97.0925)
		(width 0.18)
		(layer "F.Cu")
		(net 44)
	)
	(segment
		(start 136.8975 97.675)
		(end 136.8975 97.9575)
		(width 0.18)
		(layer "F.Cu")
		(net 44)
	)
	(segment
		(start 143.8577 97.0925)
		(end 137.48 97.0925)
		(width 0.18)
		(layer "F.Cu")
		(net 44)
	)
	(segment
		(start 129.317501 100.0325)
		(end 130.525594 100.0325)
		(width 0.18)
		(layer "F.Cu")
		(net 44)
	)
	(segment
		(start 131.8575 98.700594)
		(end 131.8575 97.16)
		(width 0.18)
		(layer "F.Cu")
		(net 44)
	)
	(segment
		(start 134.375251 97.709981)
		(end 134.165251 97.499981)
		(width 0.18)
		(layer "F.Cu")
		(net 44)
	)
	(via
		(at 132.0675 96.95)
		(size 0.6)
		(drill 0.35)
		(layers "F.Cu" "B.Cu")
		(net 44)
	)
	(via
		(at 134.165251 97.499981)
		(size 0.6)
		(drill 0.35)
		(layers "F.Cu" "B.Cu")
		(net 44)
	)
	(arc
		(start 136.48 98.175)
		(mid 136.326204 98.111296)
		(end 136.2625 97.9575)
		(width 0.18)
		(layer "F.Cu")
		(net 44)
	)
	(arc
		(start 136.2625 97.675)
		(mid 136.09189 97.26311)
		(end 135.68 97.0925)
		(width 0.18)
		(layer "F.Cu")
		(net 44)
	)
	(arc
		(start 136.8975 97.9575)
		(mid 136.833796 98.111296)
		(end 136.68 98.175)
		(width 0.18)
		(layer "F.Cu")
		(net 44)
	)
	(arc
		(start 137.48 97.0925)
		(mid 137.06811 97.26311)
		(end 136.8975 97.675)
		(width 0.18)
		(layer "F.Cu")
		(net 44)
	)
	(segment
		(start 132.0675 96.95)
		(end 131.8575 97.16)
		(width 0.18)
		(layer "B.Cu")
		(net 44)
	)
	(segment
		(start 133.955251 97.709981)
		(end 134.165251 97.499981)
		(width 0.18)
		(layer "B.Cu")
		(net 44)
	)
	(segment
		(start 132.143075 97.709981)
		(end 133.955251 97.709981)
		(width 0.18)
		(layer "B.Cu")
		(net 44)
	)
	(segment
		(start 131.8575 97.424406)
		(end 132.143075 97.709981)
		(width 0.18)
		(layer "B.Cu")
		(net 44)
	)
	(segment
		(start 131.8575 97.16)
		(end 131.8575 97.424406)
		(width 0.18)
		(layer "B.Cu")
		(net 44)
	)
	(segment
		(start 129.250001 100.6)
		(end 128.35 100.6)
		(width 0.18)
		(layer "F.Cu")
		(net 50)
	)
	(segment
		(start 143.985 105.6575)
		(end 144.8077 105.6575)
		(width 0.18)
		(layer "F.Cu")
		(net 50)
	)
	(segment
		(start 143.775 105.8675)
		(end 143.985 105.6575)
		(width 0.18)
		(layer "F.Cu")
		(net 50)
	)
	(segment
		(start 146.11556 104.4451)
		(end 146.0201 104.4451)
		(width 0.18)
		(layer "F.Cu")
		(net 50)
	)
	(segment
		(start 129.317501 100.6675)
		(end 129.250001 100.6)
		(width 0.18)
		(layer "F.Cu")
		(net 50)
	)
	(segment
		(start 139.8825 106.49)
		(end 139.8825 103.774406)
		(width 0.18)
		(layer "F.Cu")
		(net 50)
	)
	(segment
		(start 144.8077 105.6575)
		(end 146.0201 104.4451)
		(width 0.18)
		(layer "F.Cu")
		(net 50)
	)
	(segment
		(start 146.483274 104.077386)
		(end 146.11556 104.4451)
		(width 0.18)
		(layer "F.Cu")
		(net 50)
	)
	(segment
		(start 136.775594 100.6675)
		(end 129.317501 100.6675)
		(width 0.18)
		(layer "F.Cu")
		(net 50)
	)
	(segment
		(start 139.8825 103.774406)
		(end 136.775594 100.6675)
		(width 0.18)
		(layer "F.Cu")
		(net 50)
	)
	(segment
		(start 140.0925 106.7)
		(end 139.8825 106.49)
		(width 0.18)
		(layer "F.Cu")
		(net 50)
	)
	(via
		(at 143.775 105.8675)
		(size 0.6)
		(drill 0.35)
		(layers "F.Cu" "B.Cu")
		(net 50)
	)
	(via
		(at 140.0925 106.7)
		(size 0.6)
		(drill 0.35)
		(layers "F.Cu" "B.Cu")
		(net 50)
	)
	(segment
		(start 140.0925 106.7)
		(end 139.8825 106.49)
		(width 0.18)
		(layer "B.Cu")
		(net 50)
	)
	(segment
		(start 139.8825 106.050594)
		(end 140.275594 105.6575)
		(width 0.18)
		(layer "B.Cu")
		(net 50)
	)
	(segment
		(start 143.565 105.6575)
		(end 143.775 105.8675)
		(width 0.18)
		(layer "B.Cu")
		(net 50)
	)
	(segment
		(start 140.275594 105.6575)
		(end 143.565 105.6575)
		(width 0.18)
		(layer "B.Cu")
		(net 50)
	)
	(segment
		(start 139.8825 106.49)
		(end 139.8825 106.050594)
		(width 0.18)
		(layer "B.Cu")
		(net 50)
	)
	(segment
		(start 139.3075 106.7)
		(end 139.5175 106.49)
		(width 0.18)
		(layer "F.Cu")
		(net 51)
	)
	(segment
		(start 143.985 105.2925)
		(end 144.656512 105.2925)
		(width 0.18)
		(layer "F.Cu")
		(net 51)
	)
	(segment
		(start 144.656512 105.2925)
		(end 145.774506 104.174506)
		(width 0.18)
		(layer "F.Cu")
		(net 51)
	)
	(segment
		(start 139.5175 106.49)
		(end 139.5175 105.11485)
		(width 0.18)
		(layer "F.Cu")
		(net 51)
	)
	(segment
		(start 139.5175 103.925594)
		(end 136.624406 101.0325)
		(width 0.18)
		(layer "F.Cu")
		(net 51)
	)
	(segment
		(start 143.775 105.0825)
		(end 143.985 105.2925)
		(width 0.18)
		(layer "F.Cu")
		(net 51)
	)
	(segment
		(start 146.12972 103.723833)
		(end 145.774506 104.079047)
		(width 0.18)
		(layer "F.Cu")
		(net 51)
	)
	(segment
		(start 129.250001 101.1)
		(end 128.35 101.1)
		(width 0.18)
		(layer "F.Cu")
		(net 51)
	)
	(segment
		(start 139.252649 104.85)
		(end 139.252649 104.61485)
		(width 0.18)
		(layer "F.Cu")
		(net 51)
	)
	(segment
		(start 129.317501 101.0325)
		(end 129.250001 101.1)
		(width 0.18)
		(layer "F.Cu")
		(net 51)
	)
	(segment
		(start 136.624406 101.0325)
		(end 129.317501 101.0325)
		(width 0.18)
		(layer "F.Cu")
		(net 51)
	)
	(segment
		(start 139.385075 104.982425)
		(end 139.385074 104.982425)
		(width 0.18)
		(layer "F.Cu")
		(net 51)
	)
	(segment
		(start 139.385074 104.482425)
		(end 139.385075 104.482425)
		(width 0.18)
		(layer "F.Cu")
		(net 51)
	)
	(segment
		(start 139.5175 104.000594)
		(end 139.5175 103.925594)
		(width 0.18)
		(layer "F.Cu")
		(net 51)
	)
	(segment
		(start 145.774506 104.079047)
		(end 145.774506 104.174506)
		(width 0.18)
		(layer "F.Cu")
		(net 51)
	)
	(segment
		(start 139.5175 104.35)
		(end 139.5175 104.000594)
		(width 0.18)
		(layer "F.Cu")
		(net 51)
	)
	(via
		(at 143.775 105.0825)
		(size 0.6)
		(drill 0.35)
		(layers "F.Cu" "B.Cu")
		(net 51)
	)
	(via
		(at 139.3075 106.7)
		(size 0.6)
		(drill 0.35)
		(layers "F.Cu" "B.Cu")
		(net 51)
	)
	(arc
		(start 139.5175 105.11485)
		(mid 139.478714 105.021211)
		(end 139.385075 104.982425)
		(width 0.18)
		(layer "F.Cu")
		(net 51)
	)
	(arc
		(start 139.252649 104.61485)
		(mid 139.291435 104.521211)
		(end 139.385074 104.482425)
		(width 0.18)
		(layer "F.Cu")
		(net 51)
	)
	(arc
		(start 139.385074 104.982425)
		(mid 139.291435 104.943639)
		(end 139.252649 104.85)
		(width 0.18)
		(layer "F.Cu")
		(net 51)
	)
	(arc
		(start 139.385075 104.482425)
		(mid 139.478714 104.443639)
		(end 139.5175 104.35)
		(width 0.18)
		(layer "F.Cu")
		(net 51)
	)
	(segment
		(start 139.5175 105.899406)
		(end 140.124406 105.2925)
		(width 0.18)
		(layer "B.Cu")
		(net 51)
	)
	(segment
		(start 140.124406 105.2925)
		(end 143.565 105.2925)
		(width 0.18)
		(layer "B.Cu")
		(net 51)
	)
	(segment
		(start 139.5175 106.49)
		(end 139.5175 105.899406)
		(width 0.18)
		(layer "B.Cu")
		(net 51)
	)
	(segment
		(start 143.565 105.2925)
		(end 143.775 105.0825)
		(width 0.18)
		(layer "B.Cu")
		(net 51)
	)
	(segment
		(start 139.3075 106.7)
		(end 139.5175 106.49)
		(width 0.18)
		(layer "B.Cu")
		(net 51)
	)
	(segment
		(start 142.47246 100.944446)
		(end 142.47246 100.64746)
		(width 0.18)
		(layer "F.Cu")
		(net 56)
	)
	(segment
		(start 142.2175 101.199406)
		(end 142.47246 100.944446)
		(width 0.18)
		(layer "F.Cu")
		(net 56)
	)
	(segment
		(start 145.06906 102.663173)
		(end 144.738846 102.993387)
		(width 0.18)
		(layer "F.Cu")
		(net 56)
	)
	(segment
		(start 127.383499 101.6665)
		(end 126.402372 101.6665)
		(width 0.18)
		(layer "F.Cu")
		(net 56)
	)
	(segment
		(start 127.449999 101.6)
		(end 127.383499 101.6665)
		(width 0.18)
		(layer "F.Cu")
		(net 56)
	)
	(segment
		(start 144.479274 103.1575)
		(end 143.449406 103.1575)
		(width 0.18)
		(layer "F.Cu")
		(net 56)
	)
	(segment
		(start 144.738846 102.993387)
		(end 144.643387 102.993387)
		(width 0.18)
		(layer "F.Cu")
		(net 56)
	)
	(segment
		(start 142.2175 101.925594)
		(end 142.2175 101.199406)
		(width 0.18)
		(layer "F.Cu")
		(net 56)
	)
	(segment
		(start 144.643387 102.993387)
		(end 144.479274 103.1575)
		(width 0.18)
		(layer "F.Cu")
		(net 56)
	)
	(segment
		(start 126.402372 101.6665)
		(end 126.192372 101.4565)
		(width 0.18)
		(layer "F.Cu")
		(net 56)
	)
	(segment
		(start 128.35 101.6)
		(end 127.449999 101.6)
		(width 0.18)
		(layer "F.Cu")
		(net 56)
	)
	(segment
		(start 143.449406 103.1575)
		(end 142.2175 101.925594)
		(width 0.18)
		(layer "F.Cu")
		(net 56)
	)
	(via
		(at 126.192372 101.4565)
		(size 0.6)
		(drill 0.35)
		(layers "F.Cu" "B.Cu")
		(net 56)
	)
	(via
		(at 142.47246 100.64746)
		(size 0.6)
		(drill 0.35)
		(layers "F.Cu" "B.Cu")
		(net 56)
	)
	(segment
		(start 142.47246 100.944446)
		(end 142.47246 100.64746)
		(width 0.18)
		(layer "B.Cu")
		(net 56)
	)
	(segment
		(start 126.402372 101.6665)
		(end 141.750406 101.6665)
		(width 0.18)
		(layer "B.Cu")
		(net 56)
	)
	(segment
		(start 126.192372 101.4565)
		(end 126.402372 101.6665)
		(width 0.18)
		(layer "B.Cu")
		(net 56)
	)
	(segment
		(start 141.750406 101.6665)
		(end 142.47246 100.944446)
		(width 0.18)
		(layer "B.Cu")
		(net 56)
	)
	(segment
		(start 144.328086 102.7925)
		(end 143.600594 102.7925)
		(width 0.18)
		(layer "F.Cu")
		(net 57)
	)
	(segment
		(start 142.5825 101.774406)
		(end 142.5825 101.350594)
		(width 0.18)
		(layer "F.Cu")
		(net 57)
	)
	(segment
		(start 128.35 102.098)
		(end 127.449999 102.098)
		(width 0.18)
		(layer "F.Cu")
		(net 57)
	)
	(segment
		(start 144.715507 102.309619)
		(end 144.397793 102.627333)
		(width 0.18)
		(layer "F.Cu")
		(net 57)
	)
	(segment
		(start 142.730554 101.20254)
		(end 143.02754 101.20254)
		(width 0.18)
		(layer "F.Cu")
		(net 57)
	)
	(segment
		(start 143.529047 102.367399)
		(end 143.647964 102.248481)
		(width 0.18)
		(layer "F.Cu")
		(net 57)
	)
	(segment
		(start 143.600594 102.7925)
		(end 143.529047 102.720953)
		(width 0.18)
		(layer "F.Cu")
		(net 57)
	)
	(segment
		(start 143.294411 101.894926)
		(end 143.29441 101.894927)
		(width 0.18)
		(layer "F.Cu")
		(net 57)
	)
	(segment
		(start 142.82194 102.013846)
		(end 142.5825 101.774406)
		(width 0.18)
		(layer "F.Cu")
		(net 57)
	)
	(segment
		(start 126.402372 102.0315)
		(end 126.192372 102.2415)
		(width 0.18)
		(layer "F.Cu")
		(net 57)
	)
	(segment
		(start 143.529046 102.3674)
		(end 143.529047 102.367399)
		(width 0.18)
		(layer "F.Cu")
		(net 57)
	)
	(segment
		(start 142.5825 101.350594)
		(end 142.730554 101.20254)
		(width 0.18)
		(layer "F.Cu")
		(net 57)
	)
	(segment
		(start 127.449999 102.098)
		(end 127.383499 102.0315)
		(width 0.18)
		(layer "F.Cu")
		(net 57)
	)
	(segment
		(start 127.383499 102.0315)
		(end 126.402372 102.0315)
		(width 0.18)
		(layer "F.Cu")
		(net 57)
	)
	(segment
		(start 144.397793 102.722793)
		(end 144.328086 102.7925)
		(width 0.18)
		(layer "F.Cu")
		(net 57)
	)
	(segment
		(start 143.29441 101.894927)
		(end 143.175492 102.013844)
		(width 0.18)
		(layer "F.Cu")
		(net 57)
	)
	(segment
		(start 144.397793 102.627333)
		(end 144.397793 102.722793)
		(width 0.18)
		(layer "F.Cu")
		(net 57)
	)
	(segment
		(start 142.821938 102.013844)
		(end 142.82194 102.013846)
		(width 0.18)
		(layer "F.Cu")
		(net 57)
	)
	(via
		(at 143.02754 101.20254)
		(size 0.6)
		(drill 0.35)
		(layers "F.Cu" "B.Cu")
		(net 57)
	)
	(via
		(at 126.192372 102.2415)
		(size 0.6)
		(drill 0.35)
		(layers "F.Cu" "B.Cu")
		(net 57)
	)
	(arc
		(start 143.175492 102.013844)
		(mid 142.998715 102.087067)
		(end 142.821938 102.013844)
		(width 0.18)
		(layer "F.Cu")
		(net 57)
	)
	(arc
		(start 143.647964 102.248481)
		(mid 143.721187 102.071704)
		(end 143.647964 101.894927)
		(width 0.18)
		(layer "F.Cu")
		(net 57)
	)
	(arc
		(start 143.647964 101.894927)
		(mid 143.471188 101.821703)
		(end 143.294411 101.894926)
		(width 0.18)
		(layer "F.Cu")
		(net 57)
	)
	(arc
		(start 143.529047 102.720953)
		(mid 143.455823 102.544177)
		(end 143.529046 102.3674)
		(width 0.18)
		(layer "F.Cu")
		(net 57)
	)
	(segment
		(start 126.402372 102.0315)
		(end 141.901594 102.0315)
		(width 0.18)
		(layer "B.Cu")
		(net 57)
	)
	(segment
		(start 141.901594 102.0315)
		(end 142.730554 101.20254)
		(width 0.18)
		(layer "B.Cu")
		(net 57)
	)
	(segment
		(start 142.730554 101.20254)
		(end 143.02754 101.20254)
		(width 0.18)
		(layer "B.Cu")
		(net 57)
	)
	(segment
		(start 126.192372 102.2415)
		(end 126.402372 102.0315)
		(width 0.18)
		(layer "B.Cu")
		(net 57)
	)
	(segment
		(start 161.12 85.598)
		(end 160.325 85.598)
		(width 0.3)
		(layer "F.Cu")
		(net 58)
	)
	(segment
		(start 158.747 96.878)
		(end 159.222 96.878)
		(width 0.3)
		(layer "F.Cu")
		(net 58)
	)
	(segment
		(start 158.89 91.865)
		(end 158.89 89.662)
		(width 0.5)
		(layer "F.Cu")
		(net 58)
	)
	(segment
		(start 158.89 89.662)
		(end 158.89 87.985)
		(width 0.5)
		(layer "F.Cu")
		(net 58)
	)
	(segment
		(start 159.65 87.225)
		(end 159.65 86.273)
		(width 0.5)
		(layer "F.Cu")
		(net 58)
	)
	(segment
		(start 159.222 96.878)
		(end 159.512 96.588)
		(width 0.3)
		(layer "F.Cu")
		(net 58)
	)
	(segment
		(start 158.89 87.985)
		(end 159.65 87.225)
		(width 0.5)
		(layer "F.Cu")
		(net 58)
	)
	(segment
		(start 160.325 85.598)
		(end 160.0615 85.8615)
		(width 0.3)
		(layer "F.Cu")
		(net 58)
	)
	(segment
		(start 159.512 96.588)
		(end 159.512 94.742)
		(width 0.3)
		(layer "F.Cu")
		(net 58)
	)
	(segment
		(start 159.65 86.273)
		(end 160.0615 85.8615)
		(width 0.5)
		(layer "F.Cu")
		(net 58)
	)
	(segment
		(start 159.512 92.487)
		(end 158.89 91.865)
		(width 0.5)
		(layer "F.Cu")
		(net 58)
	)
	(segment
		(start 159.512 94.742)
		(end 159.512 92.487)
		(width 0.5)
		(layer "F.Cu")
		(net 58)
	)
	(segment
		(start 157.328 96.878)
		(end 156.972 96.522)
		(width 0.3)
		(layer "F.Cu")
		(net 59)
	)
	(segment
		(start 156.972 96.522)
		(end 156.972 94.742)
		(width 0.3)
		(layer "F.Cu")
		(net 59)
	)
	(segment
		(start 157.787 96.878)
		(end 157.328 96.878)
		(width 0.3)
		(layer "F.Cu")
		(net 59)
	)
	(segment
		(start 156.972 94.742)
		(end 156.972 92.2)
		(width 0.5)
		(layer "F.Cu")
		(net 59)
	)
	(segment
		(start 155.702 92.2)
		(end 154.27 92.2)
		(width 0.5)
		(layer "F.Cu")
		(net 60)
	)
	(segment
		(start 137.941185 104.986362)
		(end 137.941185 104.358091)
		(width 0.18)
		(layer "F.Cu")
		(net 61)
	)
	(segment
		(start 137.941185 104.358091)
		(end 136.749594 103.1665)
		(width 0.18)
		(layer "F.Cu")
		(net 61)
	)
	(segment
		(start 132.4 103.1665)
		(end 131.9 103.1665)
		(width 0.18)
		(layer "F.Cu")
		(net 61)
	)
	(segment
		(start 145.433453 103.712994)
		(end 145.776167 103.37028)
		(width 0.18)
		(layer "F.Cu")
		(net 61)
	)
	(segment
		(start 144.643488 104.4075)
		(end 145.337994 103.712994)
		(width 0.18)
		(layer "F.Cu")
		(net 61)
	)
	(segment
		(start 143.574406 104.4075)
		(end 144.643488 104.4075)
		(width 0.18)
		(layer "F.Cu")
		(net 61)
	)
	(segment
		(start 132.8175 102.5465)
		(end 132.8175 102.949)
		(width 0.18)
		(layer "F.Cu")
		(net 61)
	)
	(segment
		(start 134.6 104.369)
		(end 134.4 104.369)
		(width 0.18)
		(layer "F.Cu")
		(net 61)
	)
	(segment
		(start 143.299406 104.1325)
		(end 143.574406 104.4075)
		(width 0.18)
		(layer "F.Cu")
		(net 61)
	)
	(segment
		(start 134.8175 103.749)
		(end 134.8175 104.1515)
		(width 0.18)
		(layer "F.Cu")
		(net 61)
	)
	(segment
		(start 134.1825 104.1515)
		(end 134.1825 103.749)
		(width 0.18)
		(layer "F.Cu")
		(net 61)
	)
	(segment
		(start 129.317501 103.1665)
		(end 129.250001 103.099)
		(width 0.18)
		(layer "F.Cu")
		(net 61)
	)
	(segment
		(start 136.749594 103.1665)
		(end 135.4 103.1665)
		(width 0.18)
		(layer "F.Cu")
		(net 61)
	)
	(segment
		(start 129.250001 103.099)
		(end 128.35 103.099)
		(width 0.18)
		(layer "F.Cu")
		(net 61)
	)
	(segment
		(start 138.151185 105.196362)
		(end 137.941185 104.986362)
		(width 0.18)
		(layer "F.Cu")
		(net 61)
	)
	(segment
		(start 133.6 101.964)
		(end 133.4 101.964)
		(width 0.18)
		(layer "F.Cu")
		(net 61)
	)
	(segment
		(start 141.95 104.3425)
		(end 142.16 104.1325)
		(width 0.18)
		(layer "F.Cu")
		(net 61)
	)
	(segment
		(start 134.1825 103.749)
		(end 134.1825 102.5465)
		(width 0.18)
		(layer "F.Cu")
		(net 61)
	)
	(segment
		(start 132.6 103.1665)
		(end 132.4 103.1665)
		(width 0.18)
		(layer "F.Cu")
		(net 61)
	)
	(segment
		(start 131.9 103.1665)
		(end 129.317501 103.1665)
		(width 0.18)
		(layer "F.Cu")
		(net 61)
	)
	(segment
		(start 145.337994 103.712994)
		(end 145.433453 103.712994)
		(width 0.18)
		(layer "F.Cu")
		(net 61)
	)
	(segment
		(start 142.16 104.1325)
		(end 143.299406 104.1325)
		(width 0.18)
		(layer "F.Cu")
		(net 61)
	)
	(via
		(at 141.95 104.3425)
		(size 0.6)
		(drill 0.35)
		(layers "F.Cu" "B.Cu")
		(net 61)
	)
	(via
		(at 138.151185 105.196362)
		(size 0.6)
		(drill 0.35)
		(layers "F.Cu" "B.Cu")
		(net 61)
	)
	(arc
		(start 134.4 104.369)
		(mid 134.246204 104.305296)
		(end 134.1825 104.1515)
		(width 0.18)
		(layer "F.Cu")
		(net 61)
	)
	(arc
		(start 133.4 101.964)
		(mid 132.98811 102.13461)
		(end 132.8175 102.5465)
		(width 0.18)
		(layer "F.Cu")
		(net 61)
	)
	(arc
		(start 132.8175 102.949)
		(mid 132.753796 103.102796)
		(end 132.6 103.1665)
		(width 0.18)
		(layer "F.Cu")
		(net 61)
	)
	(arc
		(start 134.1825 102.5465)
		(mid 134.01189 102.13461)
		(end 133.6 101.964)
		(width 0.18)
		(layer "F.Cu")
		(net 61)
	)
	(arc
		(start 135.4 103.1665)
		(mid 134.98811 103.33711)
		(end 134.8175 103.749)
		(width 0.18)
		(layer "F.Cu")
		(net 61)
	)
	(arc
		(start 134.8175 104.1515)
		(mid 134.753796 104.305296)
		(end 134.6 104.369)
		(width 0.18)
		(layer "F.Cu")
		(net 61)
	)
	(segment
		(start 141.74 104.1325)
		(end 141.95 104.3425)
		(width 0.18)
		(layer "B.Cu")
		(net 61)
	)
	(segment
		(start 137.941185 104.986362)
		(end 137.941185 104.700863)
		(width 0.18)
		(layer "B.Cu")
		(net 61)
	)
	(segment
		(start 138.151185 105.196362)
		(end 137.941185 104.986362)
		(width 0.18)
		(layer "B.Cu")
		(net 61)
	)
	(segment
		(start 138.509548 104.1325)
		(end 141.74 104.1325)
		(width 0.18)
		(layer "B.Cu")
		(net 61)
	)
	(segment
		(start 137.941185 104.700863)
		(end 138.509548 104.1325)
		(width 0.18)
		(layer "B.Cu")
		(net 61)
	)
	(segment
		(start 133.755 82.971)
		(end 133.755 80.575)
		(width 0.2)
		(layer "F.Cu")
		(net 62)
	)
	(segment
		(start 135.135 79.195)
		(end 135.83 79.195)
		(width 0.2)
		(layer "F.Cu")
		(net 62)
	)
	(segment
		(start 133.28 83.446)
		(end 133.755 82.971)
		(width 0.2)
		(layer "F.Cu")
		(net 62)
	)
	(segment
		(start 133.755 80.575)
		(end 135.135 79.195)
		(width 0.2)
		(layer "F.Cu")
		(net 62)
	)
	(segment
		(start 132.48 83.446)
		(end 133.28 83.446)
		(width 0.2)
		(layer "F.Cu")
		(net 62)
	)
	(segment
		(start 135.83 79.195)
		(end 136.855 79.195)
		(width 0.3)
		(layer "F.Cu")
		(net 62)
	)
	(segment
		(start 159.406233 100.993767)
		(end 160.498767 100.993767)
		(width 0.3)
		(layer "F.Cu")
		(net 63)
	)
	(segment
		(start 163.47 97.125)
		(end 163.47 98.125)
		(width 0.3)
		(layer "F.Cu")
		(net 63)
	)
	(segment
		(start 162.575 97.1)
		(end 163.44 97.1)
		(width 0.3)
		(layer "F.Cu")
		(net 63)
	)
	(segment
		(start 163.44 97.1)
		(end 163.465 97.125)
		(width 0.3)
		(layer "F.Cu")
		(net 63)
	)
	(via
		(at 162.575 97.1)
		(size 0.6)
		(drill 0.35)
		(layers "F.Cu" "B.Cu")
		(net 63)
	)
	(via
		(at 159.406233 100.993767)
		(size 0.6)
		(drill 0.35)
		(layers "F.Cu" "B.Cu")
		(net 63)
	)
	(segment
		(start 159.406233 100.268767)
		(end 159.406233 100.993767)
		(width 0.3)
		(layer "B.Cu")
		(net 63)
	)
	(segment
		(start 162.575 97.1)
		(end 159.406233 100.268767)
		(width 0.3)
		(layer "B.Cu")
		(net 63)
	)
	(segment
		(start 132.655 80.15)
		(end 132.655 81.196)
		(width 0.2)
		(layer "F.Cu")
		(net 64)
	)
	(segment
		(start 132.65 82.326)
		(end 132.48 82.496)
		(width 0.3)
		(layer "F.Cu")
		(net 64)
	)
	(segment
		(start 132.65 81.196)
		(end 132.65 82.326)
		(width 0.3)
		(layer "F.Cu")
		(net 64)
	)
	(segment
		(start 160.501 97.8)
		(end 160.501 100.046)
		(width 0.3)
		(layer "F.Cu")
		(net 65)
	)
	(segment
		(start 149.875 108.585)
		(end 149.665 108.795)
		(width 0.2)
		(layer "F.Cu")
		(net 66)
	)
	(segment
		(start 149.665 105.375)
		(end 149.665 106.705)
		(width 0.2)
		(layer "F.Cu")
		(net 66)
	)
	(segment
		(start 149.875 106.915)
		(end 149.875 108.585)
		(width 0.2)
		(layer "F.Cu")
		(net 66)
	)
	(segment
		(start 148.635 110.28)
		(end 149.665 110.28)
		(width 0.2)
		(layer "F.Cu")
		(net 66)
	)
	(segment
		(start 149.665 106.705)
		(end 149.875 106.915)
		(width 0.2)
		(layer "F.Cu")
		(net 66)
	)
	(segment
		(start 149.665 108.795)
		(end 149.665 110.28)
		(width 0.2)
		(layer "F.Cu")
		(net 66)
	)
	(segment
		(start 149.665 104.92566)
		(end 149.665 105.375)
		(width 0.2)
		(layer "F.Cu")
		(net 66)
	)
	(segment
		(start 148.816726 104.077386)
		(end 149.665 104.92566)
		(width 0.2)
		(layer "F.Cu")
		(net 66)
	)
	(segment
		(start 150.584493 101.390381)
		(end 151.047927 100.926947)
		(width 0.2)
		(layer "F.Cu")
		(net 67)
	)
	(segment
		(start 151.225 100.926947)
		(end 152.565053 100.926947)
		(width 0.2)
		(layer "F.Cu")
		(net 67)
	)
	(segment
		(start 151.047927 100.926947)
		(end 151.225 100.926947)
		(width 0.2)
		(layer "F.Cu")
		(net 67)
	)
	(segment
		(start 151.073382 100.926947)
		(end 151.225 100.926947)
		(width 0.2)
		(layer "F.Cu")
		(net 67)
	)
	(segment
		(start 150.07 104.623553)
		(end 150.07 104.85)
		(width 0.2)
		(layer "F.Cu")
		(net 68)
	)
	(segment
		(start 150.35 108.725)
		(end 150.35 106.56)
		(width 0.2)
		(layer "F.Cu")
		(net 68)
	)
	(segment
		(start 150.225 111.9)
		(end 151.025 111.9)
		(width 0.2)
		(layer "F.Cu")
		(net 68)
	)
	(segment
		(start 151.225 111.7)
		(end 151.225 109.6)
		(width 0.2)
		(layer "F.Cu")
		(net 68)
	)
	(segment
		(start 151.025 111.9)
		(end 151.225 111.7)
		(width 0.2)
		(layer "F.Cu")
		(net 68)
	)
	(segment
		(start 150.07 106.28)
		(end 150.07 104.85)
		(width 0.2)
		(layer "F.Cu")
		(net 68)
	)
	(segment
		(start 151.225 109.6)
		(end 150.35 108.725)
		(width 0.2)
		(layer "F.Cu")
		(net 68)
	)
	(segment
		(start 149.68 111.355)
		(end 150.225 111.9)
		(width 0.2)
		(layer "F.Cu")
		(net 68)
	)
	(segment
		(start 150.35 106.56)
		(end 150.07 106.28)
		(width 0.2)
		(layer "F.Cu")
		(net 68)
	)
	(segment
		(start 148.63 111.355)
		(end 149.68 111.355)
		(width 0.2)
		(layer "F.Cu")
		(net 68)
	)
	(segment
		(start 149.17028 103.723833)
		(end 150.07 104.623553)
		(width 0.2)
		(layer "F.Cu")
		(net 68)
	)
	(segment
		(start 141.1 115.07)
		(end 142.23 115.07)
		(width 0.2)
		(layer "F.Cu")
		(net 69)
	)
	(segment
		(start 142.23 115.07)
		(end 142.25 115.05)
		(width 0.2)
		(layer "F.Cu")
		(net 69)
	)
	(segment
		(start 150.5 113.318)
		(end 150.518 113.3)
		(width 0.2)
		(layer "F.Cu")
		(net 70)
	)
	(segment
		(start 150.5 115.05)
		(end 150.5 113.318)
		(width 0.2)
		(layer "F.Cu")
		(net 70)
	)
	(segment
		(start 149.365 116.45)
		(end 149.345 116.43)
		(width 0.2)
		(layer "F.Cu")
		(net 71)
	)
	(segment
		(start 150.5 116.45)
		(end 149.365 116.45)
		(width 0.2)
		(layer "F.Cu")
		(net 71)
	)
	(segment
		(start 141.075 86.205142)
		(end 141.075 86.910142)
		(width 0.3)
		(layer "F.Cu")
		(net 72)
	)
	(segment
		(start 139.56 85.330142)
		(end 140.2 85.330142)
		(width 0.3)
		(layer "F.Cu")
		(net 72)
	)
	(segment
		(start 140.2 85.330142)
		(end 141.075 86.205142)
		(width 0.3)
		(layer "F.Cu")
		(net 72)
	)
	(segment
		(start 146.773 114.173)
		(end 147.65 115.05)
		(width 0.2)
		(layer "F.Cu")
		(net 73)
	)
	(segment
		(start 147.65 115.05)
		(end 147.75 115.05)
		(width 0.2)
		(layer "F.Cu")
		(net 73)
	)
	(segment
		(start 146.773 113.225)
		(end 146.773 114.173)
		(width 0.2)
		(layer "F.Cu")
		(net 73)
	)
	(segment
		(start 147.725 116.475)
		(end 147.75 116.45)
		(width 0.2)
		(layer "F.Cu")
		(net 74)
	)
	(segment
		(start 146.55 116.475)
		(end 147.725 116.475)
		(width 0.2)
		(layer "F.Cu")
		(net 74)
	)
	(segment
		(start 138.35 115.045)
		(end 139.495 115.045)
		(width 0.2)
		(layer "F.Cu")
		(net 75)
	)
	(segment
		(start 139.495 115.045)
		(end 139.5 115.05)
		(width 0.2)
		(layer "F.Cu")
		(net 75)
	)
	(segment
		(start 150.624035 100.643732)
		(end 150.718732 100.643732)
		(width 0.2)
		(layer "F.Cu")
		(net 76)
	)
	(segment
		(start 150.23094 101.036827)
		(end 150.624035 100.643732)
		(width 0.2)
		(layer "F.Cu")
		(net 76)
	)
	(segment
		(start 151.172032 100.190431)
		(end 151.726536 100.190431)
		(width 0.2)
		(layer "F.Cu")
		(net 76)
	)
	(segment
		(start 150.718732 100.643732)
		(end 151.172032 100.190431)
		(width 0.2)
		(layer "F.Cu")
		(net 76)
	)
	(segment
		(start 148.109619 104.784493)
		(end 148.635 105.309874)
		(width 0.2)
		(layer "F.Cu")
		(net 77)
	)
	(segment
		(start 148.635 105.75)
		(end 148.635 109.205)
		(width 0.2)
		(layer "F.Cu")
		(net 77)
	)
	(segment
		(start 148.635 105.309874)
		(end 148.635 105.75)
		(width 0.2)
		(layer "F.Cu")
		(net 77)
	)
	(segment
		(start 135.885 109.884)
		(end 143.441 109.884)
		(width 0.2)
		(layer "F.Cu")
		(net 78)
	)
	(segment
		(start 146.836827 104.43094)
		(end 146.16 105.107767)
		(width 0.2)
		(layer "F.Cu")
		(net 78)
	)
	(segment
		(start 143.441 109.884)
		(end 146.16 107.165)
		(width 0.2)
		(layer "F.Cu")
		(net 78)
	)
	(segment
		(start 146.16 107.165)
		(end 146.16 105.134637)
		(width 0.2)
		(layer "F.Cu")
		(net 78)
	)
	(segment
		(start 146.16 105.107767)
		(end 146.16 105.134637)
		(width 0.2)
		(layer "F.Cu")
		(net 78)
	)
	(segment
		(start 146.71 105.264874)
		(end 146.71 105.575)
		(width 0.2)
		(layer "F.Cu")
		(net 79)
	)
	(segment
		(start 146.71 107.14)
		(end 146.71 105.575)
		(width 0.2)
		(layer "F.Cu")
		(net 79)
	)
	(segment
		(start 147.190381 104.784493)
		(end 146.71 105.264874)
		(width 0.2)
		(layer "F.Cu")
		(net 79)
	)
	(segment
		(start 135.885 110.95)
		(end 142.9 110.95)
		(width 0.2)
		(layer "F.Cu")
		(net 79)
	)
	(segment
		(start 142.9 110.95)
		(end 146.71 107.14)
		(width 0.2)
		(layer "F.Cu")
		(net 79)
	)
	(segment
		(start 136.598406 103.5315)
		(end 135.4 103.5315)
		(width 0.18)
		(layer "F.Cu")
		(net 80)
	)
	(segment
		(start 132.4 103.5315)
		(end 131.9 103.5315)
		(width 0.18)
		(layer "F.Cu")
		(net 80)
	)
	(segment
		(start 129.317501 103.5315)
		(end 129.250001 103.599)
		(width 0.18)
		(layer "F.Cu")
		(net 80)
	)
	(segment
		(start 141.95 103.5575)
		(end 142.16 103.7675)
		(width 0.18)
		(layer "F.Cu")
		(net 80)
	)
	(segment
		(start 137.366185 105.196362)
		(end 137.576185 104.986362)
		(width 0.18)
		(layer "F.Cu")
		(net 80)
	)
	(segment
		(start 137.576185 104.986362)
		(end 137.576185 104.509279)
		(width 0.18)
		(layer "F.Cu")
		(net 80)
	)
	(segment
		(start 145.0924 103.4424)
		(end 145.0924 103.34694)
		(width 0.18)
		(layer "F.Cu")
		(net 80)
	)
	(segment
		(start 136.983881 104.291547)
		(end 136.817613 104.125279)
		(width 0.18)
		(layer "F.Cu")
		(net 80)
	)
	(segment
		(start 133.6 102.329)
		(end 133.4 102.329)
		(width 0.18)
		(layer "F.Cu")
		(net 80)
	)
	(segment
		(start 133.1825 102.5465)
		(end 133.1825 102.949)
		(width 0.18)
		(layer "F.Cu")
		(net 80)
	)
	(segment
		(start 142.16 103.7675)
		(end 143.450594 103.7675)
		(width 0.18)
		(layer "F.Cu")
		(net 80)
	)
	(segment
		(start 143.450594 103.7675)
		(end 143.725594 104.0425)
		(width 0.18)
		(layer "F.Cu")
		(net 80)
	)
	(segment
		(start 145.0924 103.34694)
		(end 145.422614 103.016726)
		(width 0.18)
		(layer "F.Cu")
		(net 80)
	)
	(segment
		(start 134.6 104.734)
		(end 134.4 104.734)
		(width 0.18)
		(layer "F.Cu")
		(net 80)
	)
	(segment
		(start 137.171168 104.291546)
		(end 137.171167 104.291547)
		(width 0.18)
		(layer "F.Cu")
		(net 80)
	)
	(segment
		(start 136.817613 103.750707)
		(end 136.598406 103.5315)
		(width 0.18)
		(layer "F.Cu")
		(net 80)
	)
	(segment
		(start 129.250001 103.599)
		(end 128.35 103.599)
		(width 0.18)
		(layer "F.Cu")
		(net 80)
	)
	(segment
		(start 132.6 103.5315)
		(end 132.4 103.5315)
		(width 0.18)
		(layer "F.Cu")
		(net 80)
	)
	(segment
		(start 144.4923 104.0425)
		(end 145.0924 103.4424)
		(width 0.18)
		(layer "F.Cu")
		(net 80)
	)
	(segment
		(start 133.8175 103.749)
		(end 133.8175 102.5465)
		(width 0.18)
		(layer "F.Cu")
		(net 80)
	)
	(segment
		(start 133.8175 104.1515)
		(end 133.8175 103.749)
		(width 0.18)
		(layer "F.Cu")
		(net 80)
	)
	(segment
		(start 131.9 103.5315)
		(end 129.317501 103.5315)
		(width 0.18)
		(layer "F.Cu")
		(net 80)
	)
	(segment
		(start 135.1825 103.749)
		(end 135.1825 104.1515)
		(width 0.18)
		(layer "F.Cu")
		(net 80)
	)
	(segment
		(start 137.576185 104.509279)
		(end 137.358453 104.291547)
		(width 0.18)
		(layer "F.Cu")
		(net 80)
	)
	(segment
		(start 143.725594 104.0425)
		(end 144.4923 104.0425)
		(width 0.18)
		(layer "F.Cu")
		(net 80)
	)
	(via
		(at 141.95 103.5575)
		(size 0.6)
		(drill 0.35)
		(layers "F.Cu" "B.Cu")
		(net 80)
	)
	(via
		(at 137.366185 105.196362)
		(size 0.6)
		(drill 0.35)
		(layers "F.Cu" "B.Cu")
		(net 80)
	)
	(arc
		(start 137.171167 104.291547)
		(mid 137.077523 104.330334)
		(end 136.983881 104.291547)
		(width 0.18)
		(layer "F.Cu")
		(net 80)
	)
	(arc
		(start 136.817613 104.125279)
		(mid 136.778824 104.031635)
		(end 136.817613 103.937993)
		(width 0.18)
		(layer "F.Cu")
		(net 80)
	)
	(arc
		(start 135.4 103.5315)
		(mid 135.246204 103.595204)
		(end 135.1825 103.749)
		(width 0.18)
		(layer "F.Cu")
		(net 80)
	)
	(arc
		(start 135.1825 104.1515)
		(mid 135.01189 104.56339)
		(end 134.6 104.734)
		(width 0.18)
		(layer "F.Cu")
		(net 80)
	)
	(arc
		(start 133.8175 102.5465)
		(mid 133.753796 102.392704)
		(end 133.6 102.329)
		(width 0.18)
		(layer "F.Cu")
		(net 80)
	)
	(arc
		(start 137.358453 104.291547)
		(mid 137.264811 104.252759)
		(end 137.171168 104.291546)
		(width 0.18)
		(layer "F.Cu")
		(net 80)
	)
	(arc
		(start 136.817613 103.937993)
		(mid 136.8564 103.844349)
		(end 136.817613 103.750707)
		(width 0.18)
		(layer "F.Cu")
		(net 80)
	)
	(arc
		(start 133.4 102.329)
		(mid 133.246204 102.392704)
		(end 133.1825 102.5465)
		(width 0.18)
		(layer "F.Cu")
		(net 80)
	)
	(arc
		(start 133.1825 102.949)
		(mid 133.01189 103.36089)
		(end 132.6 103.5315)
		(width 0.18)
		(layer "F.Cu")
		(net 80)
	)
	(arc
		(start 134.4 104.734)
		(mid 133.98811 104.56339)
		(end 133.8175 104.1515)
		(width 0.18)
		(layer "F.Cu")
		(net 80)
	)
	(segment
		(start 138.35836 103.7675)
		(end 141.74 103.7675)
		(width 0.18)
		(layer "B.Cu")
		(net 80)
	)
	(segment
		(start 137.366185 105.196362)
		(end 137.576185 104.986362)
		(width 0.18)
		(layer "B.Cu")
		(net 80)
	)
	(segment
		(start 137.576185 104.549675)
		(end 138.35836 103.7675)
		(width 0.18)
		(layer "B.Cu")
		(net 80)
	)
	(segment
		(start 137.576185 104.986362)
		(end 137.576185 104.549675)
		(width 0.18)
		(layer "B.Cu")
		(net 80)
	)
	(segment
		(start 141.74 103.7675)
		(end 141.95 103.5575)
		(width 0.18)
		(layer "B.Cu")
		(net 80)
	)
	(segment
		(start 149.523833 103.37028)
		(end 150.8 104.646447)
		(width 0.2)
		(layer "F.Cu")
		(net 81)
	)
	(segment
		(start 150.8 104.646447)
		(end 150.8 105)
		(width 0.2)
		(layer "F.Cu")
		(net 81)
	)
	(segment
		(start 135.885 107.7)
		(end 136.65 107.7)
		(width 0.2)
		(layer "F.Cu")
		(net 81)
	)
	(via
		(at 150.8 105)
		(size 0.6)
		(drill 0.35)
		(layers "F.Cu" "B.Cu")
		(net 81)
	)
	(via
		(at 136.65 107.7)
		(size 0.6)
		(drill 0.35)
		(layers "F.Cu" "B.Cu")
		(net 81)
	)
	(segment
		(start 138.2 109.25)
		(end 136.65 107.7)
		(width 0.2)
		(layer "B.Cu")
		(net 81)
	)
	(segment
		(start 149.2 105)
		(end 144.95 109.25)
		(width 0.2)
		(layer "B.Cu")
		(net 81)
	)
	(segment
		(start 144.95 109.25)
		(end 138.2 109.25)
		(width 0.2)
		(layer "B.Cu")
		(net 81)
	)
	(segment
		(start 150.8 105)
		(end 149.2 105)
		(width 0.2)
		(layer "B.Cu")
		(net 81)
	)
	(segment
		(start 151.325 105.275)
		(end 151.325 104.825)
		(width 0.2)
		(layer "F.Cu")
		(net 82)
	)
	(segment
		(start 150.8 105.8)
		(end 151.325 105.275)
		(width 0.2)
		(layer "F.Cu")
		(net 82)
	)
	(segment
		(start 151.325 104.46434)
		(end 151.325 104.825)
		(width 0.2)
		(layer "F.Cu")
		(net 82)
	)
	(segment
		(start 149.877386 103.016726)
		(end 151.325 104.46434)
		(width 0.2)
		(layer "F.Cu")
		(net 82)
	)
	(segment
		(start 135.885 108.75)
		(end 136.65 108.75)
		(width 0.2)
		(layer "F.Cu")
		(net 82)
	)
	(via
		(at 150.8 105.8)
		(size 0.6)
		(drill 0.35)
		(layers "F.Cu" "B.Cu")
		(net 82)
	)
	(via
		(at 136.65 108.75)
		(size 0.6)
		(drill 0.35)
		(layers "F.Cu" "B.Cu")
		(net 82)
	)
	(segment
		(start 145.21 109.75)
		(end 137.65 109.75)
		(width 0.2)
		(layer "B.Cu")
		(net 82)
	)
	(segment
		(start 150.8 105.8)
		(end 149.16 105.8)
		(width 0.2)
		(layer "B.Cu")
		(net 82)
	)
	(segment
		(start 137.65 109.75)
		(end 136.65 108.75)
		(width 0.2)
		(layer "B.Cu")
		(net 82)
	)
	(segment
		(start 149.16 105.8)
		(end 145.21 109.75)
		(width 0.2)
		(layer "B.Cu")
		(net 82)
	)
	(segment
		(start 149.15 106.81)
		(end 149.35 107.01)
		(width 0.2)
		(layer "F.Cu")
		(net 83)
	)
	(segment
		(start 149.15 105.117767)
		(end 149.15 105.7)
		(width 0.2)
		(layer "F.Cu")
		(net 83)
	)
	(segment
		(start 149.15 105.7)
		(end 149.15 106.81)
		(width 0.2)
		(layer "F.Cu")
		(net 83)
	)
	(segment
		(start 149.35 107.01)
		(end 149.35 107.7)
		(width 0.2)
		(layer "F.Cu")
		(net 83)
	)
	(segment
		(start 148.463173 104.43094)
		(end 149.15 105.117767)
		(width 0.2)
		(layer "F.Cu")
		(net 83)
	)
	(via
		(at 149.35 107.7)
		(size 0.6)
		(drill 0.35)
		(layers "F.Cu" "B.Cu")
		(net 83)
	)
	(via
		(at 153.25 118)
		(size 0.6)
		(drill 0.35)
		(layers "F.Cu" "B.Cu")
		(net 83)
	)
	(segment
		(start 152.525 107.7)
		(end 149.35 107.7)
		(width 0.2)
		(layer "B.Cu")
		(net 83)
	)
	(segment
		(start 155.6 112.95962)
		(end 154.075 111.434619)
		(width 0.2)
		(layer "B.Cu")
		(net 83)
	)
	(segment
		(start 153.25 118)
		(end 155.6 115.65)
		(width 0.2)
		(layer "B.Cu")
		(net 83)
	)
	(segment
		(start 154.075 111.434619)
		(end 154.075 109.25)
		(width 0.2)
		(layer "B.Cu")
		(net 83)
	)
	(segment
		(start 155.6 115.65)
		(end 155.6 112.95962)
		(width 0.2)
		(layer "B.Cu")
		(net 83)
	)
	(segment
		(start 154.075 109.25)
		(end 152.525 107.7)
		(width 0.2)
		(layer "B.Cu")
		(net 83)
	)
	(segment
		(start 144.532872 99.017128)
		(end 144.882872 99.367128)
		(width 0.2)
		(layer "F.Cu")
		(net 84)
	)
	(segment
		(start 144.05 98.725)
		(end 144.342128 99.017128)
		(width 0.2)
		(layer "F.Cu")
		(net 84)
	)
	(segment
		(start 144.342128 99.017128)
		(end 144.532872 99.017128)
		(width 0.2)
		(layer "F.Cu")
		(net 84)
	)
	(segment
		(start 145.776167 100.32972)
		(end 144.882872 99.436425)
		(width 0.2)
		(layer "F.Cu")
		(net 84)
	)
	(segment
		(start 144.882872 99.436425)
		(end 144.882872 99.367128)
		(width 0.2)
		(layer "F.Cu")
		(net 84)
	)
	(via
		(at 158.75 118)
		(size 0.6)
		(drill 0.35)
		(layers "F.Cu" "B.Cu")
		(net 84)
	)
	(via
		(at 144.05 98.725)
		(size 0.6)
		(drill 0.35)
		(layers "F.Cu" "B.Cu")
		(net 84)
	)
	(segment
		(start 151 103.8)
		(end 152.075 104.875001)
		(width 0.2)
		(layer "B.Cu")
		(net 84)
	)
	(segment
		(start 158.75 115.15)
		(end 158.75 118)
		(width 0.2)
		(layer "B.Cu")
		(net 84)
	)
	(segment
		(start 146.88462 103.8)
		(end 151 103.8)
		(width 0.2)
		(layer "B.Cu")
		(net 84)
	)
	(segment
		(start 152.075 104.875001)
		(end 152.075 106.31538)
		(width 0.2)
		(layer "B.Cu")
		(net 84)
	)
	(segment
		(start 154.725 111.125)
		(end 158.75 115.15)
		(width 0.2)
		(layer "B.Cu")
		(net 84)
	)
	(segment
		(start 144.05 98.725)
		(end 144.174999 98.725)
		(width 0.2)
		(layer "B.Cu")
		(net 84)
	)
	(segment
		(start 144.174999 98.725)
		(end 145.575 100.125001)
		(width 0.2)
		(layer "B.Cu")
		(net 84)
	)
	(segment
		(start 152.075 106.31538)
		(end 154.725 108.96538)
		(width 0.2)
		(layer "B.Cu")
		(net 84)
	)
	(segment
		(start 154.725 108.96538)
		(end 154.725 111.125)
		(width 0.2)
		(layer "B.Cu")
		(net 84)
	)
	(segment
		(start 145.575 102.49038)
		(end 146.88462 103.8)
		(width 0.2)
		(layer "B.Cu")
		(net 84)
	)
	(segment
		(start 145.575 100.125001)
		(end 145.575 102.49038)
		(width 0.2)
		(layer "B.Cu")
		(net 84)
	)
	(segment
		(start 144.310572 99.571232)
		(end 144.278768 99.571232)
		(width 0.2)
		(layer "F.Cu")
		(net 85)
	)
	(segment
		(start 145.422614 100.683274)
		(end 144.310572 99.571232)
		(width 0.2)
		(layer "F.Cu")
		(net 85)
	)
	(via
		(at 156 118)
		(size 0.6)
		(drill 0.35)
		(layers "F.Cu" "B.Cu")
		(net 85)
	)
	(via
		(at 144.278768 99.571232)
		(size 0.6)
		(drill 0.35)
		(layers "F.Cu" "B.Cu")
		(net 85)
	)
	(segment
		(start 156 112.9)
		(end 156 118)
		(width 0.2)
		(layer "B.Cu")
		(net 85)
	)
	(segment
		(start 145.25 100.825308)
		(end 145.25 102.625)
		(width 0.2)
		(layer "B.Cu")
		(net 85)
	)
	(segment
		(start 144.278768 99.854075)
		(end 145.25 100.825308)
		(width 0.2)
		(layer "B.Cu")
		(net 85)
	)
	(segment
		(start 154.4 111.3)
		(end 156 112.9)
		(width 0.2)
		(layer "B.Cu")
		(net 85)
	)
	(segment
		(start 144.278768 99.571232)
		(end 144.278768 99.854075)
		(width 0.2)
		(layer "B.Cu")
		(net 85)
	)
	(segment
		(start 151.75 105.00962)
		(end 151.75 106.45)
		(width 0.2)
		(layer "B.Cu")
		(net 85)
	)
	(segment
		(start 151.75 106.45)
		(end 154.4 109.1)
		(width 0.2)
		(layer "B.Cu")
		(net 85)
	)
	(segment
		(start 154.4 109.1)
		(end 154.4 111.3)
		(width 0.2)
		(layer "B.Cu")
		(net 85)
	)
	(segment
		(start 150.86538 104.125)
		(end 151.75 105.00962)
		(width 0.2)
		(layer "B.Cu")
		(net 85)
	)
	(segment
		(start 145.25 102.625)
		(end 146.75 104.125)
		(width 0.2)
		(layer "B.Cu")
		(net 85)
	)
	(segment
		(start 146.75 104.125)
		(end 150.86538 104.125)
		(width 0.2)
		(layer "B.Cu")
		(net 85)
	)
	(segment
		(start 134.574 105.574)
		(end 134.575 105.575)
		(width 0.2)
		(layer "F.Cu")
		(net 87)
	)
	(segment
		(start 146.1 98.532233)
		(end 146.836827 99.26906)
		(width 0.2)
		(layer "F.Cu")
		(net 87)
	)
	(segment
		(start 146.1 98.5)
		(end 146.1 98.532233)
		(width 0.2)
		(layer "F.Cu")
		(net 87)
	)
	(segment
		(start 133.58 105.574)
		(end 134.574 105.574)
		(width 0.2)
		(layer "F.Cu")
		(net 87)
	)
	(via
		(at 134.575 105.575)
		(size 0.6)
		(drill 0.35)
		(layers "F.Cu" "B.Cu")
		(net 87)
	)
	(via
		(at 146.1 98.5)
		(size 0.6)
		(drill 0.35)
		(layers "F.Cu" "B.Cu")
		(net 87)
	)
	(segment
		(start 144.925 102.759619)
		(end 144.925 100.959927)
		(width 0.2)
		(layer "B.Cu")
		(net 87)
	)
	(segment
		(start 143.475 99.509927)
		(end 143.475 98.557537)
		(width 0.2)
		(layer "B.Cu")
		(net 87)
	)
	(segment
		(start 145.4 106.225)
		(end 145.4 103.23462)
		(width 0.2)
		(layer "B.Cu")
		(net 87)
	)
	(segment
		(start 145.4 103.23462)
		(end 144.925 102.759619)
		(width 0.2)
		(layer "B.Cu")
		(net 87)
	)
	(segment
		(start 143.275 108.35)
		(end 145.4 106.225)
		(width 0.2)
		(layer "B.Cu")
		(net 87)
	)
	(segment
		(start 145.8 98.2)
		(end 146.1 98.5)
		(width 0.2)
		(layer "B.Cu")
		(net 87)
	)
	(segment
		(start 135.31538 105.575)
		(end 138.09038 108.35)
		(width 0.2)
		(layer "B.Cu")
		(net 87)
	)
	(segment
		(start 134.575 105.575)
		(end 135.31538 105.575)
		(width 0.2)
		(layer "B.Cu")
		(net 87)
	)
	(segment
		(start 138.09038 108.35)
		(end 143.275 108.35)
		(width 0.2)
		(layer "B.Cu")
		(net 87)
	)
	(segment
		(start 143.832537 98.2)
		(end 145.8 98.2)
		(width 0.2)
		(layer "B.Cu")
		(net 87)
	)
	(segment
		(start 144.925 100.959927)
		(end 143.475 99.509927)
		(width 0.2)
		(layer "B.Cu")
		(net 87)
	)
	(segment
		(start 143.475 98.557537)
		(end 143.832537 98.2)
		(width 0.2)
		(layer "B.Cu")
		(net 87)
	)
	(segment
		(start 133.585 107.7)
		(end 134.915 107.7)
		(width 0.2)
		(layer "F.Cu")
		(net 88)
	)
	(segment
		(start 134.155 111.98)
		(end 134.175 112)
		(width 0.2)
		(layer "F.Cu")
		(net 88)
	)
	(segment
		(start 133.585 111.98)
		(end 134.155 111.98)
		(width 0.2)
		(layer "F.Cu")
		(net 88)
	)
	(segment
		(start 133.586 109.884)
		(end 134.915 109.884)
		(width 0.2)
		(layer "F.Cu")
		(net 88)
	)
	(via
		(at 134.175 112)
		(size 0.6)
		(drill 0.35)
		(layers "F.Cu" "B.Cu")
		(net 88)
	)
	(via
		(at 134.249999 109.884)
		(size 0.6)
		(drill 0.35)
		(layers "F.Cu" "B.Cu")
		(net 88)
	)
	(via
		(at 134.249999 107.7)
		(size 0.6)
		(drill 0.35)
		(layers "F.Cu" "B.Cu")
		(net 88)
	)
	(segment
		(start 134.249999 109.884)
		(end 133.509 109.884)
		(width 0.2)
		(layer "B.Cu")
		(net 88)
	)
	(segment
		(start 133.5 108.449999)
		(end 134.249999 107.7)
		(width 0.2)
		(layer "B.Cu")
		(net 88)
	)
	(segment
		(start 134.175 112)
		(end 133.5 111.325)
		(width 0.2)
		(layer "B.Cu")
		(net 88)
	)
	(segment
		(start 133.5 111.325)
		(end 133.5 109.875)
		(width 0.2)
		(layer "B.Cu")
		(net 88)
	)
	(segment
		(start 133.5 109.875)
		(end 133.5 108.449999)
		(width 0.2)
		(layer "B.Cu")
		(net 88)
	)
	(segment
		(start 133.509 109.884)
		(end 133.5 109.875)
		(width 0.2)
		(layer "B.Cu")
		(net 88)
	)
	(segment
		(start 134.915 110.95)
		(end 134.915 111.98)
		(width 0.2)
		(layer "F.Cu")
		(net 89)
	)
	(segment
		(start 133.585 108.75)
		(end 134.915 108.75)
		(width 0.2)
		(layer "F.Cu")
		(net 89)
	)
	(segment
		(start 133.585 110.95)
		(end 134.915 110.95)
		(width 0.2)
		(layer "F.Cu")
		(net 89)
	)
	(via
		(at 134.249999 110.95)
		(size 0.6)
		(drill 0.35)
		(layers "F.Cu" "B.Cu")
		(net 89)
	)
	(via
		(at 134.249999 108.75)
		(size 0.6)
		(drill 0.35)
		(layers "F.Cu" "B.Cu")
		(net 89)
	)
	(segment
		(start 134.249999 108.75)
		(end 134.9 109.400001)
		(width 0.2)
		(layer "B.Cu")
		(net 89)
	)
	(segment
		(start 134.9 109.400001)
		(end 134.9 110.299999)
		(width 0.2)
		(layer "B.Cu")
		(net 89)
	)
	(segment
		(start 134.9 110.299999)
		(end 134.249999 110.95)
		(width 0.2)
		(layer "B.Cu")
		(net 89)
	)
	(segment
		(start 152.561 106.191)
		(end 153.43 106.191)
		(width 0.2)
		(layer "F.Cu")
		(net 90)
	)
	(segment
		(start 152.234239 105.125)
		(end 152.234239 105.864239)
		(width 0.2)
		(layer "F.Cu")
		(net 90)
	)
	(segment
		(start 152.234239 104.666472)
		(end 152.234239 105.125)
		(width 0.2)
		(layer "F.Cu")
		(net 90)
	)
	(segment
		(start 152.234239 105.864239)
		(end 152.561 106.191)
		(width 0.2)
		(layer "F.Cu")
		(net 90)
	)
	(segment
		(start 150.23094 102.663173)
		(end 152.234239 104.666472)
		(width 0.2)
		(layer "F.Cu")
		(net 90)
	)
	(segment
		(start 130.075 106.599)
		(end 130.925 106.599)
		(width 0.2)
		(layer "F.Cu")
		(net 91)
	)
	(segment
		(start 130.925 107.099)
		(end 130.075 107.099)
		(width 0.2)
		(layer "F.Cu")
		(net 92)
	)
	(segment
		(start 140.88 84.380142)
		(end 139.52 84.380142)
		(width 0.3)
		(layer "F.Cu")
		(net 93)
	)
	(segment
		(start 143.425 86.23)
		(end 143.425 86.910142)
		(width 0.3)
		(layer "F.Cu")
		(net 94)
	)
	(segment
		(start 140.35 81.060142)
		(end 139.8 81.060142)
		(width 0.2)
		(layer "F.Cu")
		(net 94)
	)
	(segment
		(start 145.1 86.23)
		(end 143.425 86.23)
		(width 0.3)
		(layer "F.Cu")
		(net 94)
	)
	(segment
		(start 145.295 87.970142)
		(end 143.425 87.970142)
		(width 0.3)
		(layer "F.Cu")
		(net 94)
	)
	(segment
		(start 139.8 81.060142)
		(end 139.53 81.330142)
		(width 0.2)
		(layer "F.Cu")
		(net 94)
	)
	(segment
		(start 143.425 87.970142)
		(end 143.425 86.910142)
		(width 0.3)
		(layer "F.Cu")
		(net 94)
	)
	(segment
		(start 139.53 81.330142)
		(end 139.53 83.160142)
		(width 0.2)
		(layer "F.Cu")
		(net 94)
	)
	(via
		(at 144.8 87.05)
		(size 0.6)
		(drill 0.35)
		(layers "F.Cu" "B.Cu")
		(net 94)
	)
	(via
		(at 139.57 83.340142)
		(size 0.6)
		(drill 0.35)
		(layers "F.Cu" "B.Cu")
		(net 94)
	)
	(segment
		(start 139.53 83.160142)
		(end 139.53 83.280142)
		(width 0.2)
		(layer "B.Cu")
		(net 94)
	)
	(segment
		(start 143.299858 87.05)
		(end 144.8 87.05)
		(width 0.2)
		(layer "B.Cu")
		(net 94)
	)
	(segment
		(start 139.53 83.280142)
		(end 143.299858 87.05)
		(width 0.2)
		(layer "B.Cu")
		(net 94)
	)
	(segment
		(start 144.995 115.045)
		(end 145 115.05)
		(width 0.2)
		(layer "F.Cu")
		(net 95)
	)
	(segment
		(start 143.85 115.045)
		(end 144.995 115.045)
		(width 0.2)
		(layer "F.Cu")
		(net 95)
	)
	(segment
		(start 141.31 81.060142)
		(end 141.25 81.120142)
		(width 0.3)
		(layer "F.Cu")
		(net 96)
	)
	(segment
		(start 141.25 82.042142)
		(end 140.896 82.396142)
		(width 0.3)
		(layer "F.Cu")
		(net 96)
	)
	(segment
		(start 141.25 81.120142)
		(end 141.25 82.042142)
		(width 0.3)
		(layer "F.Cu")
		(net 96)
	)
	(segment
		(start 141.31 79.980142)
		(end 141.31 81.060142)
		(width 0.3)
		(layer "F.Cu")
		(net 96)
	)
	(segment
		(start 142.13 82.920142)
		(end 141.704 83.346142)
		(width 0.2)
		(layer "F.Cu")
		(net 97)
	)
	(segment
		(start 141.704 83.346142)
		(end 140.896 83.346142)
		(width 0.2)
		(layer "F.Cu")
		(net 97)
	)
	(segment
		(start 142.85 79.220142)
		(end 142.13 79.940142)
		(width 0.2)
		(layer "F.Cu")
		(net 97)
	)
	(segment
		(start 143.69 79.220142)
		(end 142.85 79.220142)
		(width 0.2)
		(layer "F.Cu")
		(net 97)
	)
	(segment
		(start 142.13 79.940142)
		(end 142.13 82.920142)
		(width 0.2)
		(layer "F.Cu")
		(net 97)
	)
	(segment
		(start 143.7075 79.210142)
		(end 144.7325 79.210142)
		(width 0.3)
		(layer "F.Cu")
		(net 97)
	)
	(zone
		(net 9)
		(net_name "+5V")
		(layer "F.Cu")
		(name "+1V2")
		(hatch none 0.508)
		(priority 1)
		(connect_pads
			(clearance 0.2)
		)
		(min_thickness 0.2)
		(filled_areas_thickness no)
		(fill yes
			(thermal_gap 0.508)
			(thermal_bridge_width 0.508)
			(smoothing fillet)
			(radius 0.25)
		)
		(polygon
			(pts
				(xy 125.8 92.3) (xy 123.9 92.3) (xy 123.9 89.75) (xy 125.8 89.75)
			)
		)
	)
	(zone
		(net 2)
		(net_name "+12V")
		(layer "F.Cu")
		(name "+12V")
		(hatch edge 0.508)
		(connect_pads
			(clearance 0.2)
		)
		(min_thickness 0.2)
		(filled_areas_thickness no)
		(fill yes
			(thermal_gap 0.2)
			(thermal_bridge_width 0.35)
		)
		(polygon
			(pts
				(xy 166.257694 94.5) (xy 164.017694 94.5) (xy 164.1 86.6) (xy 166.25 86.6)
			)
		)
	)
	(zone
		(net 6)
		(net_name "/Supply/SW_1V8")
		(layer "F.Cu")
		(name "SW_5V")
		(hatch full 0.508)
		(priority 1)
		(connect_pads yes
			(clearance 0.2)
		)
		(min_thickness 0.2)
		(filled_areas_thickness no)
		(fill yes
			(thermal_gap 0.508)
			(thermal_bridge_width 0.508)
			(smoothing fillet)
			(radius 0.25)
		)
		(polygon
			(pts
				(xy 160 102.8) (xy 161.05 102.8) (xy 161.85 100.65) (xy 163.7 100.65) (xy 163.7 101.34) (xy 162.4 101.35)
				(xy 161.1 104.7) (xy 160 104.7)
			)
		)
	)
	(zone
		(net 94)
		(net_name "/Supply/OUT_3V3")
		(layer "F.Cu")
		(name "SW_5V")
		(hatch full 0.508)
		(priority 1)
		(connect_pads
			(clearance 0.2)
		)
		(min_thickness 0.2)
		(filled_areas_thickness no)
		(fill yes
			(thermal_gap 0.15)
			(thermal_bridge_width 0.35)
		)
		(polygon
			(pts
				(xy 146.499454 88.3) (xy 142.749454 88.3) (xy 142.700454 85.5) (xy 144.100454 85.5) (xy 144.600454 85.7)
				(xy 146.500454 85.7)
			)
		)
	)
	(zone
		(net 10)
		(net_name "+3V3")
		(layer "F.Cu")
		(name "SW_5V")
		(hatch full 0.508)
		(priority 1)
		(connect_pads
			(clearance 0.2)
		)
		(min_thickness 0.2)
		(filled_areas_thickness no)
		(fill yes
			(thermal_gap 0.2)
			(thermal_bridge_width 0.35)
			(smoothing fillet)
			(radius 0.25)
		)
		(polygon
			(pts
				(xy 146.6 90.680142) (xy 140 90.730142) (xy 140 88.730142) (xy 146.6 88.680142)
			)
		)
	)
	(zone
		(net 1)
		(net_name "GND")
		(layer "F.Cu")
		(name "GND")
		(hatch full 0.508)
		(connect_pads
			(clearance 0.2)
		)
		(min_thickness 0.2)
		(filled_areas_thickness no)
		(fill yes
			(thermal_gap 0.15)
			(thermal_bridge_width 0.35)
		)
		(polygon
			(pts
				(xy 151.05 77.625) (xy 151.173355 92.324804) (xy 150.625 96.025) (xy 148.275 98.5) (xy 146.475 97.775)
				(xy 145.3 96.6) (xy 144.425 95.9) (xy 123.5 95.575) (xy 123.575 77.725)
			)
		)
	)
	(zone
		(net 72)
		(net_name "/Supply/SW_3V3")
		(layer "F.Cu")
		(name "SW_5V")
		(hatch full 0.508)
		(priority 1)
		(connect_pads yes
			(clearance 0.2)
		)
		(min_thickness 0.2)
		(filled_areas_thickness no)
		(fill yes
			(thermal_gap 0.508)
			(thermal_bridge_width 0.508)
		)
		(polygon
			(pts
				(xy 143.76 83.704784) (xy 142.9 83.70564) (xy 142.5 85.260444) (xy 142.5 88.360444) (xy 140.328922 88.390444)
				(xy 140.328922 85.330444) (xy 141.45 85.330444) (xy 141.759922 84.460408) (xy 141.759922 83.685444)
				(xy 142.359922 83.010444) (xy 143.76 83.010444)
			)
		)
	)
	(zone
		(net 7)
		(net_name "/Supply/OUT_5V")
		(layer "F.Cu")
		(name "SW_5V")
		(hatch full 0.508)
		(priority 1)
		(connect_pads
			(clearance 0.2)
		)
		(min_thickness 0.2)
		(filled_areas_thickness no)
		(fill yes
			(thermal_gap 0.15)
			(thermal_bridge_width 0.35)
		)
		(polygon
			(pts
				(xy 138.029 88.35) (xy 134.279 88.35) (xy 134.23 85.55) (xy 135.63 85.55) (xy 136.13 85.75) (xy 138.03 85.75)
			)
		)
	)
	(zone
		(net 2)
		(net_name "+12V")
		(layer "F.Cu")
		(name "SW_5V")
		(hatch full 0.508)
		(priority 1)
		(connect_pads
			(clearance 0.2)
		)
		(min_thickness 0.2)
		(filled_areas_thickness no)
		(fill yes
			(thermal_gap 0.15)
			(thermal_bridge_width 0.35)
		)
		(polygon
			(pts
				(xy 138.305 82.85) (xy 133.979 82.85) (xy 133.979 81.05) (xy 138.305 81.05)
			)
		)
	)
	(zone
		(net 4)
		(net_name "/Supply/SW_5V")
		(layer "F.Cu")
		(name "SW_5V")
		(hatch full 0.508)
		(priority 1)
		(connect_pads yes
			(clearance 0.2)
		)
		(min_thickness 0.2)
		(filled_areas_thickness no)
		(fill yes
			(thermal_gap 0.508)
			(thermal_bridge_width 0.508)
		)
		(polygon
			(pts
				(xy 135.68 83.79434) (xy 134.43 83.795196) (xy 134.03 85.35) (xy 133.23 88.45) (xy 131.799 88.48)
				(xy 131.799 85.42) (xy 133.03 85.42) (xy 133.43 84.85) (xy 133.43 83.55) (xy 133.83 83.1) (xy 135.68 83.1)
			)
		)
	)
	(zone
		(net 8)
		(net_name "/Supply/OUT_1V8")
		(layer "F.Cu")
		(name "SW_5V")
		(hatch full 0.508)
		(priority 1)
		(connect_pads
			(clearance 0.254)
		)
		(min_thickness 0.254)
		(filled_areas_thickness no)
		(fill yes
			(thermal_gap 0.2)
			(thermal_bridge_width 0.35)
		)
		(polygon
			(pts
				(xy 162.2 102.9) (xy 163.25 102.9) (xy 163.55 103.2) (xy 165.9 103.2) (xy 165.9 105.8) (xy 162.2 105.8)
			)
		)
	)
	(zone
		(net 9)
		(net_name "+5V")
		(layer "F.Cu")
		(name "SW_5V")
		(hatch full 0.508)
		(priority 1)
		(connect_pads
			(clearance 0.2)
		)
		(min_thickness 0.2)
		(filled_areas_thickness no)
		(fill yes
			(thermal_gap 0.2)
			(thermal_bridge_width 0.35)
			(smoothing fillet)
			(radius 0.25)
		)
		(polygon
			(pts
				(xy 138.23 90.9) (xy 134.119669 90.931138) (xy 134.119478 90.17) (xy 131.63 90.15) (xy 131.63 88.95)
				(xy 138.23 88.9)
			)
		)
	)
	(zone
		(net 2)
		(net_name "+12V")
		(layer "F.Cu")
		(name "SW_5V")
		(hatch full 0.508)
		(priority 1)
		(connect_pads
			(clearance 0.2)
		)
		(min_thickness 0.2)
		(filled_areas_thickness no)
		(fill yes
			(thermal_gap 0.15)
			(thermal_bridge_width 0.35)
		)
		(polygon
			(pts
				(xy 146.715 82.765142) (xy 142.389 82.765142) (xy 142.389 80.965142) (xy 146.715 80.965142)
			)
		)
	)
	(zone
		(net 1)
		(net_name "GND")
		(layer "F.Cu")
		(name "GND")
		(hatch full 0.508)
		(connect_pads
			(clearance 0.2)
		)
		(min_thickness 0.2)
		(filled_areas_thickness no)
		(fill yes
			(thermal_gap 0.15)
			(thermal_bridge_width 0.35)
		)
		(polygon
			(pts
				(xy 162.45 103.175) (xy 162.475 101.525) (xy 163.7 101.525) (xy 163.7 100.5) (xy 165.05 100.5) (xy 165.05 99.025)
				(xy 166.575 99.05) (xy 166.675 103.1)
			)
		)
	)
	(zone
		(net 0)
		(net_name "")
		(layers "F.Cu" "In1.Cu")
		(name "GND_CUTOUT")
		(hatch edge 0.508)
		(connect_pads
			(clearance 0)
		)
		(min_thickness 0.254)
		(filled_areas_thickness no)
		(keepout
			(tracks allowed)
			(vias allowed)
			(pads allowed)
			(copperpour not_allowed)
			(footprints allowed)
		)
		(fill
			(thermal_gap 0.508)
			(thermal_bridge_width 0.508)
		)
		(polygon
			(pts
				(xy 150.7087 99.5881) (xy 150.315 99.1944) (xy 150.32 99.0624) (xy 150.6679 98.7145) (xy 151.1251 99.1717)
			)
		)
	)
	(zone
		(net 0)
		(net_name "")
		(layers "F.Cu" "In1.Cu")
		(name "GND_CUTOUT")
		(hatch edge 0.508)
		(connect_pads
			(clearance 0)
		)
		(min_thickness 0.254)
		(filled_areas_thickness no)
		(keepout
			(tracks allowed)
			(vias allowed)
			(pads allowed)
			(copperpour not_allowed)
			(footprints allowed)
		)
		(fill
			(thermal_gap 0.508)
			(thermal_bridge_width 0.508)
		)
		(polygon
			(pts
				(xy 152.1654 98.1164) (xy 151.754 97.705) (xy 152.1504 97.3086) (xy 152.5618 97.72)
			)
		)
	)
	(zone
		(net 0)
		(net_name "")
		(layers "F.Cu" "In1.Cu")
		(name "GND_CUTOUT")
		(hatch edge 0.508)
		(connect_pads
			(clearance 0)
		)
		(min_thickness 0.254)
		(filled_areas_thickness no)
		(keepout
			(tracks allowed)
			(vias allowed)
			(pads allowed)
			(copperpour not_allowed)
			(footprints allowed)
		)
		(fill
			(thermal_gap 0.508)
			(thermal_bridge_width 0.508)
		)
		(polygon
			(pts
				(xy 153.9494 81.7118) (xy 152.0444 81.7118) (xy 152.0444 78.2828) (xy 153.9494 78.2828)
			)
		)
	)
	(zone
		(net 0)
		(net_name "")
		(layers "F.Cu" "In1.Cu")
		(name "GND_CUTOUT")
		(hatch edge 0.508)
		(connect_pads
			(clearance 0)
		)
		(min_thickness 0.254)
		(filled_areas_thickness no)
		(keepout
			(tracks allowed)
			(vias allowed)
			(pads allowed)
			(copperpour not_allowed)
			(footprints allowed)
		)
		(fill
			(thermal_gap 0.508)
			(thermal_bridge_width 0.508)
		)
		(polygon
			(pts
				(xy 153.32 92.71) (xy 152.678 92.71) (xy 152.678 91.694) (xy 153.32 91.694)
			)
		)
	)
	(zone
		(net 0)
		(net_name "")
		(layers "F.Cu" "In1.Cu")
		(name "GND_CUTOUT")
		(hatch edge 0.508)
		(connect_pads
			(clearance 0)
		)
		(min_thickness 0.254)
		(filled_areas_thickness no)
		(keepout
			(tracks allowed)
			(vias allowed)
			(pads allowed)
			(copperpour not_allowed)
			(footprints allowed)
		)
		(fill
			(thermal_gap 0.508)
			(thermal_bridge_width 0.508)
		)
		(polygon
			(pts
				(xy 148.9476 100.405) (xy 148.719 100.1764) (xy 149.354 99.5668) (xy 149.5826 99.7954)
			)
		)
	)
	(zone
		(net 0)
		(net_name "")
		(layers "F.Cu" "In1.Cu")
		(name "GND_CUTOUT")
		(hatch edge 0.508)
		(connect_pads
			(clearance 0)
		)
		(min_thickness 0.254)
		(filled_areas_thickness no)
		(keepout
			(tracks allowed)
			(vias allowed)
			(pads allowed)
			(copperpour not_allowed)
			(footprints allowed)
		)
		(fill
			(thermal_gap 0.508)
			(thermal_bridge_width 0.508)
		)
		(polygon
			(pts
				(xy 150.2024 98.725) (xy 150.05 98.725) (xy 149.669 98.344) (xy 150.0881 97.9249) (xy 150.5453 98.3821)
			)
		)
	)
	(zone
		(net 0)
		(net_name "")
		(layers "F.Cu" "In1.Cu")
		(name "GND_CUTOUT")
		(hatch edge 0.508)
		(connect_pads
			(clearance 0)
		)
		(min_thickness 0.254)
		(filled_areas_thickness no)
		(keepout
			(tracks allowed)
			(vias allowed)
			(pads allowed)
			(copperpour not_allowed)
			(footprints allowed)
		)
		(fill
			(thermal_gap 0.508)
			(thermal_bridge_width 0.508)
		)
		(polygon
			(pts
				(xy 149.320121 100.750068) (xy 149.091521 100.521468) (xy 149.726521 99.911868) (xy 149.955121 100.140468)
			)
		)
	)
	(zone
		(net 0)
		(net_name "")
		(layers "F.Cu" "In1.Cu")
		(name "GND_CUTOUT")
		(hatch edge 0.508)
		(connect_pads
			(clearance 0)
		)
		(min_thickness 0.254)
		(filled_areas_thickness no)
		(keepout
			(tracks allowed)
			(vias allowed)
			(pads allowed)
			(copperpour not_allowed)
			(footprints allowed)
		)
		(fill
			(thermal_gap 0.508)
			(thermal_bridge_width 0.508)
		)
		(polygon
			(pts
				(xy 152.1401 96.7701) (xy 151.6829 96.3129) (xy 152.102 95.8938) (xy 152.5592 96.351)
			)
		)
	)
	(zone
		(net 0)
		(net_name "")
		(layers "F.Cu" "In1.Cu")
		(name "GND_CUTOUT")
		(hatch edge 0.508)
		(connect_pads
			(clearance 0)
		)
		(min_thickness 0.254)
		(filled_areas_thickness no)
		(keepout
			(tracks allowed)
			(vias allowed)
			(pads allowed)
			(copperpour not_allowed)
			(footprints allowed)
		)
		(fill
			(thermal_gap 0.508)
			(thermal_bridge_width 0.508)
		)
		(polygon
			(pts
				(xy 151.4511 97.4542) (xy 150.9939 96.997) (xy 151.413 96.5779) (xy 151.8702 97.0351)
			)
		)
	)
	(zone
		(net 0)
		(net_name "")
		(layers "F.Cu" "In1.Cu")
		(name "GND_CUTOUT")
		(hatch edge 0.508)
		(connect_pads
			(clearance 0)
		)
		(min_thickness 0.254)
		(filled_areas_thickness no)
		(keepout
			(tracks allowed)
			(vias allowed)
			(pads allowed)
			(copperpour not_allowed)
			(footprints allowed)
		)
		(fill
			(thermal_gap 0.508)
			(thermal_bridge_width 0.508)
		)
		(polygon
			(pts
				(xy 150.81 98.115) (xy 150.3578 97.6628) (xy 150.7769 97.2437) (xy 151.2291 97.6959)
			)
		)
	)
	(zone
		(net 0)
		(net_name "")
		(layers "F.Cu" "In1.Cu")
		(name "GND_CUTOUT")
		(hatch edge 0.508)
		(connect_pads
			(clearance 0)
		)
		(min_thickness 0.254)
		(filled_areas_thickness no)
		(keepout
			(tracks allowed)
			(vias allowed)
			(pads allowed)
			(copperpour not_allowed)
			(footprints allowed)
		)
		(fill
			(thermal_gap 0.508)
			(thermal_bridge_width 0.508)
		)
		(polygon
			(pts
				(xy 151.3945 98.9023) (xy 150.9373 98.4451) (xy 151.3537 98.0287) (xy 151.8109 98.4859)
			)
		)
	)
	(zone
		(net 1)
		(net_name "GND")
		(layers "In1.Cu" "In2.Cu" "B.Cu")
		(name "GND")
		(hatch edge 0.508)
		(connect_pads
			(clearance 0.2)
		)
		(min_thickness 0.2)
		(filled_areas_thickness no)
		(fill yes
			(thermal_gap 0.2)
			(thermal_bridge_width 0.35)
		)
		(polygon
			(pts
				(xy 166.751 120.904) (xy 123.571 120.904) (xy 123.571 77.724) (xy 166.751 77.724)
			)
		)
	)
	(zone
		(net 10)
		(net_name "+3V3")
		(layer "B.Cu")
		(name "+3V3")
		(hatch none 0.508)
		(priority 1)
		(connect_pads
			(clearance 0.2)
		)
		(min_thickness 0.2)
		(filled_areas_thickness no)
		(fill yes
			(thermal_gap 0.508)
			(thermal_bridge_width 0.508)
			(smoothing fillet)
			(radius 0.25)
		)
		(polygon
			(pts
				(xy 146.55 90.75) (xy 142.25 90.75) (xy 140.022324 92.986249) (xy 132.518832 92.998598) (xy 131.210023 94.305797)
				(xy 126.287545 94.303046) (xy 124.775 95.805142) (xy 124.821779 109.805142) (xy 126.225 110.605142)
				(xy 127.05 112.280142) (xy 127.05 113.105142) (xy 125.35 112.780142) (xy 123.6 111.405142) (xy 123.55 90.830142)
				(xy 134.8 90.780142) (xy 138.85 90.780142) (xy 140.95 88.680142) (xy 146.55 88.680142)
			)
		)
	)
	(zone
		(net 2)
		(net_name "+12V")
		(layer "B.Cu")
		(name "SW_5V")
		(hatch full 0.508)
		(priority 2)
		(connect_pads
			(clearance 0.2)
		)
		(min_thickness 0.2)
		(filled_areas_thickness no)
		(fill yes
			(thermal_gap 0.15)
			(thermal_bridge_width 0.35)
		)
		(polygon
			(pts
				(xy 166.1 91.94) (xy 166.1 86.9) (xy 164.01 84.81) (xy 160.62 84.81) (xy 158.76 82.95) (xy 149.83 82.95)
				(xy 147.56 80.68) (xy 135.4 80.68) (xy 134.865 81.215) (xy 134.54894 81.20894) (xy 134.55 82.22)
				(xy 135.5 83.01) (xy 147.02 83.01) (xy 149.09 85.08) (xy 148.15 85.08) (xy 148.39 85.08) (xy 157.67 85.08)
				(xy 159.29 86.7) (xy 159.62 87.03) (xy 162.98 87.03) (xy 164.42 88.47) (xy 164.42 91.66) (xy 164.7 91.94)
			)
		)
	)
	(zone
		(net 9)
		(net_name "+5V")
		(layer "B.Cu")
		(name "+5V")
		(hatch edge 0.508)
		(priority 1)
		(connect_pads
			(clearance 0.2)
		)
		(min_thickness 0.2)
		(filled_areas_thickness no)
		(fill yes
			(thermal_gap 0.508)
			(thermal_bridge_width 0.508)
			(smoothing fillet)
			(radius 0.25)
		)
		(polygon
			(pts
				(xy 138.115988 90.7984) (xy 130.7 90.8) (xy 129.198979 92.312555) (xy 123.906 92.3) (xy 123.906 88.8)
				(xy 138.099988 88.7984)
			)
		)
	)
	(zone
		(net 0)
		(net_name "")
		(layer "B.Cu")
		(name "CSI keepout")
		(hatch edge 0.508)
		(connect_pads
			(clearance 0)
		)
		(min_thickness 0.2)
		(filled_areas_thickness no)
		(keepout
			(tracks allowed)
			(vias allowed)
			(pads allowed)
			(copperpour not_allowed)
			(footprints allowed)
		)
		(fill
			(thermal_gap 0.2)
			(thermal_bridge_width 0.35)
		)
		(polygon
			(pts
				(xy 138.25 108.25) (xy 144.3 108.25) (xy 147 104.6) (xy 143.075 99.725) (xy 135.325 96.15) (xy 134.910617 96.05)
				(xy 128.691225 96.034731) (xy 125.25 97.4) (xy 125.25 103.325) (xy 126.65 103.775) (xy 135.025 104.5)
			)
		)
	)
)
